G04 ================== begin FILE IDENTIFICATION RECORD ==================*
G04 Layout Name:  9324_DA0F0TMBIJ0_F0T_Motherboard_J_v01_20230324_0910.brd*
G04 Film Name:    gnd7*
G04 File Format:  Gerber RS274X*
G04 File Origin:  Cadence Allegro 17.2-S081*
G04 Origin Date:  Sat Mar 25 08:45:12 2023*
G04 *
G04 Layer:  DRAWING FORMAT/TITLE_BLOCK_A*
G04 Layer:  PIN/SPECIAL_DRILL*
G04 Layer:  VIA CLASS/GND7*
G04 Layer:  PIN/GND7*
G04 Layer:  MANUFACTURING/PHOTOPLOT_OUTLINE*
G04 Layer:  ETCH/GND7*
G04 Layer:  DRAWING FORMAT/TITLE_BLOCK*
G04 Layer:  DRAWING FORMAT/TITLE_DATA_GND7*
G04 *
G04 Offset:    (0.00 0.00)*
G04 Mirror:    No*
G04 Mode:      Negative*
G04 Rotation:  0*
G04 FullContactRelief:  No*
G04 UndefLineWidth:     6.00*
G04 ================== end FILE IDENTIFICATION RECORD ====================*
%FSLAX25Y25*MOIN*%
%IR0*IPPOS*OFA0.00000B0.00000*MIA0B0*SFA1.00000B1.00000*%
%ADD15C,.03*%
%ADD31C,.06*%
%ADD46C,.061*%
%ADD27C,.07*%
%AMMACRO55*
4,1,36,0.0,.01,
-.001736,.009848,
-.00342,.009397,
-.005,.00866,
-.006428,.00766,
-.00766,.006428,
-.00866,.005,
-.009397,.00342,
-.009848,.001736,
-.01,0.0,
-.009848,-.001736,
-.009397,-.00342,
-.00866,-.005,
-.00766,-.006428,
-.006428,-.00766,
-.005,-.00866,
-.00342,-.009397,
-.001736,-.009848,
0.0,-.01,
.001736,-.009848,
.00342,-.009397,
.005,-.00866,
.006428,-.00766,
.00766,-.006428,
.00866,-.005,
.009397,-.00342,
.009848,-.001736,
.01,0.0,
.009848,.001736,
.009397,.00342,
.00866,.005,
.00766,.006428,
.006428,.00766,
.005,.00866,
.00342,.009397,
.001736,.009848,
0.0,.01,
0.0*
%
%ADD55MACRO55*%
%ADD52C,.071*%
%ADD29C,.062*%
%ADD17C,.026*%
%AMMACRO71*
4,1,36,.0025,0.0,
.002462,.000434,
.002349,.000855,
.002165,.00125,
.001915,.001607,
.001607,.001915,
.00125,.002165,
.000855,.002349,
.000434,.002462,
0.0,.0025,
-.000434,.002462,
-.000855,.002349,
-.00125,.002165,
-.001607,.001915,
-.001915,.001607,
-.002165,.00125,
-.002349,.000855,
-.002462,.000434,
-.0025,0.0,
-.002462,-.000434,
-.002349,-.000855,
-.002165,-.00125,
-.001915,-.001607,
-.001607,-.001915,
-.00125,-.002165,
-.000855,-.002349,
-.000434,-.002462,
0.0,-.0025,
.000434,-.002462,
.000855,-.002349,
.00125,-.002165,
.001607,-.001915,
.001915,-.001607,
.002165,-.00125,
.002349,-.000855,
.002462,-.000434,
.0025,0.0,
135.*
%
%ADD71MACRO71*%
%ADD67C,.064*%
%AMMACRO19*
4,1,36,.0025,0.0,
.002462,.000434,
.002349,.000855,
.002165,.00125,
.001915,.001607,
.001607,.001915,
.00125,.002165,
.000855,.002349,
.000434,.002462,
0.0,.0025,
-.000434,.002462,
-.000855,.002349,
-.00125,.002165,
-.001607,.001915,
-.001915,.001607,
-.002165,.00125,
-.002349,.000855,
-.002462,.000434,
-.0025,0.0,
-.002462,-.000434,
-.002349,-.000855,
-.002165,-.00125,
-.001915,-.001607,
-.001607,-.001915,
-.00125,-.002165,
-.000855,-.002349,
-.000434,-.002462,
0.0,-.0025,
.000434,-.002462,
.000855,-.002349,
.00125,-.002165,
.001607,-.001915,
.001915,-.001607,
.002165,-.00125,
.002349,-.000855,
.002462,-.000434,
.0025,0.0,
225.*
%
%ADD19MACRO19*%
%AMMACRO14*
4,1,36,.0025,0.0,
.002462,.000434,
.002349,.000855,
.002165,.00125,
.001915,.001607,
.001607,.001915,
.00125,.002165,
.000855,.002349,
.000434,.002462,
0.0,.0025,
-.000434,.002462,
-.000855,.002349,
-.00125,.002165,
-.001607,.001915,
-.001915,.001607,
-.002165,.00125,
-.002349,.000855,
-.002462,.000434,
-.0025,0.0,
-.002462,-.000434,
-.002349,-.000855,
-.002165,-.00125,
-.001915,-.001607,
-.001607,-.001915,
-.00125,-.002165,
-.000855,-.002349,
-.000434,-.002462,
0.0,-.0025,
.000434,-.002462,
.000855,-.002349,
.00125,-.002165,
.001607,-.001915,
.001915,-.001607,
.002165,-.00125,
.002349,-.000855,
.002462,-.000434,
.0025,0.0,
180.*
%
%ADD14MACRO14*%
%AMMACRO11*
4,1,36,.0025,0.0,
.002462,.000434,
.002349,.000855,
.002165,.00125,
.001915,.001607,
.001607,.001915,
.00125,.002165,
.000855,.002349,
.000434,.002462,
0.0,.0025,
-.000434,.002462,
-.000855,.002349,
-.00125,.002165,
-.001607,.001915,
-.001915,.001607,
-.002165,.00125,
-.002349,.000855,
-.002462,.000434,
-.0025,0.0,
-.002462,-.000434,
-.002349,-.000855,
-.002165,-.00125,
-.001915,-.001607,
-.001607,-.001915,
-.00125,-.002165,
-.000855,-.002349,
-.000434,-.002462,
0.0,-.0025,
.000434,-.002462,
.000855,-.002349,
.00125,-.002165,
.001607,-.001915,
.001915,-.001607,
.002165,-.00125,
.002349,-.000855,
.002462,-.000434,
.0025,0.0,
270.*
%
%ADD11MACRO11*%
%AMMACRO53*
4,1,36,-.0025,0.0,
-.002462,.000434,
-.002349,.000855,
-.002165,.00125,
-.001915,.001607,
-.001607,.001915,
-.00125,.002165,
-.000855,.002349,
-.000434,.002462,
0.0,.0025,
.000434,.002462,
.000855,.002349,
.00125,.002165,
.001607,.001915,
.001915,.001607,
.002165,.00125,
.002349,.000855,
.002462,.000434,
.0025,0.0,
.002462,-.000434,
.002349,-.000855,
.002165,-.00125,
.001915,-.001607,
.001607,-.001915,
.00125,-.002165,
.000855,-.002349,
.000434,-.002462,
0.0,-.0025,
-.000434,-.002462,
-.000855,-.002349,
-.00125,-.002165,
-.001607,-.001915,
-.001915,-.001607,
-.002165,-.00125,
-.002349,-.000855,
-.002462,-.000434,
-.0025,0.0,
180.*
%
%ADD53MACRO53*%
%AMMACRO44*
4,1,36,.003,0.0,
.002954,.000521,
.002819,.001026,
.002598,.0015,
.002298,.001928,
.001928,.002298,
.0015,.002598,
.001026,.002819,
.000521,.002954,
0.0,.003,
-.000521,.002954,
-.001026,.002819,
-.0015,.002598,
-.001928,.002298,
-.002298,.001928,
-.002598,.0015,
-.002819,.001026,
-.002954,.000521,
-.003,0.0,
-.002954,-.000521,
-.002819,-.001026,
-.002598,-.0015,
-.002298,-.001928,
-.001928,-.002298,
-.0015,-.002598,
-.001026,-.002819,
-.000521,-.002954,
0.0,-.003,
.000521,-.002954,
.001026,-.002819,
.0015,-.002598,
.001928,-.002298,
.002298,-.001928,
.002598,-.0015,
.002819,-.001026,
.002954,-.000521,
.003,0.0,
270.*
%
%ADD44MACRO44*%
%AMMACRO42*
4,1,36,.003,0.0,
.002954,.000521,
.002819,.001026,
.002598,.0015,
.002298,.001928,
.001928,.002298,
.0015,.002598,
.001026,.002819,
.000521,.002954,
0.0,.003,
-.000521,.002954,
-.001026,.002819,
-.0015,.002598,
-.001928,.002298,
-.002298,.001928,
-.002598,.0015,
-.002819,.001026,
-.002954,.000521,
-.003,0.0,
-.002954,-.000521,
-.002819,-.001026,
-.002598,-.0015,
-.002298,-.001928,
-.001928,-.002298,
-.0015,-.002598,
-.001026,-.002819,
-.000521,-.002954,
0.0,-.003,
.000521,-.002954,
.001026,-.002819,
.0015,-.002598,
.001928,-.002298,
.002298,-.001928,
.002598,-.0015,
.002819,-.001026,
.002954,-.000521,
.003,0.0,
180.*
%
%ADD42MACRO42*%
%ADD25C,.074*%
%AMMACRO74*
4,1,36,-.003,0.0,
-.002954,.000521,
-.002819,.001026,
-.002598,.0015,
-.002298,.001928,
-.001928,.002298,
-.0015,.002598,
-.001026,.002819,
-.000521,.002954,
0.0,.003,
.000521,.002954,
.001026,.002819,
.0015,.002598,
.001928,.002298,
.002298,.001928,
.002598,.0015,
.002819,.001026,
.002954,.000521,
.003,0.0,
.002954,-.000521,
.002819,-.001026,
.002598,-.0015,
.002298,-.001928,
.001928,-.002298,
.0015,-.002598,
.001026,-.002819,
.000521,-.002954,
0.0,-.003,
-.000521,-.002954,
-.001026,-.002819,
-.0015,-.002598,
-.001928,-.002298,
-.002298,-.001928,
-.002598,-.0015,
-.002819,-.001026,
-.002954,-.000521,
-.003,0.0,
270.*
%
%ADD74MACRO74*%
%ADD73C,.0435*%
%ADD63C,.06015*%
%ADD50C,.076*%
%ADD49C,.095*%
%ADD23C,.0257*%
%ADD76C,.087*%
%ADD35C,.03417*%
%ADD41C,.0259*%
%ADD26C,.0277*%
%AMMACRO40*
4,1,15,.06231,.03403,
.067273,.022693,
.070191,.010666,
.070977,-.001684,
.069606,-.013984,
.066121,-.025858,
.06231,-.03403,
.06745,-.03917,
.073227,-.026862,
.076779,-.013739,
.077998,-.000197,
.076848,.01335,
.073362,.026492,
.067647,.038828,
.06745,.03917,
.06231,.03403,
0.0*
4,1,15,.03403,-.06231,
.022693,-.067273,
.010666,-.070191,
-.001684,-.070977,
-.013984,-.069606,
-.025858,-.066121,
-.03403,-.06231,
-.03917,-.06745,
-.026862,-.073227,
-.013739,-.076779,
-.000197,-.077998,
.01335,-.076848,
.026492,-.073362,
.038828,-.067647,
.03917,-.06745,
.03403,-.06231,
0.0*
4,1,15,-.06231,-.03403,
-.067273,-.022693,
-.070191,-.010666,
-.070977,.001684,
-.069606,.013984,
-.066121,.025858,
-.06231,.03403,
-.06745,.03917,
-.073227,.026862,
-.076779,.013739,
-.077998,.000197,
-.076848,-.01335,
-.073362,-.026492,
-.067647,-.038828,
-.06745,-.03917,
-.06231,-.03403,
0.0*
4,1,15,-.03403,.06231,
-.022693,.067273,
-.010666,.070191,
.001684,.070977,
.013984,.069606,
.025858,.066121,
.03403,.06231,
.03917,.06745,
.026862,.073227,
.013739,.076779,
.000197,.077998,
-.01335,.076848,
-.026492,.073362,
-.038828,.067647,
-.03917,.06745,
-.03403,.06231,
0.0*
%
%ADD40MACRO40*%
%AMMACRO10*
4,1,18,.09673,.06845,
.107147,.050613,
.114308,.031238,
.117996,.010914,
.118098,-.009741,
.114613,-.030101,
.107644,-.049546,
.097406,-.067485,
.09673,-.06845,
.10175,-.07347,
.112962,-.054685,
.120742,-.034239,
.124853,-.012752,
.125171,.009122,
.121685,.030719,
.114502,.051383,
.10384,.070486,
.10175,.07347,
.09673,.06845,
0.0*
4,1,18,.06845,-.09673,
.050613,-.107147,
.031238,-.114308,
.010914,-.117996,
-.009741,-.118098,
-.030101,-.114613,
-.049546,-.107644,
-.067485,-.097406,
-.06845,-.09673,
-.07347,-.10175,
-.054685,-.112962,
-.034239,-.120742,
-.012752,-.124853,
.009122,-.125171,
.030719,-.121685,
.051383,-.114502,
.070486,-.10384,
.07347,-.10175,
.06845,-.09673,
0.0*
4,1,18,-.09673,-.06845,
-.107147,-.050613,
-.114308,-.031238,
-.117996,-.010914,
-.118098,.009741,
-.114613,.030101,
-.107644,.049546,
-.097406,.067485,
-.09673,.06845,
-.10175,.07347,
-.112962,.054685,
-.120742,.034239,
-.124853,.012752,
-.125171,-.009122,
-.121685,-.030719,
-.114502,-.051383,
-.10384,-.070486,
-.10175,-.07347,
-.09673,-.06845,
0.0*
4,1,18,-.06845,.09673,
-.050613,.107147,
-.031238,.114308,
-.010914,.117996,
.009741,.118098,
.030101,.114613,
.049546,.107644,
.067485,.097406,
.06845,.09673,
.07347,.10175,
.054685,.112962,
.034239,.120742,
.012752,.124853,
-.009122,.125171,
-.030719,.121685,
-.051383,.114502,
-.070486,.10384,
-.07347,.10175,
-.06845,.09673,
0.0*
%
%ADD10MACRO10*%
%ADD36C,.03187*%
%AMMACRO37*
4,1,16,.0711,.04282,
.077455,.029823,
.081457,.01592,
.082984,.001533,
.08199,-.0129,
.078504,-.026942,
.072633,-.040164,
.0711,-.04282,
.07619,-.04791,
.083352,-.033952,
.087981,-.018962,
.089937,-.003396,
.089161,.012273,
.085675,.027569,
.079586,.042027,
.07619,.04791,
.0711,.04282,
0.0*
4,1,16,.04282,-.0711,
.029823,-.077455,
.01592,-.081457,
.001533,-.082984,
-.0129,-.08199,
-.026942,-.078504,
-.040164,-.072633,
-.04282,-.0711,
-.04791,-.07619,
-.033952,-.083352,
-.018962,-.087981,
-.003396,-.089937,
.012273,-.089161,
.027569,-.085675,
.042027,-.079586,
.04791,-.07619,
.04282,-.0711,
0.0*
4,1,16,-.0711,-.04282,
-.077455,-.029823,
-.081457,-.01592,
-.082984,-.001533,
-.08199,.0129,
-.078504,.026942,
-.072633,.040164,
-.0711,.04282,
-.07619,.04791,
-.083352,.033952,
-.087981,.018962,
-.089937,.003396,
-.089161,-.012273,
-.085675,-.027569,
-.079586,-.042027,
-.07619,-.04791,
-.0711,-.04282,
0.0*
4,1,16,-.04282,.0711,
-.029823,.077455,
-.01592,.081457,
-.001533,.082984,
.0129,.08199,
.026942,.078504,
.040164,.072633,
.04282,.0711,
.04791,.07619,
.033952,.083352,
.018962,.087981,
.003396,.089937,
-.012273,.089161,
-.027569,.085675,
-.042027,.079586,
-.04791,.07619,
-.04282,.0711,
0.0*
%
%ADD37MACRO37*%
%AMMACRO32*
4,1,15,.02438,.01377,
.026401,.009327,
.027619,.004601,
.027999,-.000265,
.027527,-.005123,
.02622,-.009825,
.02438,-.01377,
.02948,-.01887,
.032309,-.013464,
.034156,-.007649,
.034965,-.001602,
.034712,.004494,
.033405,.010454,
.031082,.016095,
.02948,.01887,
.02438,.01377,
90.*
4,1,15,.01377,-.02438,
.009327,-.026401,
.004601,-.027619,
-.000265,-.027999,
-.005123,-.027527,
-.009825,-.02622,
-.01377,-.02438,
-.01887,-.02948,
-.013464,-.032309,
-.007649,-.034156,
-.001602,-.034965,
.004494,-.034712,
.010454,-.033405,
.016095,-.031082,
.01887,-.02948,
.01377,-.02438,
90.*
4,1,15,-.02438,-.01377,
-.026401,-.009327,
-.027619,-.004601,
-.027999,.000265,
-.027527,.005123,
-.02622,.009825,
-.02438,.01377,
-.02948,.01887,
-.032309,.013464,
-.034156,.007649,
-.034965,.001602,
-.034712,-.004494,
-.033405,-.010454,
-.031082,-.016095,
-.02948,-.01887,
-.02438,-.01377,
90.*
4,1,15,-.01377,.02438,
-.009327,.026401,
-.004601,.027619,
.000265,.027999,
.005123,.027527,
.009825,.02622,
.01377,.02438,
.01887,.02948,
.013464,.032309,
.007649,.034156,
.001602,.034965,
-.004494,.034712,
-.010454,.033405,
-.016095,.031082,
-.01887,.02948,
-.01377,.02438,
90.*
%
%ADD32MACRO32*%
%AMMACRO30*
4,1,15,.02438,.01377,
.026401,.009327,
.027619,.004601,
.027999,-.000265,
.027527,-.005123,
.02622,-.009825,
.02438,-.01377,
.02948,-.01887,
.032309,-.013464,
.034156,-.007649,
.034965,-.001602,
.034712,.004494,
.033405,.010454,
.031082,.016095,
.02948,.01887,
.02438,.01377,
0.0*
4,1,15,.01377,-.02438,
.009327,-.026401,
.004601,-.027619,
-.000265,-.027999,
-.005123,-.027527,
-.009825,-.02622,
-.01377,-.02438,
-.01887,-.02948,
-.013464,-.032309,
-.007649,-.034156,
-.001602,-.034965,
.004494,-.034712,
.010454,-.033405,
.016095,-.031082,
.01887,-.02948,
.01377,-.02438,
0.0*
4,1,15,-.02438,-.01377,
-.026401,-.009327,
-.027619,-.004601,
-.027999,.000265,
-.027527,.005123,
-.02622,.009825,
-.02438,.01377,
-.02948,.01887,
-.032309,.013464,
-.034156,.007649,
-.034965,.001602,
-.034712,-.004494,
-.033405,-.010454,
-.031082,-.016095,
-.02948,-.01887,
-.02438,-.01377,
0.0*
4,1,15,-.01377,.02438,
-.009327,.026401,
-.004601,.027619,
.000265,.027999,
.005123,.027527,
.009825,.02622,
.01377,.02438,
.01887,.02948,
.013464,.032309,
.007649,.034156,
.001602,.034965,
-.004494,.034712,
-.010454,.033405,
-.016095,.031082,
-.01887,.02948,
-.01377,.02438,
0.0*
%
%ADD30MACRO30*%
%AMMACRO48*
4,1,15,.02475,.01414,
.026829,.009627,
.028094,.004822,
.028504,-.000129,
.028049,-.005077,
.026741,-.009871,
.02475,-.01414,
.02984,-.01923,
.032726,-.013756,
.034617,-.007864,
.035457,-.001734,
.03522,.00445,
.033912,.010498,
.031574,.016227,
.02984,.01923,
.02475,.01414,
90.*
4,1,15,.01414,-.02475,
.009627,-.026829,
.004822,-.028094,
-.000129,-.028504,
-.005077,-.028049,
-.009871,-.026741,
-.01414,-.02475,
-.01923,-.02984,
-.013756,-.032726,
-.007864,-.034617,
-.001734,-.035457,
.00445,-.03522,
.010498,-.033912,
.016227,-.031574,
.01923,-.02984,
.01414,-.02475,
90.*
4,1,15,-.02475,-.01414,
-.026829,-.009627,
-.028094,-.004822,
-.028504,.000129,
-.028049,.005077,
-.026741,.009871,
-.02475,.01414,
-.02984,.01923,
-.032726,.013756,
-.034617,.007864,
-.035457,.001734,
-.03522,-.00445,
-.033912,-.010498,
-.031574,-.016227,
-.02984,-.01923,
-.02475,-.01414,
90.*
4,1,15,-.01414,.02475,
-.009627,.026829,
-.004822,.028094,
.000129,.028504,
.005077,.028049,
.009871,.026741,
.01414,.02475,
.01923,.02984,
.013756,.032726,
.007864,.034617,
.001734,.035457,
-.00445,.03522,
-.010498,.033912,
-.016227,.031574,
-.01923,.02984,
-.01414,.02475,
90.*
%
%ADD48MACRO48*%
%AMMACRO66*
4,1,18,.07103,.05689,
.07983,.043691,
.086204,.029165,
.089959,.013753,
.09098,-.002077,
.089237,-.017844,
.084783,-.033069,
.077753,-.047289,
.07103,-.05689,
.07601,-.06186,
.085597,-.047721,
.092583,-.032132,
.096757,-.015567,
.09799,.001471,
.096246,.018464,
.091577,.034897,
.084126,.050269,
.07601,.06186,
.07103,.05689,
0.0*
4,1,18,.05689,-.07103,
.043691,-.07983,
.029165,-.086204,
.013753,-.089959,
-.002077,-.09098,
-.017844,-.089237,
-.033069,-.084783,
-.047289,-.077753,
-.05689,-.07103,
-.06186,-.07601,
-.047721,-.085597,
-.032132,-.092583,
-.015567,-.096757,
.001471,-.09799,
.018464,-.096246,
.034897,-.091577,
.050269,-.084126,
.06186,-.07601,
.05689,-.07103,
0.0*
4,1,18,-.07103,-.05689,
-.07983,-.043691,
-.086204,-.029165,
-.089959,-.013753,
-.09098,.002077,
-.089237,.017844,
-.084783,.033069,
-.077753,.047289,
-.07103,.05689,
-.07601,.06186,
-.085597,.047721,
-.092583,.032132,
-.096757,.015567,
-.09799,-.001471,
-.096246,-.018464,
-.091577,-.034897,
-.084126,-.050269,
-.07601,-.06186,
-.07103,-.05689,
0.0*
4,1,18,-.05689,.07103,
-.043691,.07983,
-.029165,.086204,
-.013753,.089959,
.002077,.09098,
.017844,.089237,
.033069,.084783,
.047289,.077753,
.05689,.07103,
.06186,.07601,
.047721,.085597,
.032132,.092583,
.015567,.096757,
-.001471,.09799,
-.018464,.096246,
-.034897,.091577,
-.050269,.084126,
-.06186,.07601,
-.05689,.07103,
0.0*
%
%ADD66MACRO66*%
%AMMACRO51*
4,1,15,.02475,.01414,
.026829,.009627,
.028094,.004822,
.028504,-.000129,
.028049,-.005077,
.026741,-.009871,
.02475,-.01414,
.02984,-.01923,
.032726,-.013756,
.034617,-.007864,
.035457,-.001734,
.03522,.00445,
.033912,.010498,
.031574,.016227,
.02984,.01923,
.02475,.01414,
0.0*
4,1,15,.01414,-.02475,
.009627,-.026829,
.004822,-.028094,
-.000129,-.028504,
-.005077,-.028049,
-.009871,-.026741,
-.01414,-.02475,
-.01923,-.02984,
-.013756,-.032726,
-.007864,-.034617,
-.001734,-.035457,
.00445,-.03522,
.010498,-.033912,
.016227,-.031574,
.01923,-.02984,
.01414,-.02475,
0.0*
4,1,15,-.02475,-.01414,
-.026829,-.009627,
-.028094,-.004822,
-.028504,.000129,
-.028049,.005077,
-.026741,.009871,
-.02475,.01414,
-.02984,.01923,
-.032726,.013756,
-.034617,.007864,
-.035457,.001734,
-.03522,-.00445,
-.033912,-.010498,
-.031574,-.016227,
-.02984,-.01923,
-.02475,-.01414,
0.0*
4,1,15,-.01414,.02475,
-.009627,.026829,
-.004822,.028094,
.000129,.028504,
.005077,.028049,
.009871,.026741,
.01414,.02475,
.01923,.02984,
.013756,.032726,
.007864,.034617,
.001734,.035457,
-.00445,.03522,
-.010498,.033912,
-.016227,.031574,
-.01923,.02984,
-.01414,.02475,
0.0*
%
%ADD51MACRO51*%
%AMMACRO38*
4,1,16,.02511,.01451,
.027248,.009929,
.028558,.005047,
.029001,.000011,
.028562,-.005025,
.027256,-.009909,
.025121,-.014491,
.02511,-.01451,
.0302,-.01959,
.033143,-.014048,
.035079,-.00808,
.035949,-.001865,
.035727,.004405,
.034419,.010542,
.032065,.016359,
.0302,.01959,
.02511,.01451,
90.*
4,1,16,.01451,-.02511,
.009929,-.027248,
.005047,-.028558,
.000011,-.029001,
-.005025,-.028562,
-.009909,-.027256,
-.014491,-.025121,
-.01451,-.02511,
-.01959,-.0302,
-.014048,-.033143,
-.00808,-.035079,
-.001865,-.035949,
.004405,-.035727,
.010542,-.034419,
.016359,-.032065,
.01959,-.0302,
.01451,-.02511,
90.*
4,1,16,-.02511,-.01451,
-.027248,-.009929,
-.028558,-.005047,
-.029001,-.000011,
-.028562,.005025,
-.027256,.009909,
-.025121,.014491,
-.02511,.01451,
-.0302,.01959,
-.033143,.014048,
-.035079,.00808,
-.035949,.001865,
-.035727,-.004405,
-.034419,-.010542,
-.032065,-.016359,
-.0302,-.01959,
-.02511,-.01451,
90.*
4,1,16,-.01451,.02511,
-.009929,.027248,
-.005047,.028558,
-.000011,.029001,
.005025,.028562,
.009909,.027256,
.014491,.025121,
.01451,.02511,
.01959,.0302,
.014048,.033143,
.00808,.035079,
.001865,.035949,
-.004405,.035727,
-.010542,.034419,
-.016359,.032065,
-.01959,.0302,
-.01451,.02511,
90.*
%
%ADD38MACRO38*%
%AMMACRO28*
4,1,16,.02511,.01451,
.027248,.009929,
.028558,.005047,
.029001,.000011,
.028562,-.005025,
.027256,-.009909,
.025121,-.014491,
.02511,-.01451,
.0302,-.01959,
.033143,-.014048,
.035079,-.00808,
.035949,-.001865,
.035727,.004405,
.034419,.010542,
.032065,.016359,
.0302,.01959,
.02511,.01451,
0.0*
4,1,16,.01451,-.02511,
.009929,-.027248,
.005047,-.028558,
.000011,-.029001,
-.005025,-.028562,
-.009909,-.027256,
-.014491,-.025121,
-.01451,-.02511,
-.01959,-.0302,
-.014048,-.033143,
-.00808,-.035079,
-.001865,-.035949,
.004405,-.035727,
.010542,-.034419,
.016359,-.032065,
.01959,-.0302,
.01451,-.02511,
0.0*
4,1,16,-.02511,-.01451,
-.027248,-.009929,
-.028558,-.005047,
-.029001,-.000011,
-.028562,.005025,
-.027256,.009909,
-.025121,.014491,
-.02511,.01451,
-.0302,.01959,
-.033143,.014048,
-.035079,.00808,
-.035949,.001865,
-.035727,-.004405,
-.034419,-.010542,
-.032065,-.016359,
-.0302,-.01959,
-.02511,-.01451,
0.0*
4,1,16,-.01451,.02511,
-.009929,.027248,
-.005047,.028558,
-.000011,.029001,
.005025,.028562,
.009909,.027256,
.014491,.025121,
.01451,.02511,
.01959,.0302,
.014048,.033143,
.00808,.035079,
.001865,.035949,
-.004405,.035727,
-.010542,.034419,
-.016359,.032065,
-.01959,.0302,
-.01451,.02511,
0.0*
%
%ADD28MACRO28*%
%AMMACRO78*
4,1,15,.03682,.01914,
.039584,.012455,
.041146,.005393,
.041457,-.001834,
.040509,-.009005,
.03833,-.015903,
.03682,-.01914,
.04197,-.0243,
.045552,-.016643,
.04775,-.00848,
.048497,-.000059,
.047771,.008363,
.045593,.016531,
.042029,.024197,
.04197,.0243,
.03682,.01914,
0.0*
4,1,15,.01914,-.03682,
.012455,-.039584,
.005393,-.041146,
-.001834,-.041457,
-.009005,-.040509,
-.015903,-.03833,
-.01914,-.03682,
-.0243,-.04197,
-.016643,-.045552,
-.00848,-.04775,
-.000059,-.048497,
.008363,-.047771,
.016531,-.045593,
.024197,-.042029,
.0243,-.04197,
.01914,-.03682,
0.0*
4,1,15,-.03682,-.01914,
-.039584,-.012455,
-.041146,-.005393,
-.041457,.001834,
-.040509,.009005,
-.03833,.015903,
-.03682,.01914,
-.04197,.0243,
-.045552,.016643,
-.04775,.00848,
-.048497,.000059,
-.047771,-.008363,
-.045593,-.016531,
-.042029,-.024197,
-.04197,-.0243,
-.03682,-.01914,
0.0*
4,1,15,-.01914,.03682,
-.012455,.039584,
-.005393,.041146,
.001834,.041457,
.009005,.040509,
.015903,.03833,
.01914,.03682,
.0243,.04197,
.016643,.045552,
.00848,.04775,
.000059,.048497,
-.008363,.047771,
-.016531,.045593,
-.024197,.042029,
-.0243,.04197,
-.01914,.03682,
0.0*
%
%ADD78MACRO78*%
%AMMACRO75*
4,1,15,-.03682,.01914,
-.039584,.012455,
-.041146,.005393,
-.041457,-.001834,
-.040509,-.009005,
-.03833,-.015903,
-.03682,-.01914,
-.04197,-.0243,
-.045552,-.016643,
-.04775,-.00848,
-.048497,-.000059,
-.047771,.008363,
-.045593,.016531,
-.042029,.024197,
-.04197,.0243,
-.03682,.01914,
0.0*
4,1,15,-.01914,-.03682,
-.012455,-.039584,
-.005393,-.041146,
.001834,-.041457,
.009005,-.040509,
.015903,-.03833,
.01914,-.03682,
.0243,-.04197,
.016643,-.045552,
.00848,-.04775,
.000059,-.048497,
-.008363,-.047771,
-.016531,-.045593,
-.024197,-.042029,
-.0243,-.04197,
-.01914,-.03682,
0.0*
4,1,15,.03682,-.01914,
.039584,-.012455,
.041146,-.005393,
.041457,.001834,
.040509,.009005,
.03833,.015903,
.03682,.01914,
.04197,.0243,
.045552,.016643,
.04775,.00848,
.048497,.000059,
.047771,-.008363,
.045593,-.016531,
.042029,-.024197,
.04197,-.0243,
.03682,-.01914,
0.0*
4,1,15,.01914,.03682,
.012455,.039584,
.005393,.041146,
-.001834,.041457,
-.009005,.040509,
-.015903,.03833,
-.01914,.03682,
-.0243,.04197,
-.016643,.045552,
-.00848,.04775,
-.000059,.048497,
.008363,.047771,
.016531,.045593,
.024197,.042029,
.0243,.04197,
.01914,.03682,
0.0*
%
%ADD75MACRO75*%
%AMMACRO22*
4,1,25,-.0605,.00499,
-.05909,.011105,
-.05664,.016881,
-.053224,.022145,
-.048946,.026736,
-.043935,.030513,
-.038345,.033364,
-.032345,.0352,
-.02985,.03564,
-.025195,.035958,
-.02422,.03599,
-.005,.03599,
-.005,.03099,
-.02474,.03099,
-.026534,.030943,
-.028322,.030793,
-.02985,.03058,
-.035086,.029247,
-.040011,.027025,
-.044475,.023982,
-.048343,.020209,
-.051497,.015823,
-.053842,.010955,
-.055305,.005754,
-.05544,.00499,
-.0605,.00499,
0.0*
4,1,27,.005,.03599,
.02451,.03599,
.026071,.035998,
.027631,.035916,
.029183,.035743,
.02985,.03564,
.035965,.03423,
.041741,.03178,
.047005,.028364,
.051596,.024086,
.055373,.019075,
.058224,.013485,
.06006,.007485,
.0605,.00499,
.05544,.00499,
.054107,.010226,
.051885,.015151,
.048842,.019615,
.045069,.023483,
.040683,.026637,
.035815,.028982,
.030614,.030445,
.02985,.03058,
.0281,.030818,
.02634,.030955,
.02482,.03099,
.005,.03099,
.005,.03599,
0.0*
4,1,25,-.0605,-.00501,
-.05544,-.00501,
-.054107,-.010246,
-.051885,-.015171,
-.048842,-.019635,
-.045069,-.023503,
-.040683,-.026657,
-.035815,-.029002,
-.030614,-.030465,
-.02985,-.0306,
-.028079,-.03084,
-.026298,-.030976,
-.02487,-.03101,
-.005,-.03101,
-.005,-.03601,
-.02375,-.03601,
-.028562,-.035772,
-.02985,-.03566,
-.035965,-.03425,
-.041741,-.0318,
-.047005,-.028384,
-.051596,-.024106,
-.055373,-.019095,
-.058224,-.013505,
-.06006,-.007505,
-.0605,-.00501,
0.0*
4,1,27,.005,-.03101,
.02485,-.03101,
.02659,-.030963,
.028324,-.030815,
.02985,-.0306,
.035086,-.029267,
.040011,-.027045,
.044475,-.024002,
.048343,-.020229,
.051497,-.015843,
.053842,-.010975,
.055305,-.005774,
.05544,-.00501,
.0605,-.00501,
.05909,-.011125,
.05664,-.016901,
.053224,-.022165,
.048946,-.026756,
.043935,-.030533,
.038345,-.033384,
.032345,-.03522,
.02985,-.03566,
.028758,-.035841,
.027658,-.035958,
.026553,-.036011,
.02578,-.03601,
.005,-.03601,
.005,-.03101,
0.0*
%
%ADD22MACRO22*%
%ADD61R,.285X.23*%
%ADD68C,.142*%
%AMMACRO62*
4,1,36,0.0,.01,
-.001736,.009848,
-.00342,.009397,
-.005,.00866,
-.006428,.00766,
-.00766,.006428,
-.00866,.005,
-.009397,.00342,
-.009848,.001736,
-.01,0.0,
-.009848,-.001736,
-.009397,-.00342,
-.00866,-.005,
-.00766,-.006428,
-.006428,-.00766,
-.005,-.00866,
-.00342,-.009397,
-.001736,-.009848,
0.0,-.01,
.001736,-.009848,
.00342,-.009397,
.005,-.00866,
.006428,-.00766,
.00766,-.006428,
.00866,-.005,
.009397,-.00342,
.009848,-.001736,
.01,0.0,
.009848,.001736,
.009397,.00342,
.00866,.005,
.00766,.006428,
.006428,.00766,
.005,.00866,
.00342,.009397,
.001736,.009848,
0.0,.01,
180.*
%
%ADD62MACRO62*%
%ADD33O,.219X.156*%
%ADD13C,.125*%
%AMMACRO69*
4,1,36,.0025,0.0,
.002462,.000434,
.002349,.000855,
.002165,.00125,
.001915,.001607,
.001607,.001915,
.00125,.002165,
.000855,.002349,
.000434,.002462,
0.0,.0025,
-.000434,.002462,
-.000855,.002349,
-.00125,.002165,
-.001607,.001915,
-.001915,.001607,
-.002165,.00125,
-.002349,.000855,
-.002462,.000434,
-.0025,0.0,
-.002462,-.000434,
-.002349,-.000855,
-.002165,-.00125,
-.001915,-.001607,
-.001607,-.001915,
-.00125,-.002165,
-.000855,-.002349,
-.000434,-.002462,
0.0,-.0025,
.000434,-.002462,
.000855,-.002349,
.00125,-.002165,
.001607,-.001915,
.001915,-.001607,
.002165,-.00125,
.002349,-.000855,
.002462,-.000434,
.0025,0.0,
30.*
%
%ADD69MACRO69*%
%ADD18C,.424*%
%ADD21C,.155*%
%ADD54C,.291*%
%ADD39C,.165*%
%ADD56C,.247*%
%ADD45C,.256*%
%AMMACRO34*
4,1,36,0.0,.0085,
.001476,.008371,
.002907,.007987,
.00425,.007361,
.005464,.006511,
.006511,.005464,
.007361,.00425,
.007987,.002907,
.008371,.001476,
.0085,0.0,
.008371,-.001476,
.007987,-.002907,
.007361,-.00425,
.006511,-.005464,
.005464,-.006511,
.00425,-.007361,
.002907,-.007987,
.001476,-.008371,
0.0,-.0085,
-.001476,-.008371,
-.002907,-.007987,
-.00425,-.007361,
-.005464,-.006511,
-.006511,-.005464,
-.007361,-.00425,
-.007987,-.002907,
-.008371,-.001476,
-.0085,0.0,
-.008371,.001476,
-.007987,.002907,
-.007361,.00425,
-.006511,.005464,
-.005464,.006511,
-.00425,.007361,
-.002907,.007987,
-.001476,.008371,
0.0,.0085,
180.*
%
%ADD34MACRO34*%
%AMMACRO60*
4,1,20,-.0075,-.05555,
-.0075,-.06273,
-.013677,-.060878,
-.019439,-.057981,
-.024611,-.054127,
-.029034,-.049434,
-.032576,-.044045,
-.035127,-.038122,
-.036612,-.031846,
-.037,-.0265,
-.037,-.0075,
-.03,-.0075,
-.03,-.0265,
-.029544,-.03171,
-.028191,-.036762,
-.02598,-.041502,
-.022981,-.045786,
-.019282,-.049484,
-.014998,-.052484,
-.010258,-.054694,
-.0075,-.05555,
90.*
4,1,20,.0075,-.06273,
.0075,-.05555,
.01243,-.053806,
.016983,-.051232,
.02102,-.047906,
.024418,-.043931,
.027073,-.039425,
.028906,-.034527,
.029861,-.029385,
.03,-.0265,
.03,-.0075,
.037,-.0075,
.037,-.0265,
.036438,-.032925,
.034769,-.039154,
.032043,-.044999,
.028344,-.050282,
.023784,-.054842,
.018501,-.058541,
.012656,-.061266,
.0075,-.06273,
90.*
4,1,20,-.0075,.06273,
-.0075,.05555,
-.01243,.053806,
-.016983,.051232,
-.02102,.047906,
-.024418,.043931,
-.027073,.039425,
-.028906,.034527,
-.029861,.029385,
-.03,.0265,
-.03,.0075,
-.037,.0075,
-.037,.0265,
-.036438,.032925,
-.034769,.039154,
-.032043,.044999,
-.028344,.050282,
-.023784,.054842,
-.018501,.058541,
-.012656,.061266,
-.0075,.06273,
90.*
4,1,20,.0075,.05555,
.0075,.06273,
.013677,.060878,
.019439,.057981,
.024611,.054127,
.029034,.049434,
.032576,.044045,
.035127,.038122,
.036612,.031846,
.037,.0265,
.037,.0075,
.03,.0075,
.03,.0265,
.029544,.03171,
.028191,.036762,
.02598,.041502,
.022981,.045786,
.019282,.049484,
.014998,.052484,
.010258,.054694,
.0075,.05555,
90.*
%
%ADD60MACRO60*%
%AMMACRO20*
4,1,36,.0025,0.0,
.002462,.000434,
.002349,.000855,
.002165,.00125,
.001915,.001607,
.001607,.001915,
.00125,.002165,
.000855,.002349,
.000434,.002462,
0.0,.0025,
-.000434,.002462,
-.000855,.002349,
-.00125,.002165,
-.001607,.001915,
-.001915,.001607,
-.002165,.00125,
-.002349,.000855,
-.002462,.000434,
-.0025,0.0,
-.002462,-.000434,
-.002349,-.000855,
-.002165,-.00125,
-.001915,-.001607,
-.001607,-.001915,
-.00125,-.002165,
-.000855,-.002349,
-.000434,-.002462,
0.0,-.0025,
.000434,-.002462,
.000855,-.002349,
.00125,-.002165,
.001607,-.001915,
.001915,-.001607,
.002165,-.00125,
.002349,-.000855,
.002462,-.000434,
.0025,0.0,
90.*
%
%ADD20MACRO20*%
%AMMACRO57*
4,1,36,0.0,.019,
-.003299,.018711,
-.006498,.017854,
-.0095,.016454,
-.012213,.014555,
-.014555,.012213,
-.016454,.0095,
-.017854,.006498,
-.018711,.003299,
-.019,0.0,
-.018711,-.003299,
-.017854,-.006498,
-.016454,-.0095,
-.014555,-.012213,
-.012213,-.014555,
-.0095,-.016454,
-.006498,-.017854,
-.003299,-.018711,
0.0,-.019,
.003299,-.018711,
.006498,-.017854,
.0095,-.016454,
.012213,-.014555,
.014555,-.012213,
.016454,-.0095,
.017854,-.006498,
.018711,-.003299,
.019,0.0,
.018711,.003299,
.017854,.006498,
.016454,.0095,
.014555,.012213,
.012213,.014555,
.0095,.016454,
.006498,.017854,
.003299,.018711,
0.0,.019,
270.*
%
%ADD57MACRO57*%
%AMMACRO43*
4,1,36,.003,0.0,
.002954,.000521,
.002819,.001026,
.002598,.0015,
.002298,.001928,
.001928,.002298,
.0015,.002598,
.001026,.002819,
.000521,.002954,
0.0,.003,
-.000521,.002954,
-.001026,.002819,
-.0015,.002598,
-.001928,.002298,
-.002298,.001928,
-.002598,.0015,
-.002819,.001026,
-.002954,.000521,
-.003,0.0,
-.002954,-.000521,
-.002819,-.001026,
-.002598,-.0015,
-.002298,-.001928,
-.001928,-.002298,
-.0015,-.002598,
-.001026,-.002819,
-.000521,-.002954,
0.0,-.003,
.000521,-.002954,
.001026,-.002819,
.0015,-.002598,
.001928,-.002298,
.002298,-.001928,
.002598,-.0015,
.002819,-.001026,
.002954,-.000521,
.003,0.0,
90.*
%
%ADD43MACRO43*%
%AMMACRO12*
4,1,36,.0025,0.0,
.002462,.000434,
.002349,.000855,
.002165,.00125,
.001915,.001607,
.001607,.001915,
.00125,.002165,
.000855,.002349,
.000434,.002462,
0.0,.0025,
-.000434,.002462,
-.000855,.002349,
-.00125,.002165,
-.001607,.001915,
-.001915,.001607,
-.002165,.00125,
-.002349,.000855,
-.002462,.000434,
-.0025,0.0,
-.002462,-.000434,
-.002349,-.000855,
-.002165,-.00125,
-.001915,-.001607,
-.001607,-.001915,
-.00125,-.002165,
-.000855,-.002349,
-.000434,-.002462,
0.0,-.0025,
.000434,-.002462,
.000855,-.002349,
.00125,-.002165,
.001607,-.001915,
.001915,-.001607,
.002165,-.00125,
.002349,-.000855,
.002462,-.000434,
.0025,0.0,
0.0*
%
%ADD12MACRO12*%
%AMMACRO72*
4,1,36,-.003,0.0,
-.002954,.000521,
-.002819,.001026,
-.002598,.0015,
-.002298,.001928,
-.001928,.002298,
-.0015,.002598,
-.001026,.002819,
-.000521,.002954,
0.0,.003,
.000521,.002954,
.001026,.002819,
.0015,.002598,
.001928,.002298,
.002298,.001928,
.002598,.0015,
.002819,.001026,
.002954,.000521,
.003,0.0,
.002954,-.000521,
.002819,-.001026,
.002598,-.0015,
.002298,-.001928,
.001928,-.002298,
.0015,-.002598,
.001026,-.002819,
.000521,-.002954,
0.0,-.003,
-.000521,-.002954,
-.001026,-.002819,
-.0015,-.002598,
-.001928,-.002298,
-.002298,-.001928,
-.002598,-.0015,
-.002819,-.001026,
-.002954,-.000521,
-.003,0.0,
90.*
%
%ADD72MACRO72*%
%AMMACRO64*
4,1,36,-.0025,0.0,
-.002462,.000434,
-.002349,.000855,
-.002165,.00125,
-.001915,.001607,
-.001607,.001915,
-.00125,.002165,
-.000855,.002349,
-.000434,.002462,
0.0,.0025,
.000434,.002462,
.000855,.002349,
.00125,.002165,
.001607,.001915,
.001915,.001607,
.002165,.00125,
.002349,.000855,
.002462,.000434,
.0025,0.0,
.002462,-.000434,
.002349,-.000855,
.002165,-.00125,
.001915,-.001607,
.001607,-.001915,
.00125,-.002165,
.000855,-.002349,
.000434,-.002462,
0.0,-.0025,
-.000434,-.002462,
-.000855,-.002349,
-.00125,-.002165,
-.001607,-.001915,
-.001915,-.001607,
-.002165,-.00125,
-.002349,-.000855,
-.002462,-.000434,
-.0025,0.0,
0.0*
%
%ADD64MACRO64*%
%ADD58C,.188*%
%AMMACRO16*
4,1,36,.003,0.0,
.002954,.000521,
.002819,.001026,
.002598,.0015,
.002298,.001928,
.001928,.002298,
.0015,.002598,
.001026,.002819,
.000521,.002954,
0.0,.003,
-.000521,.002954,
-.001026,.002819,
-.0015,.002598,
-.001928,.002298,
-.002298,.001928,
-.002598,.0015,
-.002819,.001026,
-.002954,.000521,
-.003,0.0,
-.002954,-.000521,
-.002819,-.001026,
-.002598,-.0015,
-.002298,-.001928,
-.001928,-.002298,
-.0015,-.002598,
-.001026,-.002819,
-.000521,-.002954,
0.0,-.003,
.000521,-.002954,
.001026,-.002819,
.0015,-.002598,
.001928,-.002298,
.002298,-.001928,
.002598,-.0015,
.002819,-.001026,
.002954,-.000521,
.003,0.0,
0.0*
%
%ADD16MACRO16*%
%AMMACRO24*
4,1,16,.02584,.01524,
.028094,.010521,
.029494,.005483,
.029998,.000278,
.029591,-.004935,
.028284,-.009999,
.026118,-.014758,
.02584,-.01524,
.03092,-.02032,
.033979,-.014642,
.036005,-.008519,
.036938,-.002138,
.036748,.004309,
.035441,.010625,
.033058,.016618,
.03092,.02032,
.02584,.01524,
180.*
4,1,16,.01524,-.02584,
.010521,-.028094,
.005483,-.029494,
.000278,-.029998,
-.004935,-.029591,
-.009999,-.028284,
-.014758,-.026118,
-.01524,-.02584,
-.02032,-.03092,
-.014642,-.033979,
-.008519,-.036005,
-.002138,-.036938,
.004309,-.036748,
.010625,-.035441,
.016618,-.033058,
.02032,-.03092,
.01524,-.02584,
180.*
4,1,16,-.02584,-.01524,
-.028094,-.010521,
-.029494,-.005483,
-.029998,-.000278,
-.029591,.004935,
-.028284,.009999,
-.026118,.014758,
-.02584,.01524,
-.03092,.02032,
-.033979,.014642,
-.036005,.008519,
-.036938,.002138,
-.036748,-.004309,
-.035441,-.010625,
-.033058,-.016618,
-.03092,-.02032,
-.02584,-.01524,
180.*
4,1,16,-.01524,.02584,
-.010521,.028094,
-.005483,.029494,
-.000278,.029998,
.004935,.029591,
.009999,.028284,
.014758,.026118,
.01524,.02584,
.02032,.03092,
.014642,.033979,
.008519,.036005,
.002138,.036938,
-.004309,.036748,
-.010625,.035441,
-.016618,.033058,
-.02032,.03092,
-.01524,.02584,
180.*
%
%ADD24MACRO24*%
%AMMACRO65*
4,1,15,.02438,.01377,
.026401,.009327,
.027619,.004601,
.027999,-.000265,
.027527,-.005123,
.02622,-.009825,
.02438,-.01377,
.02948,-.01887,
.032309,-.013464,
.034156,-.007649,
.034965,-.001602,
.034712,.004494,
.033405,.010454,
.031082,.016095,
.02948,.01887,
.02438,.01377,
270.*
4,1,15,.01377,-.02438,
.009327,-.026401,
.004601,-.027619,
-.000265,-.027999,
-.005123,-.027527,
-.009825,-.02622,
-.01377,-.02438,
-.01887,-.02948,
-.013464,-.032309,
-.007649,-.034156,
-.001602,-.034965,
.004494,-.034712,
.010454,-.033405,
.016095,-.031082,
.01887,-.02948,
.01377,-.02438,
270.*
4,1,15,-.02438,-.01377,
-.026401,-.009327,
-.027619,-.004601,
-.027999,.000265,
-.027527,.005123,
-.02622,.009825,
-.02438,.01377,
-.02948,.01887,
-.032309,.013464,
-.034156,.007649,
-.034965,.001602,
-.034712,-.004494,
-.033405,-.010454,
-.031082,-.016095,
-.02948,-.01887,
-.02438,-.01377,
270.*
4,1,15,-.01377,.02438,
-.009327,.026401,
-.004601,.027619,
.000265,.027999,
.005123,.027527,
.009825,.02622,
.01377,.02438,
.01887,.02948,
.013464,.032309,
.007649,.034156,
.001602,.034965,
-.004494,.034712,
-.010454,.033405,
-.016095,.031082,
-.01887,.02948,
-.01377,.02438,
270.*
%
%ADD65MACRO65*%
%AMMACRO70*
4,1,15,.02475,.01414,
.026829,.009627,
.028094,.004822,
.028504,-.000129,
.028049,-.005077,
.026741,-.009871,
.02475,-.01414,
.02984,-.01923,
.032726,-.013756,
.034617,-.007864,
.035457,-.001734,
.03522,.00445,
.033912,.010498,
.031574,.016227,
.02984,.01923,
.02475,.01414,
180.*
4,1,15,.01414,-.02475,
.009627,-.026829,
.004822,-.028094,
-.000129,-.028504,
-.005077,-.028049,
-.009871,-.026741,
-.01414,-.02475,
-.01923,-.02984,
-.013756,-.032726,
-.007864,-.034617,
-.001734,-.035457,
.00445,-.03522,
.010498,-.033912,
.016227,-.031574,
.01923,-.02984,
.01414,-.02475,
180.*
4,1,15,-.02475,-.01414,
-.026829,-.009627,
-.028094,-.004822,
-.028504,.000129,
-.028049,.005077,
-.026741,.009871,
-.02475,.01414,
-.02984,.01923,
-.032726,.013756,
-.034617,.007864,
-.035457,.001734,
-.03522,-.00445,
-.033912,-.010498,
-.031574,-.016227,
-.02984,-.01923,
-.02475,-.01414,
180.*
4,1,15,-.01414,.02475,
-.009627,.026829,
-.004822,.028094,
.000129,.028504,
.005077,.028049,
.009871,.026741,
.01414,.02475,
.01923,.02984,
.013756,.032726,
.007864,.034617,
.001734,.035457,
-.00445,.03522,
-.010498,.033912,
-.016227,.031574,
-.01923,.02984,
-.01414,.02475,
180.*
%
%ADD70MACRO70*%
%AMMACRO47*
4,1,15,.02475,.01414,
.026829,.009627,
.028094,.004822,
.028504,-.000129,
.028049,-.005077,
.026741,-.009871,
.02475,-.01414,
.02984,-.01923,
.032726,-.013756,
.034617,-.007864,
.035457,-.001734,
.03522,.00445,
.033912,.010498,
.031574,.016227,
.02984,.01923,
.02475,.01414,
270.*
4,1,15,.01414,-.02475,
.009627,-.026829,
.004822,-.028094,
-.000129,-.028504,
-.005077,-.028049,
-.009871,-.026741,
-.01414,-.02475,
-.01923,-.02984,
-.013756,-.032726,
-.007864,-.034617,
-.001734,-.035457,
.00445,-.03522,
.010498,-.033912,
.016227,-.031574,
.01923,-.02984,
.01414,-.02475,
270.*
4,1,15,-.02475,-.01414,
-.026829,-.009627,
-.028094,-.004822,
-.028504,.000129,
-.028049,.005077,
-.026741,.009871,
-.02475,.01414,
-.02984,.01923,
-.032726,.013756,
-.034617,.007864,
-.035457,.001734,
-.03522,-.00445,
-.033912,-.010498,
-.031574,-.016227,
-.02984,-.01923,
-.02475,-.01414,
270.*
4,1,15,-.01414,.02475,
-.009627,.026829,
-.004822,.028094,
.000129,.028504,
.005077,.028049,
.009871,.026741,
.01414,.02475,
.01923,.02984,
.013756,.032726,
.007864,.034617,
.001734,.035457,
-.00445,.03522,
-.010498,.033912,
-.016227,.031574,
-.01923,.02984,
-.01414,.02475,
270.*
%
%ADD47MACRO47*%
%AMMACRO59*
4,1,15,.04124,.02356,
.044705,.016041,
.046811,.008034,
.047495,-.000216,
.046736,-.008461,
.044557,-.016448,
.04124,-.02356,
.04635,-.02867,
.050624,-.020186,
.05336,-.011088,
.054475,-.001654,
.053935,.007831,
.051756,.017077,
.048004,.025805,
.04635,.02867,
.04124,.02356,
0.0*
4,1,15,.02356,-.04124,
.016041,-.044705,
.008034,-.046811,
-.000216,-.047495,
-.008461,-.046736,
-.016448,-.044557,
-.02356,-.04124,
-.02867,-.04635,
-.020186,-.050624,
-.011088,-.05336,
-.001654,-.054475,
.007831,-.053935,
.017077,-.051756,
.025805,-.048004,
.02867,-.04635,
.02356,-.04124,
0.0*
4,1,15,-.04124,-.02356,
-.044705,-.016041,
-.046811,-.008034,
-.047495,.000216,
-.046736,.008461,
-.044557,.016448,
-.04124,.02356,
-.04635,.02867,
-.050624,.020186,
-.05336,.011088,
-.054475,.001654,
-.053935,-.007831,
-.051756,-.017077,
-.048004,-.025805,
-.04635,-.02867,
-.04124,-.02356,
0.0*
4,1,15,-.02356,.04124,
-.016041,.044705,
-.008034,.046811,
.000216,.047495,
.008461,.046736,
.016448,.044557,
.02356,.04124,
.02867,.04635,
.020186,.050624,
.011088,.05336,
.001654,.054475,
-.007831,.053935,
-.017077,.051756,
-.025805,.048004,
-.02867,.04635,
-.02356,.04124,
0.0*
%
%ADD59MACRO59*%
%AMMACRO79*
4,1,15,.03682,.01914,
.039584,.012455,
.041146,.005393,
.041457,-.001834,
.040509,-.009005,
.03833,-.015903,
.03682,-.01914,
.04197,-.0243,
.045552,-.016643,
.04775,-.00848,
.048497,-.000059,
.047771,.008363,
.045593,.016531,
.042029,.024197,
.04197,.0243,
.03682,.01914,
180.*
4,1,15,.01914,-.03682,
.012455,-.039584,
.005393,-.041146,
-.001834,-.041457,
-.009005,-.040509,
-.015903,-.03833,
-.01914,-.03682,
-.0243,-.04197,
-.016643,-.045552,
-.00848,-.04775,
-.000059,-.048497,
.008363,-.047771,
.016531,-.045593,
.024197,-.042029,
.0243,-.04197,
.01914,-.03682,
180.*
4,1,15,-.03682,-.01914,
-.039584,-.012455,
-.041146,-.005393,
-.041457,.001834,
-.040509,.009005,
-.03833,.015903,
-.03682,.01914,
-.04197,.0243,
-.045552,.016643,
-.04775,.00848,
-.048497,.000059,
-.047771,-.008363,
-.045593,-.016531,
-.042029,-.024197,
-.04197,-.0243,
-.03682,-.01914,
180.*
4,1,15,-.01914,.03682,
-.012455,.039584,
-.005393,.041146,
.001834,.041457,
.009005,.040509,
.015903,.03833,
.01914,.03682,
.0243,.04197,
.016643,.045552,
.00848,.04775,
.000059,.048497,
-.008363,.047771,
-.016531,.045593,
-.024197,.042029,
-.0243,.04197,
-.01914,.03682,
180.*
%
%ADD79MACRO79*%
%AMMACRO77*
4,1,15,-.03682,.01914,
-.039584,.012455,
-.041146,.005393,
-.041457,-.001834,
-.040509,-.009005,
-.03833,-.015903,
-.03682,-.01914,
-.04197,-.0243,
-.045552,-.016643,
-.04775,-.00848,
-.048497,-.000059,
-.047771,.008363,
-.045593,.016531,
-.042029,.024197,
-.04197,.0243,
-.03682,.01914,
180.*
4,1,15,-.01914,-.03682,
-.012455,-.039584,
-.005393,-.041146,
.001834,-.041457,
.009005,-.040509,
.015903,-.03833,
.01914,-.03682,
.0243,-.04197,
.016643,-.045552,
.00848,-.04775,
.000059,-.048497,
-.008363,-.047771,
-.016531,-.045593,
-.024197,-.042029,
-.0243,-.04197,
-.01914,-.03682,
180.*
4,1,15,.03682,-.01914,
.039584,-.012455,
.041146,-.005393,
.041457,.001834,
.040509,.009005,
.03833,.015903,
.03682,.01914,
.04197,.0243,
.045552,.016643,
.04775,.00848,
.048497,.000059,
.047771,-.008363,
.045593,-.016531,
.042029,-.024197,
.04197,-.0243,
.03682,-.01914,
180.*
4,1,15,.01914,.03682,
.012455,.039584,
.005393,.041146,
-.001834,.041457,
-.009005,.040509,
-.015903,.03833,
-.01914,.03682,
-.0243,.04197,
-.016643,.045552,
-.00848,.04775,
-.000059,.048497,
.008363,.047771,
.016531,.045593,
.024197,.042029,
.0243,.04197,
.01914,.03682,
180.*
%
%ADD77MACRO77*%
%ADD80C,.006*%
%ADD111C,.04006*%
%ADD105C,.03016*%
%ADD114C,.02604*%
%ADD100C,.03018*%
%ADD112C,.02605*%
%ADD115C,.02606*%
%ADD109C,.07008*%
%ADD83C,.07306*%
%ADD113C,.02609*%
%ADD92C,.07208*%
%ADD96C,.07308*%
%ADD106R,.00674X.03234*%
%ADD97C,.07608*%
%ADD107R,.00674X.03236*%
%ADD95C,.07808*%
%ADD94C,.09708*%
%ADD89O,.1621X.2251*%
%ADD85C,.311*%
%ADD103C,.1621*%
%ADD82O,.03004X.06404*%
%ADD104C,.16211*%
%ADD108R,.02206X.02404*%
%ADD99C,.1751*%
%ADD81O,.03006X.06406*%
%ADD116R,.02002X.01882*%
%ADD98C,.43406*%
%ADD84C,.16506*%
%ADD101R,.01604X.01906*%
%ADD90R,.01906X.01604*%
%ADD93C,.25806*%
%ADD91R,.01906X.01606*%
%ADD102C,.43376*%
%ADD110C,.19786*%
%ADD88O,.43374X.77626*%
%ADD86O,.43374X.69752*%
%ADD87O,.43376X.69754*%
G75*
%LPD*%
G75*
G36*
G01X-984580Y-698988D02*
X5868320D01*
Y4193602D01*
X-984580D01*
Y-698988D01*
G37*
%LPC*%
G75*
G36*
G01X895188Y129004D02*
X1002542D01*
X1009024Y122522D01*
Y46378D01*
G03X1018898Y36504I9874J0D01*
G01X1510244D01*
G02X1516118Y30630I0J-5874D01*
G01Y-3937D01*
G03X1525992Y-13811I9874J0D01*
G01X1796071D01*
G03X1805945Y-3937I0J9874D01*
G01Y30630D01*
G02X1811819Y36504I5874J0D01*
G01X1828062D01*
X1828081Y36500D01*
G03X1828470Y36462I388J1962D01*
G03X1828859Y36500I1J2000D01*
G01X1828878Y36504D01*
X1849606D01*
G02X1855480Y30630I0J-5874D01*
G01Y-40945D01*
G02X1849606Y-46819I-5874J0D01*
G01X7874D01*
G02X2000Y-40945I0J5874D01*
G01Y30630D01*
G02X7874Y36504I5874J0D01*
G01X35835D01*
G02X41709Y30630I0J-5874D01*
G01Y-3937D01*
G03X51583Y-13811I9874J0D01*
G01X321661D01*
G03X331535Y-3937I0J9874D01*
G01Y30630D01*
G02X337409Y36504I5874J0D01*
G01X480717D01*
G02X486591Y30630I0J-5874D01*
G01Y16850D01*
G03X496465Y6976I9874J0D01*
G01X766543D01*
G03X776417Y16850I0J9874D01*
G01Y30630D01*
G02X782291Y36504I5874J0D01*
G01X879134D01*
G03X889008Y46378I0J9874D01*
G01Y122824D01*
X895188Y129004D01*
G37*
G36*
G01X1829886Y1650538D02*
X1829890D01*
Y1650237D01*
X1829888Y1650228D01*
G03X1829820Y1649712I1932J-517D01*
G03X1829886Y1649203I2000J1D01*
G01Y1612316D01*
G03X1832779Y1605332I9877J0D01*
G01X1839978Y1598133D01*
G02X1841697Y1593983I-4151J-4151D01*
G01Y326095D01*
G03X1844590Y319111I9878J1D01*
G01X1853757Y309944D01*
G02X1855476Y305794I-4151J-4151D01*
G01Y54252D01*
G02X1849606Y48382I-5870J0D01*
G01X1829186D01*
Y48378D01*
X1827844D01*
Y48382D01*
X1803945D01*
G03X1794067Y38504I0J-9878D01*
G01Y3937D01*
G02X1792134Y2004I-1933J0D01*
G01X1529929D01*
G02X1527996Y3937I0J1933D01*
G01Y38504D01*
G03X1518118Y48382I-9878J0D01*
G01X1026772D01*
G02X1020902Y54252I0J5870D01*
G01Y131004D01*
G03X1011024Y140882I-9878J0D01*
G01X887008D01*
G03X877130Y131004I0J-9878D01*
G01Y54252D01*
G02X871260Y48382I-5870J0D01*
G01X774417D01*
G03X764539Y38504I0J-9878D01*
G01Y24724D01*
G02X762606Y22791I-1933J0D01*
G01X500402D01*
G02X498469Y24724I0J1933D01*
G01Y38504D01*
G03X488591Y48382I-9878J0D01*
G01X329535D01*
G03X319657Y38504I0J-9878D01*
G01Y3937D01*
G02X317724Y2004I-1933J0D01*
G01X55520D01*
G02X53587Y3937I0J1933D01*
G01Y38504D01*
G03X43709Y48382I-9878J0D01*
G01X7874D01*
G02X2004Y54252I0J5870D01*
G01Y305794D01*
G02X3723Y309944I5870J-1D01*
G01X6985Y313206D01*
G03X9878Y320190I-6984J6984D01*
G01Y1588078D01*
G02X11597Y1592228I5870J-1D01*
G01X24701Y1605332D01*
G03X27595Y1612316I-6983J6985D01*
G01Y1732244D01*
G02X33465Y1738114I5870J0D01*
G01X765732D01*
Y1736890D01*
G03X769705Y1732917I3973J0D01*
G01X1087854D01*
G03X1091827Y1736890I0J3973D01*
G01Y1738114D01*
X1824016D01*
G02X1829886Y1732244I0J-5870D01*
G01Y1650538D01*
G37*
G36*
G01X1867354Y305795D02*
G03X1862156Y318343I-17746J-1D01*
G01X1855296Y325203D01*
G02X1853575Y329357I4153J4154D01*
G01Y1593984D01*
G03X1848377Y1606532I-17746J-1D01*
G01X1843484Y1611425D01*
G02X1841764Y1615579I4156J4154D01*
G01Y1732244D01*
G02X1847638Y1738118I5874J0D01*
G01X1857480D01*
G03X1867354Y1747992I0J9874D01*
G01Y1815072D01*
G02X1873228Y1820946I5874J0D01*
G01X2093700D01*
G02X2099574Y1815072I0J-5874D01*
G01Y1791450D01*
G02X2093700Y1785576I-5874J0D01*
G01X2031574D01*
G03X2021700Y1775702I0J-9874D01*
G01Y1229954D01*
G03X2031574Y1220080I9874J0D01*
G01X2093700D01*
G02X2099574Y1214206I0J-5874D01*
G01Y-40945D01*
G02X2093700Y-46819I-5874J0D01*
G01X1873228D01*
G02X1867354Y-40945I0J5874D01*
G01Y305795D01*
G37*
%LPD*%
G75*
G36*
G01X1027874Y6319D02*
Y10639D01*
G02X1028176Y10942I302J1D01*
G01X1030586D01*
G02X1030888Y10639I-1J-303D01*
G01Y6319D01*
G02X1030586Y6016I-302J-1D01*
G01X1028176D01*
G02X1027874Y6319I1J303D01*
G37*
G36*
G01X1294850Y10659D02*
Y6339D01*
G02X1294548Y6036I-302J-1D01*
G01X1292138D01*
G02X1291836Y6339I1J303D01*
G01Y10659D01*
G02X1292138Y10962I302J1D01*
G01X1294548D01*
G02X1294850Y10659I-1J-303D01*
G37*
G36*
G01X1337192Y6319D02*
Y10639D01*
G02X1337495Y10942I303J0D01*
G01X1339905D01*
G02X1340208Y10639I0J-303D01*
G01Y6319D01*
G02X1339905Y6016I-303J0D01*
G01X1337495D01*
G02X1337192Y6319I0J303D01*
G37*
G36*
G01X1487210Y10659D02*
Y6339D01*
G02X1486907Y6036I-303J0D01*
G01X1484497D01*
G02X1484194Y6339I0J303D01*
G01Y10659D01*
G02X1484497Y10962I303J0D01*
G01X1486907D01*
G02X1487210Y10659I0J-303D01*
G37*
G36*
G01X1030586Y-29058D02*
G02X1030710Y-29085I-1J-303D01*
G03X1031202Y-28950I164J365D01*
G02X1032433Y-28308I1232J-861D01*
G02X1033936Y-29811I0J-1503D01*
G01Y-33211D01*
G02X1032433Y-34714I-1503J0D01*
G02X1031210Y-34084I0J1502D01*
G03X1030715Y-33955I-325J-233D01*
G02X1030586Y-33984I-129J274D01*
G01X1028176D01*
G02X1027874Y-33681I1J303D01*
G01Y-29361D01*
G02X1028176Y-29058I302J1D01*
G01X1030586D01*
G37*
G36*
G01X1288788Y-33211D02*
Y-29811D01*
G02X1290291Y-28308I1503J0D01*
G02X1291514Y-28938I0J-1502D01*
G03X1292009Y-29067I325J233D01*
G02X1292138Y-29038I129J-274D01*
G01X1294548D01*
G02X1294850Y-29341I-1J-303D01*
G01Y-33661D01*
G02X1294548Y-33964I-302J-1D01*
G01X1292138D01*
G02X1292014Y-33937I1J303D01*
G03X1291522Y-34072I-164J-365D01*
G02X1290291Y-34714I-1232J861D01*
G02X1288788Y-33211I0J1503D01*
G37*
G36*
G01X1339905Y-29058D02*
G02X1340029Y-29085I-1J-303D01*
G03X1340521Y-28950I164J365D01*
G02X1341752Y-28308I1232J-861D01*
G02X1343254Y-29811I-1J-1503D01*
G01Y-33211D01*
G02X1341752Y-34714I-1502J-1D01*
G02X1340529Y-34084I0J1502D01*
G03X1340034Y-33955I-325J-233D01*
G02X1339905Y-33984I-129J274D01*
G01X1337495D01*
G02X1337192Y-33681I0J303D01*
G01Y-29361D01*
G02X1337495Y-29058I303J0D01*
G01X1339905D01*
G37*
G36*
G01X1481148Y-33211D02*
Y-29811D01*
G02X1482650Y-28308I1502J1D01*
G02X1483873Y-28938I0J-1502D01*
G03X1484368Y-29067I325J233D01*
G02X1484497Y-29038I129J-274D01*
G01X1486907D01*
G02X1487210Y-29341I0J-303D01*
G01Y-33661D01*
G02X1486907Y-33964I-303J0D01*
G01X1484497D01*
G02X1484373Y-33937I1J303D01*
G03X1483881Y-34072I-164J-365D01*
G02X1482650Y-34714I-1232J861D01*
G02X1481148Y-33211I1J1503D01*
G37*
G36*
G01X721194Y-19048D02*
G02X721318Y-19074I1J-302D01*
G03X721810Y-18939I164J365D01*
G02X723041Y-18298I1231J-862D01*
G02X724544Y-19800I1J-1502D01*
G01Y-23200D01*
G02X723041Y-24702I-1503J1D01*
G02X721818Y-24073I-1J1502D01*
G03X721323Y-23944I-325J-233D01*
G02X721194Y-23972I-127J274D01*
G01X718784D01*
G02X718482Y-23670I0J302D01*
G01Y-19350D01*
G02X718784Y-19048I302J0D01*
G01X721194D01*
G37*
G36*
G01X979396Y-23200D02*
Y-19800D01*
G02X980899Y-18298I1503J-1D01*
G02X982122Y-18927I1J-1502D01*
G03X982617Y-19056I325J233D01*
G02X982746Y-19028I127J-274D01*
G01X985156D01*
G02X985458Y-19330I0J-302D01*
G01Y-23650D01*
G02X985156Y-23952I-302J0D01*
G01X982746D01*
G02X982622Y-23926I-1J302D01*
G03X982130Y-24061I-164J-365D01*
G02X980899Y-24702I-1231J862D01*
G02X979396Y-23200I-1J1502D01*
G37*
G36*
G01X1030586Y-9058D02*
G02X1030710Y-9085I-1J-303D01*
G03X1031202Y-8950I164J365D01*
G02X1032433Y-8308I1232J-861D01*
G02X1033936Y-9811I0J-1503D01*
G01Y-13211D01*
G02X1032433Y-14714I-1503J0D01*
G02X1031210Y-14084I0J1502D01*
G03X1030715Y-13955I-325J-233D01*
G02X1030586Y-13984I-129J274D01*
G01X1028176D01*
G02X1027874Y-13681I1J303D01*
G01Y-9361D01*
G02X1028176Y-9058I302J1D01*
G01X1030586D01*
G37*
G36*
G01X1288788Y-13211D02*
Y-9811D01*
G02X1290291Y-8308I1503J0D01*
G02X1291514Y-8938I0J-1502D01*
G03X1292009Y-9067I325J233D01*
G02X1292138Y-9038I129J-274D01*
G01X1294548D01*
G02X1294850Y-9341I-1J-303D01*
G01Y-13661D01*
G02X1294548Y-13964I-302J-1D01*
G01X1292138D01*
G02X1292014Y-13937I1J303D01*
G03X1291522Y-14072I-164J-365D01*
G02X1290291Y-14714I-1232J861D01*
G02X1288788Y-13211I0J1503D01*
G37*
G36*
G01X1339905Y-9058D02*
G02X1340029Y-9085I-1J-303D01*
G03X1340521Y-8950I164J365D01*
G02X1341752Y-8308I1232J-861D01*
G02X1343254Y-9811I-1J-1503D01*
G01Y-13211D01*
G02X1341752Y-14714I-1502J-1D01*
G02X1340529Y-14084I0J1502D01*
G03X1340034Y-13955I-325J-233D01*
G02X1339905Y-13984I-129J274D01*
G01X1337495D01*
G02X1337192Y-13681I0J303D01*
G01Y-9361D01*
G02X1337495Y-9058I303J0D01*
G01X1339905D01*
G37*
G36*
G01X1481148Y-13211D02*
Y-9811D01*
G02X1482650Y-8308I1502J1D01*
G02X1483873Y-8938I0J-1502D01*
G03X1484368Y-9067I325J233D01*
G02X1484497Y-9038I129J-274D01*
G01X1486907D01*
G02X1487210Y-9341I0J-303D01*
G01Y-13661D01*
G02X1486907Y-13964I-303J0D01*
G01X1484497D01*
G02X1484373Y-13937I1J303D01*
G03X1483881Y-14072I-164J-365D01*
G02X1482650Y-14714I-1232J861D01*
G02X1481148Y-13211I1J1503D01*
G37*
G36*
G01X838154Y10952D02*
G02X838278Y10926I1J-302D01*
G03X838770Y11061I164J365D01*
G02X840001Y11702I1231J-862D01*
G02X841504Y10200I1J-1502D01*
G01Y6800D01*
G02X840001Y5298I-1503J1D01*
G02X838778Y5927I-1J1502D01*
G03X838283Y6056I-325J-233D01*
G02X838154Y6028I-127J274D01*
G01X835744D01*
G02X835442Y6330I0J302D01*
G01Y10650D01*
G02X835744Y10952I302J0D01*
G01X838154D01*
G37*
G36*
G01X979396Y6800D02*
Y10200D01*
G02X980899Y11702I1503J-1D01*
G02X982122Y11073I1J-1502D01*
G03X982617Y10944I325J233D01*
G02X982746Y10972I127J-274D01*
G01X985156D01*
G02X985458Y10670I0J-302D01*
G01Y6350D01*
G02X985156Y6048I-302J0D01*
G01X982746D01*
G02X982622Y6074I-1J302D01*
G03X982130Y5939I-164J-365D01*
G02X980899Y5298I-1231J862D01*
G02X979396Y6800I-1J1502D01*
G37*
G36*
G01X1758669Y52153D02*
G02X1760173Y50649I0J-1504D01*
G01Y50648D01*
G02X1760172Y50593I-1504J0D01*
G02X1758669Y49100I-1503J10D01*
G01X1755269D01*
G02X1753766Y50593I0J1503D01*
G02X1753765Y50648I1503J55D01*
G01Y50649D01*
G02X1755269Y52153I1504J0D01*
G02X1755620Y52112I2J-1504D01*
G01X1755643Y52106D01*
X1758295D01*
X1758318Y52112D01*
G02X1758669Y52153I349J-1463D01*
G37*
G36*
G01X1394374Y172851D02*
G02X1395334Y173198I960J-1154D01*
G01X1398734D01*
G02X1400236Y171696I0J-1502D01*
G02X1398743Y170194I-1502J0D01*
G02X1398182Y170076I-561J1276D01*
G02X1397656Y170179I0J1394D01*
G01X1397620Y170194D01*
X1395334D01*
G02X1394882Y170264I1J1502D01*
G02X1394184Y170076I-699J1206D01*
G01X1394182D01*
G02Y172864I0J1394D01*
G02X1394374Y172851I2J-1394D01*
G37*
G36*
G01X880168Y504762D02*
Y508162D01*
G02X881670Y509664I1502J0D01*
G02X882945Y508955I0J-1501D01*
G02X883184Y508142I-1265J-813D01*
G01Y508141D01*
G02X883173Y507963I-1504J4D01*
G01X883172Y507952D01*
Y504897D01*
X883173Y504888D01*
G02X883180Y504743I-1493J-145D01*
G01Y504742D01*
G02X881680Y503242I-1500J0D01*
G02X880398Y503963I0J1500D01*
G02X880168Y504762I1273J799D01*
G37*
G36*
G01X963269Y1556947D02*
G03X963539I135J148D01*
G02X965904Y1557866I2365J-2584D01*
G02X969115Y1555762I0J-3502D01*
G02X970504Y1554262I-115J-1500D01*
G02X969016Y1552758I-1504J0D01*
G02X965904Y1550862I-3112J1606D01*
G02X963539Y1551781I0J3503D01*
G03X963269I-135J-148D01*
G02X960904Y1550862I-2365J2584D01*
G02Y1557866I0J3502D01*
G02X963269Y1556947I0J-3503D01*
G37*
G36*
G01X1010001D02*
G03X1010271I135J148D01*
G02X1012636Y1557866I2365J-2584D01*
G02X1015849Y1555757I0J-3502D01*
G02X1016012Y1555766I164J-1495D01*
G02Y1552758I0J-1504D01*
G02X1015759Y1552779I-3J1504D01*
G02X1012636Y1550862I-3123J1585D01*
G02X1010271Y1551781I0J3503D01*
G03X1010001I-135J-148D01*
G02X1007636Y1550862I-2365J2584D01*
G02Y1557866I0J3502D01*
G02X1010001Y1556947I0J-3503D01*
G37*
G36*
G01X1056733D02*
G03X1057003I135J148D01*
G02X1059368Y1557866I2365J-2584D01*
G02X1062579Y1555762I0J-3502D01*
G02X1063968Y1554262I-115J-1500D01*
G02X1062480Y1552758I-1504J0D01*
G02X1059368Y1550862I-3112J1606D01*
G02X1057003Y1551781I0J3503D01*
G03X1056733I-135J-148D01*
G02X1054368Y1550862I-2365J2584D01*
G02Y1557866I0J3502D01*
G02X1056733Y1556947I0J-3503D01*
G37*
G36*
G01X1080099D02*
G03X1080369I135J148D01*
G02X1082734Y1557866I2365J-2584D01*
G02X1085945Y1555762I0J-3502D01*
G02X1087334Y1554262I-115J-1500D01*
G02X1085846Y1552758I-1504J0D01*
G02X1082734Y1550862I-3112J1606D01*
G02X1080369Y1551781I0J3503D01*
G03X1080099I-135J-148D01*
G02X1077734Y1550862I-2365J2584D01*
G02Y1557866I0J3502D01*
G02X1080099Y1556947I0J-3503D01*
G37*
G36*
G01X986635D02*
G03X986905I135J148D01*
G02X989270Y1557866I2365J-2584D01*
G02X992481Y1555762I0J-3502D01*
G02X993966Y1554262I-15J-1500D01*
G02X992466Y1552762I-1500J0D01*
G02X992385Y1552764I-3J1500D01*
G02X989270Y1550862I-3115J1600D01*
G02X986905Y1551781I0J3503D01*
G03X986635I-135J-148D01*
G02X984270Y1550862I-2365J2584D01*
G02Y1557866I0J3502D01*
G02X986635Y1556947I0J-3503D01*
G37*
G36*
G01X1033367D02*
G03X1033637I135J148D01*
G02X1036002Y1557866I2365J-2584D01*
G02X1039214Y1555760I0J-3502D01*
G02X1039298Y1555762I78J-1498D01*
G02Y1552762I0J-1500D01*
G02X1039121Y1552772I-4J1500D01*
G02X1036002Y1550862I-3119J1592D01*
G02X1033637Y1551781I0J3503D01*
G03X1033367I-135J-148D01*
G02X1031002Y1550862I-2365J2584D01*
G02Y1557866I0J3502D01*
G02X1033367Y1556947I0J-3503D01*
G37*
G36*
G01X229206Y1656840D02*
X232906D01*
G02X233208Y1656537I-1J-303D01*
G01Y1646531D01*
G02X232906Y1646228I-302J-1D01*
G01X229206D01*
G02X228904Y1646531I1J303D01*
G01Y1648936D01*
G02X228890Y1649173I2002J237D01*
G02X228904Y1649410I2016J0D01*
G01Y1653660D01*
G02X228890Y1653897I2002J237D01*
G02X228904Y1654134I2016J0D01*
G01Y1656537D01*
G02X229206Y1656840I302J1D01*
G37*
G36*
G01X276450D02*
X280150D01*
G02X280452Y1656537I-1J-303D01*
G01Y1646531D01*
G02X280150Y1646228I-302J-1D01*
G01X276450D01*
G02X276148Y1646531I1J303D01*
G01Y1648936D01*
G02X276134Y1649173I2002J237D01*
G02X276148Y1649410I2016J0D01*
G01Y1653660D01*
G02X276134Y1653897I2002J237D01*
G02X276148Y1654134I2016J0D01*
G01Y1656537D01*
G02X276450Y1656840I302J1D01*
G37*
G36*
G01X237080Y1660776D02*
X240780D01*
G02X241082Y1660474I0J-302D01*
G01Y1650468D01*
G02X240780Y1650166I-302J0D01*
G01X237080D01*
G02X236778Y1650468I0J302D01*
G01Y1652873D01*
G02X236764Y1653110I2002J237D01*
G02X236778Y1653347I2016J0D01*
G01Y1657597D01*
G02X236764Y1657834I2002J237D01*
G02X236778Y1658071I2016J0D01*
G01Y1660474D01*
G02X237080Y1660776I302J0D01*
G37*
G36*
G01X268576D02*
X272276D01*
G02X272578Y1660474I0J-302D01*
G01Y1650468D01*
G02X272276Y1650166I-302J0D01*
G01X268576D01*
G02X268274Y1650468I0J302D01*
G01Y1652873D01*
G02X268260Y1653110I2002J237D01*
G02X268274Y1653347I2016J0D01*
G01Y1657597D01*
G02X268260Y1657834I2002J237D01*
G02X268274Y1658071I2016J0D01*
G01Y1660474D01*
G02X268576Y1660776I302J0D01*
G37*
G36*
G01X284324D02*
X288024D01*
G02X288326Y1660474I0J-302D01*
G01Y1650468D01*
G02X288024Y1650166I-302J0D01*
G01X284324D01*
G02X284022Y1650468I0J302D01*
G01Y1652873D01*
G02X284008Y1653110I2002J237D01*
G02X284022Y1653347I2016J0D01*
G01Y1657597D01*
G02X284008Y1657834I2002J237D01*
G02X284022Y1658071I2016J0D01*
G01Y1660474D01*
G02X284324Y1660776I302J0D01*
G37*
G36*
G01X229206Y1671014D02*
X232906D01*
G02X233208Y1670711I-1J-303D01*
G01Y1660705D01*
G02X232906Y1660402I-302J-1D01*
G01X229206D01*
G02X228904Y1660705I1J303D01*
G01Y1663109D01*
G02X228890Y1663346I2002J237D01*
G02X228904Y1663583I2016J0D01*
G01Y1667833D01*
G02X228890Y1668070I2002J237D01*
G02X228904Y1668307I2016J0D01*
G01Y1670711D01*
G02X229206Y1671014I302J1D01*
G37*
G36*
G01X244954D02*
X248654D01*
G02X248956Y1670711I-1J-303D01*
G01Y1660705D01*
G02X248654Y1660402I-302J-1D01*
G01X244954D01*
G02X244652Y1660705I1J303D01*
G01Y1663109D01*
G02X244638Y1663346I2002J237D01*
G02X244652Y1663583I2016J0D01*
G01Y1667833D01*
G02X244638Y1668070I2002J237D01*
G02X244652Y1668307I2016J0D01*
G01Y1670711D01*
G02X244954Y1671014I302J1D01*
G37*
G36*
G01X276450D02*
X280150D01*
G02X280452Y1670711I-1J-303D01*
G01Y1660705D01*
G02X280150Y1660402I-302J-1D01*
G01X276450D01*
G02X276148Y1660705I1J303D01*
G01Y1663109D01*
G02X276134Y1663346I2002J237D01*
G02X276148Y1663583I2016J0D01*
G01Y1667833D01*
G02X276134Y1668070I2002J237D01*
G02X276148Y1668307I2016J0D01*
G01Y1670711D01*
G02X276450Y1671014I302J1D01*
G37*
G36*
G01X252828Y1674950D02*
X256528D01*
G02X256830Y1674648I0J-302D01*
G01Y1664642D01*
G02X256528Y1664340I-302J0D01*
G01X252828D01*
G02X252526Y1664642I0J302D01*
G01Y1667046D01*
G02X252512Y1667283I2002J237D01*
G02X252526Y1667520I2016J0D01*
G01Y1671770D01*
G02X252512Y1672007I2002J237D01*
G02X252526Y1672244I2016J0D01*
G01Y1674648D01*
G02X252828Y1674950I302J0D01*
G37*
G36*
G01X268576D02*
X272276D01*
G02X272578Y1674648I0J-302D01*
G01Y1664642D01*
G02X272276Y1664340I-302J0D01*
G01X268576D01*
G02X268274Y1664642I0J302D01*
G01Y1667046D01*
G02X268260Y1667283I2002J237D01*
G02X268274Y1667520I2016J0D01*
G01Y1671770D01*
G02X268260Y1672007I2002J237D01*
G02X268274Y1672244I2016J0D01*
G01Y1674648D01*
G02X268576Y1674950I302J0D01*
G37*
G36*
G01X284324D02*
X288024D01*
G02X288326Y1674648I0J-302D01*
G01Y1664642D01*
G02X288024Y1664340I-302J0D01*
G01X284324D01*
G02X284022Y1664642I0J302D01*
G01Y1667046D01*
G02X284008Y1667283I2002J237D01*
G02X284022Y1667520I2016J0D01*
G01Y1671770D01*
G02X284008Y1672007I2002J237D01*
G02X284022Y1672244I2016J0D01*
G01Y1674648D01*
G02X284324Y1674950I302J0D01*
G37*
G36*
G01X229206Y1685186D02*
X232906D01*
G02X233208Y1684884I0J-302D01*
G01Y1674878D01*
G02X232906Y1674576I-302J0D01*
G01X229206D01*
G02X228904Y1674878I0J302D01*
G01Y1677282D01*
G02X228890Y1677519I2002J237D01*
G02X228904Y1677756I2016J0D01*
G01Y1682007D01*
G02X228890Y1682244I2002J237D01*
G02X228904Y1682481I2016J0D01*
G01Y1684884D01*
G02X229206Y1685186I302J0D01*
G37*
G36*
G01X244954D02*
X248654D01*
G02X248956Y1684884I0J-302D01*
G01Y1674878D01*
G02X248654Y1674576I-302J0D01*
G01X244954D01*
G02X244652Y1674878I0J302D01*
G01Y1677282D01*
G02X244638Y1677519I2002J237D01*
G02X244652Y1677756I2016J0D01*
G01Y1682007D01*
G02X244638Y1682244I2002J237D01*
G02X244652Y1682481I2016J0D01*
G01Y1684884D01*
G02X244954Y1685186I302J0D01*
G37*
G36*
G01X260702D02*
X264402D01*
G02X264704Y1684884I0J-302D01*
G01Y1674878D01*
G02X264402Y1674576I-302J0D01*
G01X260702D01*
G02X260400Y1674878I0J302D01*
G01Y1677282D01*
G02X260386Y1677519I2002J237D01*
G02X260400Y1677756I2016J0D01*
G01Y1682007D01*
G02X260386Y1682244I2002J237D01*
G02X260400Y1682481I2016J0D01*
G01Y1684884D01*
G02X260702Y1685186I302J0D01*
G37*
G36*
G01X276450D02*
X280150D01*
G02X280452Y1684884I0J-302D01*
G01Y1674878D01*
G02X280150Y1674576I-302J0D01*
G01X276450D01*
G02X276148Y1674878I0J302D01*
G01Y1677282D01*
G02X276134Y1677519I2002J237D01*
G02X276148Y1677756I2016J0D01*
G01Y1682007D01*
G02X276134Y1682244I2002J237D01*
G02X276148Y1682481I2016J0D01*
G01Y1684884D01*
G02X276450Y1685186I302J0D01*
G37*
G36*
G01X560308D02*
X564008D01*
G02X564310Y1684884I0J-302D01*
G01Y1674878D01*
G02X564008Y1674576I-302J0D01*
G01X560308D01*
G02X560006Y1674878I0J302D01*
G01Y1677282D01*
G02X559992Y1677519I2002J237D01*
G02X560006Y1677756I2016J0D01*
G01Y1682007D01*
G02X559992Y1682244I2002J237D01*
G02X560006Y1682481I2016J0D01*
G01Y1684884D01*
G02X560308Y1685186I302J0D01*
G37*
G36*
G01X576056D02*
X579756D01*
G02X580058Y1684884I0J-302D01*
G01Y1674878D01*
G02X579756Y1674576I-302J0D01*
G01X576056D01*
G02X575754Y1674878I0J302D01*
G01Y1677282D01*
G02X575740Y1677519I2002J237D01*
G02X575754Y1677756I2016J0D01*
G01Y1682007D01*
G02X575740Y1682244I2002J237D01*
G02X575754Y1682481I2016J0D01*
G01Y1684884D01*
G02X576056Y1685186I302J0D01*
G37*
G36*
G01X591804D02*
X595504D01*
G02X595806Y1684884I0J-302D01*
G01Y1674878D01*
G02X595504Y1674576I-302J0D01*
G01X591804D01*
G02X591502Y1674878I0J302D01*
G01Y1677282D01*
G02X591488Y1677519I2002J237D01*
G02X591502Y1677756I2016J0D01*
G01Y1682007D01*
G02X591488Y1682244I2002J237D01*
G02X591502Y1682481I2016J0D01*
G01Y1684884D01*
G02X591804Y1685186I302J0D01*
G37*
G36*
G01X607552D02*
X611252D01*
G02X611554Y1684884I0J-302D01*
G01Y1674878D01*
G02X611252Y1674576I-302J0D01*
G01X607552D01*
G02X607250Y1674878I0J302D01*
G01Y1677282D01*
G02X607236Y1677519I2002J237D01*
G02X607250Y1677756I2016J0D01*
G01Y1682007D01*
G02X607236Y1682244I2002J237D01*
G02X607250Y1682481I2016J0D01*
G01Y1684884D01*
G02X607552Y1685186I302J0D01*
G37*
G36*
G01X1237080D02*
X1240780D01*
G02X1241082Y1684884I0J-302D01*
G01Y1674878D01*
G02X1240780Y1674576I-302J0D01*
G01X1237080D01*
G02X1236778Y1674878I0J302D01*
G01Y1677282D01*
G02X1236764Y1677519I2002J237D01*
G02X1236778Y1677756I2016J0D01*
G01Y1682007D01*
G02X1236764Y1682244I2002J237D01*
G02X1236778Y1682481I2016J0D01*
G01Y1684884D01*
G02X1237080Y1685186I302J0D01*
G37*
G36*
G01X1252828D02*
X1256528D01*
G02X1256830Y1684884I0J-302D01*
G01Y1674878D01*
G02X1256528Y1674576I-302J0D01*
G01X1252828D01*
G02X1252526Y1674878I0J302D01*
G01Y1677282D01*
G02X1252512Y1677519I2002J237D01*
G02X1252526Y1677756I2016J0D01*
G01Y1682007D01*
G02X1252512Y1682244I2002J237D01*
G02X1252526Y1682481I2016J0D01*
G01Y1684884D01*
G02X1252828Y1685186I302J0D01*
G37*
G36*
G01X1268576D02*
X1272276D01*
G02X1272578Y1684884I0J-302D01*
G01Y1674878D01*
G02X1272276Y1674576I-302J0D01*
G01X1268576D01*
G02X1268274Y1674878I0J302D01*
G01Y1677282D01*
G02X1268260Y1677519I2002J237D01*
G02X1268274Y1677756I2016J0D01*
G01Y1682007D01*
G02X1268260Y1682244I2002J237D01*
G02X1268274Y1682481I2016J0D01*
G01Y1684884D01*
G02X1268576Y1685186I302J0D01*
G37*
G36*
G01X1284324D02*
X1288024D01*
G02X1288326Y1684884I0J-302D01*
G01Y1674878D01*
G02X1288024Y1674576I-302J0D01*
G01X1284324D01*
G02X1284022Y1674878I0J302D01*
G01Y1677282D01*
G02X1284008Y1677519I2002J237D01*
G02X1284022Y1677756I2016J0D01*
G01Y1682007D01*
G02X1284008Y1682244I2002J237D01*
G02X1284022Y1682481I2016J0D01*
G01Y1684884D01*
G02X1284324Y1685186I302J0D01*
G37*
G36*
G01X1568182D02*
X1571882D01*
G02X1572184Y1684884I0J-302D01*
G01Y1674878D01*
G02X1571882Y1674576I-302J0D01*
G01X1568182D01*
G02X1567880Y1674878I0J302D01*
G01Y1677282D01*
G02X1567866Y1677519I2002J237D01*
G02X1567880Y1677756I2016J0D01*
G01Y1682007D01*
G02X1567866Y1682244I2002J237D01*
G02X1567880Y1682481I2016J0D01*
G01Y1684884D01*
G02X1568182Y1685186I302J0D01*
G37*
G36*
G01X1583930D02*
X1587630D01*
G02X1587932Y1684884I0J-302D01*
G01Y1674878D01*
G02X1587630Y1674576I-302J0D01*
G01X1583930D01*
G02X1583628Y1674878I0J302D01*
G01Y1677282D01*
G02X1583614Y1677519I2002J237D01*
G02X1583628Y1677756I2016J0D01*
G01Y1682007D01*
G02X1583614Y1682244I2002J237D01*
G02X1583628Y1682481I2016J0D01*
G01Y1684884D01*
G02X1583930Y1685186I302J0D01*
G37*
G36*
G01X1599678D02*
X1603378D01*
G02X1603680Y1684884I0J-302D01*
G01Y1674878D01*
G02X1603378Y1674576I-302J0D01*
G01X1599678D01*
G02X1599376Y1674878I0J302D01*
G01Y1677282D01*
G02X1599362Y1677519I2002J237D01*
G02X1599376Y1677756I2016J0D01*
G01Y1682007D01*
G02X1599362Y1682244I2002J237D01*
G02X1599376Y1682481I2016J0D01*
G01Y1684884D01*
G02X1599678Y1685186I302J0D01*
G37*
G36*
G01X1615426D02*
X1619126D01*
G02X1619428Y1684884I0J-302D01*
G01Y1674878D01*
G02X1619126Y1674576I-302J0D01*
G01X1615426D01*
G02X1615124Y1674878I0J302D01*
G01Y1677282D01*
G02X1615110Y1677519I2002J237D01*
G02X1615124Y1677756I2016J0D01*
G01Y1682007D01*
G02X1615110Y1682244I2002J237D01*
G02X1615124Y1682481I2016J0D01*
G01Y1684884D01*
G02X1615426Y1685186I302J0D01*
G37*
G36*
G01X296135D02*
X299835D01*
G02X300138Y1684884I1J-302D01*
G01Y1674878D01*
G02X299835Y1674576I-303J1D01*
G01X296135D01*
G02X295832Y1674878I-1J302D01*
G01Y1677290D01*
G02X295819Y1677519I2003J229D01*
G02X295832Y1677748I2016J0D01*
G01Y1682015D01*
G02X295819Y1682244I2003J229D01*
G02X295832Y1682473I2016J0D01*
G01Y1684884D01*
G02X296135Y1685186I303J-1D01*
G37*
G36*
G01X311883D02*
X315583D01*
G02X315886Y1684884I1J-302D01*
G01Y1674878D01*
G02X315583Y1674576I-303J1D01*
G01X311883D01*
G02X311580Y1674878I-1J302D01*
G01Y1677290D01*
G02X311567Y1677519I2003J229D01*
G02X311580Y1677748I2016J0D01*
G01Y1682015D01*
G02X311567Y1682244I2003J229D01*
G02X311580Y1682473I2016J0D01*
G01Y1684884D01*
G02X311883Y1685186I303J-1D01*
G37*
G36*
G01X327631D02*
X331331D01*
G02X331634Y1684884I1J-302D01*
G01Y1674878D01*
G02X331331Y1674576I-303J1D01*
G01X327631D01*
G02X327328Y1674878I-1J302D01*
G01Y1677290D01*
G02X327315Y1677519I2003J229D01*
G02X327328Y1677748I2016J0D01*
G01Y1682015D01*
G02X327315Y1682244I2003J229D01*
G02X327328Y1682473I2016J0D01*
G01Y1684884D01*
G02X327631Y1685186I303J-1D01*
G37*
G36*
G01X343379D02*
X347079D01*
G02X347382Y1684884I1J-302D01*
G01Y1674878D01*
G02X347079Y1674576I-303J1D01*
G01X343379D01*
G02X343076Y1674878I-1J302D01*
G01Y1677290D01*
G02X343063Y1677519I2003J229D01*
G02X343076Y1677748I2016J0D01*
G01Y1682015D01*
G02X343063Y1682244I2003J229D01*
G02X343076Y1682473I2016J0D01*
G01Y1684884D01*
G02X343379Y1685186I303J-1D01*
G37*
G36*
G01X493379D02*
X497079D01*
G02X497382Y1684884I1J-302D01*
G01Y1674878D01*
G02X497079Y1674576I-303J1D01*
G01X493379D01*
G02X493076Y1674878I-1J302D01*
G01Y1677290D01*
G02X493063Y1677519I2003J229D01*
G02X493076Y1677748I2016J0D01*
G01Y1682015D01*
G02X493063Y1682244I2003J229D01*
G02X493076Y1682473I2016J0D01*
G01Y1684884D01*
G02X493379Y1685186I303J-1D01*
G37*
G36*
G01X509127D02*
X512827D01*
G02X513130Y1684884I1J-302D01*
G01Y1674878D01*
G02X512827Y1674576I-303J1D01*
G01X509127D01*
G02X508824Y1674878I-1J302D01*
G01Y1677290D01*
G02X508811Y1677519I2003J229D01*
G02X508824Y1677748I2016J0D01*
G01Y1682015D01*
G02X508811Y1682244I2003J229D01*
G02X508824Y1682473I2016J0D01*
G01Y1684884D01*
G02X509127Y1685186I303J-1D01*
G37*
G36*
G01X524875D02*
X528575D01*
G02X528878Y1684884I1J-302D01*
G01Y1674878D01*
G02X528575Y1674576I-303J1D01*
G01X524875D01*
G02X524572Y1674878I-1J302D01*
G01Y1677290D01*
G02X524559Y1677519I2003J229D01*
G02X524572Y1677748I2016J0D01*
G01Y1682015D01*
G02X524559Y1682244I2003J229D01*
G02X524572Y1682473I2016J0D01*
G01Y1684884D01*
G02X524875Y1685186I303J-1D01*
G37*
G36*
G01X540623D02*
X544323D01*
G02X544626Y1684884I1J-302D01*
G01Y1674878D01*
G02X544323Y1674576I-303J1D01*
G01X540623D01*
G02X540320Y1674878I-1J302D01*
G01Y1677290D01*
G02X540307Y1677519I2003J229D01*
G02X540320Y1677748I2016J0D01*
G01Y1682015D01*
G02X540307Y1682244I2003J229D01*
G02X540320Y1682473I2016J0D01*
G01Y1684884D01*
G02X540623Y1685186I303J-1D01*
G37*
G36*
G01X1304009D02*
X1307709D01*
G02X1308012Y1684884I1J-302D01*
G01Y1674878D01*
G02X1307709Y1674576I-303J1D01*
G01X1304009D01*
G02X1303706Y1674878I-1J302D01*
G01Y1677290D01*
G02X1303693Y1677519I2003J229D01*
G02X1303706Y1677748I2016J0D01*
G01Y1682015D01*
G02X1303693Y1682244I2003J229D01*
G02X1303706Y1682473I2016J0D01*
G01Y1684884D01*
G02X1304009Y1685186I303J-1D01*
G37*
G36*
G01X1319757D02*
X1323457D01*
G02X1323760Y1684884I1J-302D01*
G01Y1674878D01*
G02X1323457Y1674576I-303J1D01*
G01X1319757D01*
G02X1319454Y1674878I-1J302D01*
G01Y1677290D01*
G02X1319441Y1677519I2003J229D01*
G02X1319454Y1677748I2016J0D01*
G01Y1682015D01*
G02X1319441Y1682244I2003J229D01*
G02X1319454Y1682473I2016J0D01*
G01Y1684884D01*
G02X1319757Y1685186I303J-1D01*
G37*
G36*
G01X1335505D02*
X1339205D01*
G02X1339508Y1684884I1J-302D01*
G01Y1674878D01*
G02X1339205Y1674576I-303J1D01*
G01X1335505D01*
G02X1335202Y1674878I-1J302D01*
G01Y1677290D01*
G02X1335189Y1677519I2003J229D01*
G02X1335202Y1677748I2016J0D01*
G01Y1682015D01*
G02X1335189Y1682244I2003J229D01*
G02X1335202Y1682473I2016J0D01*
G01Y1684884D01*
G02X1335505Y1685186I303J-1D01*
G37*
G36*
G01X1351253D02*
X1354953D01*
G02X1355256Y1684884I1J-302D01*
G01Y1674878D01*
G02X1354953Y1674576I-303J1D01*
G01X1351253D01*
G02X1350950Y1674878I-1J302D01*
G01Y1677290D01*
G02X1350937Y1677519I2003J229D01*
G02X1350950Y1677748I2016J0D01*
G01Y1682015D01*
G02X1350937Y1682244I2003J229D01*
G02X1350950Y1682473I2016J0D01*
G01Y1684884D01*
G02X1351253Y1685186I303J-1D01*
G37*
G36*
G01X1501253D02*
X1504953D01*
G02X1505256Y1684884I1J-302D01*
G01Y1674878D01*
G02X1504953Y1674576I-303J1D01*
G01X1501253D01*
G02X1500950Y1674878I-1J302D01*
G01Y1677290D01*
G02X1500937Y1677519I2003J229D01*
G02X1500950Y1677748I2016J0D01*
G01Y1682015D01*
G02X1500937Y1682244I2003J229D01*
G02X1500950Y1682473I2016J0D01*
G01Y1684884D01*
G02X1501253Y1685186I303J-1D01*
G37*
G36*
G01X1517001D02*
X1520701D01*
G02X1521004Y1684884I1J-302D01*
G01Y1674878D01*
G02X1520701Y1674576I-303J1D01*
G01X1517001D01*
G02X1516698Y1674878I-1J302D01*
G01Y1677290D01*
G02X1516685Y1677519I2003J229D01*
G02X1516698Y1677748I2016J0D01*
G01Y1682015D01*
G02X1516685Y1682244I2003J229D01*
G02X1516698Y1682473I2016J0D01*
G01Y1684884D01*
G02X1517001Y1685186I303J-1D01*
G37*
G36*
G01X1532749D02*
X1536449D01*
G02X1536752Y1684884I1J-302D01*
G01Y1674878D01*
G02X1536449Y1674576I-303J1D01*
G01X1532749D01*
G02X1532446Y1674878I-1J302D01*
G01Y1677290D01*
G02X1532433Y1677519I2003J229D01*
G02X1532446Y1677748I2016J0D01*
G01Y1682015D01*
G02X1532433Y1682244I2003J229D01*
G02X1532446Y1682473I2016J0D01*
G01Y1684884D01*
G02X1532749Y1685186I303J-1D01*
G37*
G36*
G01X1548497D02*
X1552197D01*
G02X1552500Y1684884I1J-302D01*
G01Y1674878D01*
G02X1552197Y1674576I-303J1D01*
G01X1548497D01*
G02X1548194Y1674878I-1J302D01*
G01Y1677290D01*
G02X1548181Y1677519I2003J229D01*
G02X1548194Y1677748I2016J0D01*
G01Y1682015D01*
G02X1548181Y1682244I2003J229D01*
G02X1548194Y1682473I2016J0D01*
G01Y1684884D01*
G02X1548497Y1685186I303J-1D01*
G37*
G36*
G01X237080Y1689124D02*
X240780D01*
G02X241082Y1688821I-1J-303D01*
G01Y1678815D01*
G02X240780Y1678512I-302J-1D01*
G01X237080D01*
G02X236778Y1678815I1J303D01*
G01Y1681219D01*
G02X236764Y1681456I2002J237D01*
G02X236778Y1681693I2016J0D01*
G01Y1685943D01*
G02X236764Y1686180I2002J237D01*
G02X236778Y1686417I2016J0D01*
G01Y1688821D01*
G02X237080Y1689124I302J1D01*
G37*
G36*
G01X252828D02*
X256528D01*
G02X256830Y1688821I-1J-303D01*
G01Y1678815D01*
G02X256528Y1678512I-302J-1D01*
G01X252828D01*
G02X252526Y1678815I1J303D01*
G01Y1681219D01*
G02X252512Y1681456I2002J237D01*
G02X252526Y1681693I2016J0D01*
G01Y1685943D01*
G02X252512Y1686180I2002J237D01*
G02X252526Y1686417I2016J0D01*
G01Y1688821D01*
G02X252828Y1689124I302J1D01*
G37*
G36*
G01X268576D02*
X272276D01*
G02X272578Y1688821I-1J-303D01*
G01Y1678815D01*
G02X272276Y1678512I-302J-1D01*
G01X268576D01*
G02X268274Y1678815I1J303D01*
G01Y1681219D01*
G02X268260Y1681456I2002J237D01*
G02X268274Y1681693I2016J0D01*
G01Y1685943D01*
G02X268260Y1686180I2002J237D01*
G02X268274Y1686417I2016J0D01*
G01Y1688821D01*
G02X268576Y1689124I302J1D01*
G37*
G36*
G01X284324D02*
X288024D01*
G02X288326Y1688821I-1J-303D01*
G01Y1678815D01*
G02X288024Y1678512I-302J-1D01*
G01X284324D01*
G02X284022Y1678815I1J303D01*
G01Y1681219D01*
G02X284008Y1681456I2002J237D01*
G02X284022Y1681693I2016J0D01*
G01Y1685943D01*
G02X284008Y1686180I2002J237D01*
G02X284022Y1686417I2016J0D01*
G01Y1688821D01*
G02X284324Y1689124I302J1D01*
G37*
G36*
G01X304009D02*
X307709D01*
G02X308012Y1688821I0J-303D01*
G01Y1678815D01*
G02X307709Y1678512I-303J0D01*
G01X304009D01*
G02X303706Y1678815I0J303D01*
G01Y1681227D01*
G02X303693Y1681456I2003J229D01*
G02X303706Y1681685I2016J0D01*
G01Y1685951D01*
G02X303693Y1686180I2003J229D01*
G02X303706Y1686409I2016J0D01*
G01Y1688821D01*
G02X304009Y1689124I303J0D01*
G37*
G36*
G01X319757D02*
X323457D01*
G02X323760Y1688821I0J-303D01*
G01Y1678815D01*
G02X323457Y1678512I-303J0D01*
G01X319757D01*
G02X319454Y1678815I0J303D01*
G01Y1681227D01*
G02X319441Y1681456I2003J229D01*
G02X319454Y1681685I2016J0D01*
G01Y1685951D01*
G02X319441Y1686180I2003J229D01*
G02X319454Y1686409I2016J0D01*
G01Y1688821D01*
G02X319757Y1689124I303J0D01*
G37*
G36*
G01X335505D02*
X339205D01*
G02X339508Y1688821I0J-303D01*
G01Y1678815D01*
G02X339205Y1678512I-303J0D01*
G01X335505D01*
G02X335202Y1678815I0J303D01*
G01Y1681227D01*
G02X335189Y1681456I2003J229D01*
G02X335202Y1681685I2016J0D01*
G01Y1685951D01*
G02X335189Y1686180I2003J229D01*
G02X335202Y1686409I2016J0D01*
G01Y1688821D01*
G02X335505Y1689124I303J0D01*
G37*
G36*
G01X351253D02*
X354953D01*
G02X355256Y1688821I0J-303D01*
G01Y1678815D01*
G02X354953Y1678512I-303J0D01*
G01X351253D01*
G02X350950Y1678815I0J303D01*
G01Y1681227D01*
G02X350937Y1681456I2003J229D01*
G02X350950Y1681685I2016J0D01*
G01Y1685951D01*
G02X350937Y1686180I2003J229D01*
G02X350950Y1686409I2016J0D01*
G01Y1688821D01*
G02X351253Y1689124I303J0D01*
G37*
G36*
G01X501253D02*
X504953D01*
G02X505256Y1688821I0J-303D01*
G01Y1678815D01*
G02X504953Y1678512I-303J0D01*
G01X501253D01*
G02X500950Y1678815I0J303D01*
G01Y1681227D01*
G02X500937Y1681456I2003J229D01*
G02X500950Y1681685I2016J0D01*
G01Y1685951D01*
G02X500937Y1686180I2003J229D01*
G02X500950Y1686409I2016J0D01*
G01Y1688821D01*
G02X501253Y1689124I303J0D01*
G37*
G36*
G01X517001D02*
X520701D01*
G02X521004Y1688821I0J-303D01*
G01Y1678815D01*
G02X520701Y1678512I-303J0D01*
G01X517001D01*
G02X516698Y1678815I0J303D01*
G01Y1681227D01*
G02X516685Y1681456I2003J229D01*
G02X516698Y1681685I2016J0D01*
G01Y1685951D01*
G02X516685Y1686180I2003J229D01*
G02X516698Y1686409I2016J0D01*
G01Y1688821D01*
G02X517001Y1689124I303J0D01*
G37*
G36*
G01X532749D02*
X536449D01*
G02X536752Y1688821I0J-303D01*
G01Y1678815D01*
G02X536449Y1678512I-303J0D01*
G01X532749D01*
G02X532446Y1678815I0J303D01*
G01Y1681227D01*
G02X532433Y1681456I2003J229D01*
G02X532446Y1681685I2016J0D01*
G01Y1685951D01*
G02X532433Y1686180I2003J229D01*
G02X532446Y1686409I2016J0D01*
G01Y1688821D01*
G02X532749Y1689124I303J0D01*
G37*
G36*
G01X548497D02*
X552197D01*
G02X552500Y1688821I0J-303D01*
G01Y1678815D01*
G02X552197Y1678512I-303J0D01*
G01X548497D01*
G02X548194Y1678815I0J303D01*
G01Y1681227D01*
G02X548181Y1681456I2003J229D01*
G02X548194Y1681685I2016J0D01*
G01Y1685951D01*
G02X548181Y1686180I2003J229D01*
G02X548194Y1686409I2016J0D01*
G01Y1688821D01*
G02X548497Y1689124I303J0D01*
G37*
G36*
G01X568182D02*
X571882D01*
G02X572184Y1688821I-1J-303D01*
G01Y1678815D01*
G02X571882Y1678512I-302J-1D01*
G01X568182D01*
G02X567880Y1678815I1J303D01*
G01Y1681219D01*
G02X567866Y1681456I2002J237D01*
G02X567880Y1681693I2016J0D01*
G01Y1685943D01*
G02X567866Y1686180I2002J237D01*
G02X567880Y1686417I2016J0D01*
G01Y1688821D01*
G02X568182Y1689124I302J1D01*
G37*
G36*
G01X583930D02*
X587630D01*
G02X587932Y1688821I-1J-303D01*
G01Y1678815D01*
G02X587630Y1678512I-302J-1D01*
G01X583930D01*
G02X583628Y1678815I1J303D01*
G01Y1681219D01*
G02X583614Y1681456I2002J237D01*
G02X583628Y1681693I2016J0D01*
G01Y1685943D01*
G02X583614Y1686180I2002J237D01*
G02X583628Y1686417I2016J0D01*
G01Y1688821D01*
G02X583930Y1689124I302J1D01*
G37*
G36*
G01X599678D02*
X603378D01*
G02X603680Y1688821I-1J-303D01*
G01Y1678815D01*
G02X603378Y1678512I-302J-1D01*
G01X599678D01*
G02X599376Y1678815I1J303D01*
G01Y1681219D01*
G02X599362Y1681456I2002J237D01*
G02X599376Y1681693I2016J0D01*
G01Y1685943D01*
G02X599362Y1686180I2002J237D01*
G02X599376Y1686417I2016J0D01*
G01Y1688821D01*
G02X599678Y1689124I302J1D01*
G37*
G36*
G01X615426D02*
X619126D01*
G02X619428Y1688821I-1J-303D01*
G01Y1678815D01*
G02X619126Y1678512I-302J-1D01*
G01X615426D01*
G02X615124Y1678815I1J303D01*
G01Y1681219D01*
G02X615110Y1681456I2002J237D01*
G02X615124Y1681693I2016J0D01*
G01Y1685943D01*
G02X615110Y1686180I2002J237D01*
G02X615124Y1686417I2016J0D01*
G01Y1688821D01*
G02X615426Y1689124I302J1D01*
G37*
G36*
G01X1244954D02*
X1248654D01*
G02X1248956Y1688821I-1J-303D01*
G01Y1678815D01*
G02X1248654Y1678512I-302J-1D01*
G01X1244954D01*
G02X1244652Y1678815I1J303D01*
G01Y1681219D01*
G02X1244638Y1681456I2002J237D01*
G02X1244652Y1681693I2016J0D01*
G01Y1685943D01*
G02X1244638Y1686180I2002J237D01*
G02X1244652Y1686417I2016J0D01*
G01Y1688821D01*
G02X1244954Y1689124I302J1D01*
G37*
G36*
G01X1260702D02*
X1264402D01*
G02X1264704Y1688821I-1J-303D01*
G01Y1678815D01*
G02X1264402Y1678512I-302J-1D01*
G01X1260702D01*
G02X1260400Y1678815I1J303D01*
G01Y1681219D01*
G02X1260386Y1681456I2002J237D01*
G02X1260400Y1681693I2016J0D01*
G01Y1685943D01*
G02X1260386Y1686180I2002J237D01*
G02X1260400Y1686417I2016J0D01*
G01Y1688821D01*
G02X1260702Y1689124I302J1D01*
G37*
G36*
G01X1276450D02*
X1280150D01*
G02X1280452Y1688821I-1J-303D01*
G01Y1678815D01*
G02X1280150Y1678512I-302J-1D01*
G01X1276450D01*
G02X1276148Y1678815I1J303D01*
G01Y1681219D01*
G02X1276134Y1681456I2002J237D01*
G02X1276148Y1681693I2016J0D01*
G01Y1685943D01*
G02X1276134Y1686180I2002J237D01*
G02X1276148Y1686417I2016J0D01*
G01Y1688821D01*
G02X1276450Y1689124I302J1D01*
G37*
G36*
G01X1292198D02*
X1295898D01*
G02X1296200Y1688821I-1J-303D01*
G01Y1678815D01*
G02X1295898Y1678512I-302J-1D01*
G01X1292198D01*
G02X1291896Y1678815I1J303D01*
G01Y1681219D01*
G02X1291882Y1681456I2002J237D01*
G02X1291896Y1681693I2016J0D01*
G01Y1685943D01*
G02X1291882Y1686180I2002J237D01*
G02X1291896Y1686417I2016J0D01*
G01Y1688821D01*
G02X1292198Y1689124I302J1D01*
G37*
G36*
G01X1311883D02*
X1315583D01*
G02X1315886Y1688821I0J-303D01*
G01Y1678815D01*
G02X1315583Y1678512I-303J0D01*
G01X1311883D01*
G02X1311580Y1678815I0J303D01*
G01Y1681227D01*
G02X1311567Y1681456I2003J229D01*
G02X1311580Y1681685I2016J0D01*
G01Y1685951D01*
G02X1311567Y1686180I2003J229D01*
G02X1311580Y1686409I2016J0D01*
G01Y1688821D01*
G02X1311883Y1689124I303J0D01*
G37*
G36*
G01X1327631D02*
X1331331D01*
G02X1331634Y1688821I0J-303D01*
G01Y1678815D01*
G02X1331331Y1678512I-303J0D01*
G01X1327631D01*
G02X1327328Y1678815I0J303D01*
G01Y1681227D01*
G02X1327315Y1681456I2003J229D01*
G02X1327328Y1681685I2016J0D01*
G01Y1685951D01*
G02X1327315Y1686180I2003J229D01*
G02X1327328Y1686409I2016J0D01*
G01Y1688821D01*
G02X1327631Y1689124I303J0D01*
G37*
G36*
G01X1343379D02*
X1347079D01*
G02X1347382Y1688821I0J-303D01*
G01Y1678815D01*
G02X1347079Y1678512I-303J0D01*
G01X1343379D01*
G02X1343076Y1678815I0J303D01*
G01Y1681227D01*
G02X1343063Y1681456I2003J229D01*
G02X1343076Y1681685I2016J0D01*
G01Y1685951D01*
G02X1343063Y1686180I2003J229D01*
G02X1343076Y1686409I2016J0D01*
G01Y1688821D01*
G02X1343379Y1689124I303J0D01*
G37*
G36*
G01X1359127D02*
X1362827D01*
G02X1363130Y1688821I0J-303D01*
G01Y1678815D01*
G02X1362827Y1678512I-303J0D01*
G01X1359127D01*
G02X1358824Y1678815I0J303D01*
G01Y1681227D01*
G02X1358811Y1681456I2003J229D01*
G02X1358824Y1681685I2016J0D01*
G01Y1685951D01*
G02X1358811Y1686180I2003J229D01*
G02X1358824Y1686409I2016J0D01*
G01Y1688821D01*
G02X1359127Y1689124I303J0D01*
G37*
G36*
G01X1509127D02*
X1512827D01*
G02X1513130Y1688821I0J-303D01*
G01Y1678815D01*
G02X1512827Y1678512I-303J0D01*
G01X1509127D01*
G02X1508824Y1678815I0J303D01*
G01Y1681227D01*
G02X1508811Y1681456I2003J229D01*
G02X1508824Y1681685I2016J0D01*
G01Y1685951D01*
G02X1508811Y1686180I2003J229D01*
G02X1508824Y1686409I2016J0D01*
G01Y1688821D01*
G02X1509127Y1689124I303J0D01*
G37*
G36*
G01X1524875D02*
X1528575D01*
G02X1528878Y1688821I0J-303D01*
G01Y1678815D01*
G02X1528575Y1678512I-303J0D01*
G01X1524875D01*
G02X1524572Y1678815I0J303D01*
G01Y1681227D01*
G02X1524559Y1681456I2003J229D01*
G02X1524572Y1681685I2016J0D01*
G01Y1685951D01*
G02X1524559Y1686180I2003J229D01*
G02X1524572Y1686409I2016J0D01*
G01Y1688821D01*
G02X1524875Y1689124I303J0D01*
G37*
G36*
G01X1540623D02*
X1544323D01*
G02X1544626Y1688821I0J-303D01*
G01Y1678815D01*
G02X1544323Y1678512I-303J0D01*
G01X1540623D01*
G02X1540320Y1678815I0J303D01*
G01Y1681227D01*
G02X1540307Y1681456I2003J229D01*
G02X1540320Y1681685I2016J0D01*
G01Y1685951D01*
G02X1540307Y1686180I2003J229D01*
G02X1540320Y1686409I2016J0D01*
G01Y1688821D01*
G02X1540623Y1689124I303J0D01*
G37*
G36*
G01X1556371D02*
X1560071D01*
G02X1560374Y1688821I0J-303D01*
G01Y1678815D01*
G02X1560071Y1678512I-303J0D01*
G01X1556371D01*
G02X1556068Y1678815I0J303D01*
G01Y1681227D01*
G02X1556055Y1681456I2003J229D01*
G02X1556068Y1681685I2016J0D01*
G01Y1685951D01*
G02X1556055Y1686180I2003J229D01*
G02X1556068Y1686409I2016J0D01*
G01Y1688821D01*
G02X1556371Y1689124I303J0D01*
G37*
G36*
G01X1576056D02*
X1579756D01*
G02X1580058Y1688821I-1J-303D01*
G01Y1678815D01*
G02X1579756Y1678512I-302J-1D01*
G01X1576056D01*
G02X1575754Y1678815I1J303D01*
G01Y1681219D01*
G02X1575740Y1681456I2002J237D01*
G02X1575754Y1681693I2016J0D01*
G01Y1685943D01*
G02X1575740Y1686180I2002J237D01*
G02X1575754Y1686417I2016J0D01*
G01Y1688821D01*
G02X1576056Y1689124I302J1D01*
G37*
G36*
G01X1591804D02*
X1595504D01*
G02X1595806Y1688821I-1J-303D01*
G01Y1678815D01*
G02X1595504Y1678512I-302J-1D01*
G01X1591804D01*
G02X1591502Y1678815I1J303D01*
G01Y1681219D01*
G02X1591488Y1681456I2002J237D01*
G02X1591502Y1681693I2016J0D01*
G01Y1685943D01*
G02X1591488Y1686180I2002J237D01*
G02X1591502Y1686417I2016J0D01*
G01Y1688821D01*
G02X1591804Y1689124I302J1D01*
G37*
G36*
G01X1607552D02*
X1611252D01*
G02X1611554Y1688821I-1J-303D01*
G01Y1678815D01*
G02X1611252Y1678512I-302J-1D01*
G01X1607552D01*
G02X1607250Y1678815I1J303D01*
G01Y1681219D01*
G02X1607236Y1681456I2002J237D01*
G02X1607250Y1681693I2016J0D01*
G01Y1685943D01*
G02X1607236Y1686180I2002J237D01*
G02X1607250Y1686417I2016J0D01*
G01Y1688821D01*
G02X1607552Y1689124I302J1D01*
G37*
G36*
G01X1623300D02*
X1627000D01*
G02X1627302Y1688821I-1J-303D01*
G01Y1678815D01*
G02X1627000Y1678512I-302J-1D01*
G01X1623300D01*
G02X1622998Y1678815I1J303D01*
G01Y1681219D01*
G02X1622984Y1681456I2002J237D01*
G02X1622998Y1681693I2016J0D01*
G01Y1685943D01*
G02X1622984Y1686180I2002J237D01*
G02X1622998Y1686417I2016J0D01*
G01Y1688821D01*
G02X1623300Y1689124I302J1D01*
G37*
G36*
G01X229206Y1699360D02*
X232906D01*
G02X233208Y1699057I-1J-303D01*
G01Y1689051D01*
G02X232906Y1688748I-302J-1D01*
G01X229206D01*
G02X228904Y1689051I1J303D01*
G01Y1691455D01*
G02X228890Y1691692I2002J237D01*
G02X228904Y1691929I2016J0D01*
G01Y1696180D01*
G02X228890Y1696417I2002J237D01*
G02X228904Y1696654I2016J0D01*
G01Y1699057D01*
G02X229206Y1699360I302J1D01*
G37*
G36*
G01X244954D02*
X248654D01*
G02X248956Y1699057I-1J-303D01*
G01Y1689051D01*
G02X248654Y1688748I-302J-1D01*
G01X244954D01*
G02X244652Y1689051I1J303D01*
G01Y1691455D01*
G02X244638Y1691692I2002J237D01*
G02X244652Y1691929I2016J0D01*
G01Y1696180D01*
G02X244638Y1696417I2002J237D01*
G02X244652Y1696654I2016J0D01*
G01Y1699057D01*
G02X244954Y1699360I302J1D01*
G37*
G36*
G01X260702D02*
X264402D01*
G02X264704Y1699057I-1J-303D01*
G01Y1689051D01*
G02X264402Y1688748I-302J-1D01*
G01X260702D01*
G02X260400Y1689051I1J303D01*
G01Y1691455D01*
G02X260386Y1691692I2002J237D01*
G02X260400Y1691929I2016J0D01*
G01Y1696180D01*
G02X260386Y1696417I2002J237D01*
G02X260400Y1696654I2016J0D01*
G01Y1699057D01*
G02X260702Y1699360I302J1D01*
G37*
G36*
G01X276450D02*
X280150D01*
G02X280452Y1699057I-1J-303D01*
G01Y1689051D01*
G02X280150Y1688748I-302J-1D01*
G01X276450D01*
G02X276148Y1689051I1J303D01*
G01Y1691455D01*
G02X276134Y1691692I2002J237D01*
G02X276148Y1691929I2016J0D01*
G01Y1696180D01*
G02X276134Y1696417I2002J237D01*
G02X276148Y1696654I2016J0D01*
G01Y1699057D01*
G02X276450Y1699360I302J1D01*
G37*
G36*
G01X296135D02*
X299835D01*
G02X300138Y1699057I0J-303D01*
G01Y1689051D01*
G02X299835Y1688748I-303J0D01*
G01X296135D01*
G02X295832Y1689051I0J303D01*
G01Y1691463D01*
G02X295819Y1691692I2003J229D01*
G02X295832Y1691921I2016J0D01*
G01Y1696188D01*
G02X295819Y1696417I2003J229D01*
G02X295832Y1696646I2016J0D01*
G01Y1699057D01*
G02X296135Y1699360I303J0D01*
G37*
G36*
G01X311883D02*
X315583D01*
G02X315886Y1699057I0J-303D01*
G01Y1689051D01*
G02X315583Y1688748I-303J0D01*
G01X311883D01*
G02X311580Y1689051I0J303D01*
G01Y1691463D01*
G02X311567Y1691692I2003J229D01*
G02X311580Y1691921I2016J0D01*
G01Y1696188D01*
G02X311567Y1696417I2003J229D01*
G02X311580Y1696646I2016J0D01*
G01Y1699057D01*
G02X311883Y1699360I303J0D01*
G37*
G36*
G01X327631D02*
X331331D01*
G02X331634Y1699057I0J-303D01*
G01Y1689051D01*
G02X331331Y1688748I-303J0D01*
G01X327631D01*
G02X327328Y1689051I0J303D01*
G01Y1691463D01*
G02X327315Y1691692I2003J229D01*
G02X327328Y1691921I2016J0D01*
G01Y1696188D01*
G02X327315Y1696417I2003J229D01*
G02X327328Y1696646I2016J0D01*
G01Y1699057D01*
G02X327631Y1699360I303J0D01*
G37*
G36*
G01X343379D02*
X347079D01*
G02X347382Y1699057I0J-303D01*
G01Y1689051D01*
G02X347079Y1688748I-303J0D01*
G01X343379D01*
G02X343076Y1689051I0J303D01*
G01Y1691463D01*
G02X343063Y1691692I2003J229D01*
G02X343076Y1691921I2016J0D01*
G01Y1696188D01*
G02X343063Y1696417I2003J229D01*
G02X343076Y1696646I2016J0D01*
G01Y1699057D01*
G02X343379Y1699360I303J0D01*
G37*
G36*
G01X493379D02*
X497079D01*
G02X497382Y1699057I0J-303D01*
G01Y1689051D01*
G02X497079Y1688748I-303J0D01*
G01X493379D01*
G02X493076Y1689051I0J303D01*
G01Y1691463D01*
G02X493063Y1691692I2003J229D01*
G02X493076Y1691921I2016J0D01*
G01Y1696188D01*
G02X493063Y1696417I2003J229D01*
G02X493076Y1696646I2016J0D01*
G01Y1699057D01*
G02X493379Y1699360I303J0D01*
G37*
G36*
G01X509127D02*
X512827D01*
G02X513130Y1699057I0J-303D01*
G01Y1689051D01*
G02X512827Y1688748I-303J0D01*
G01X509127D01*
G02X508824Y1689051I0J303D01*
G01Y1691463D01*
G02X508811Y1691692I2003J229D01*
G02X508824Y1691921I2016J0D01*
G01Y1696188D01*
G02X508811Y1696417I2003J229D01*
G02X508824Y1696646I2016J0D01*
G01Y1699057D01*
G02X509127Y1699360I303J0D01*
G37*
G36*
G01X524875D02*
X528575D01*
G02X528878Y1699057I0J-303D01*
G01Y1689051D01*
G02X528575Y1688748I-303J0D01*
G01X524875D01*
G02X524572Y1689051I0J303D01*
G01Y1691463D01*
G02X524559Y1691692I2003J229D01*
G02X524572Y1691921I2016J0D01*
G01Y1696188D01*
G02X524559Y1696417I2003J229D01*
G02X524572Y1696646I2016J0D01*
G01Y1699057D01*
G02X524875Y1699360I303J0D01*
G37*
G36*
G01X540623D02*
X544323D01*
G02X544626Y1699057I0J-303D01*
G01Y1689051D01*
G02X544323Y1688748I-303J0D01*
G01X540623D01*
G02X540320Y1689051I0J303D01*
G01Y1691463D01*
G02X540307Y1691692I2003J229D01*
G02X540320Y1691921I2016J0D01*
G01Y1696188D01*
G02X540307Y1696417I2003J229D01*
G02X540320Y1696646I2016J0D01*
G01Y1699057D01*
G02X540623Y1699360I303J0D01*
G37*
G36*
G01X560308D02*
X564008D01*
G02X564310Y1699057I-1J-303D01*
G01Y1689051D01*
G02X564008Y1688748I-302J-1D01*
G01X560308D01*
G02X560006Y1689051I1J303D01*
G01Y1691455D01*
G02X559992Y1691692I2002J237D01*
G02X560006Y1691929I2016J0D01*
G01Y1696180D01*
G02X559992Y1696417I2002J237D01*
G02X560006Y1696654I2016J0D01*
G01Y1699057D01*
G02X560308Y1699360I302J1D01*
G37*
G36*
G01X576056D02*
X579756D01*
G02X580058Y1699057I-1J-303D01*
G01Y1689051D01*
G02X579756Y1688748I-302J-1D01*
G01X576056D01*
G02X575754Y1689051I1J303D01*
G01Y1691455D01*
G02X575740Y1691692I2002J237D01*
G02X575754Y1691929I2016J0D01*
G01Y1696180D01*
G02X575740Y1696417I2002J237D01*
G02X575754Y1696654I2016J0D01*
G01Y1699057D01*
G02X576056Y1699360I302J1D01*
G37*
G36*
G01X591804D02*
X595504D01*
G02X595806Y1699057I-1J-303D01*
G01Y1689051D01*
G02X595504Y1688748I-302J-1D01*
G01X591804D01*
G02X591502Y1689051I1J303D01*
G01Y1691455D01*
G02X591488Y1691692I2002J237D01*
G02X591502Y1691929I2016J0D01*
G01Y1696180D01*
G02X591488Y1696417I2002J237D01*
G02X591502Y1696654I2016J0D01*
G01Y1699057D01*
G02X591804Y1699360I302J1D01*
G37*
G36*
G01X607552D02*
X611252D01*
G02X611554Y1699057I-1J-303D01*
G01Y1689051D01*
G02X611252Y1688748I-302J-1D01*
G01X607552D01*
G02X607250Y1689051I1J303D01*
G01Y1691455D01*
G02X607236Y1691692I2002J237D01*
G02X607250Y1691929I2016J0D01*
G01Y1696180D01*
G02X607236Y1696417I2002J237D01*
G02X607250Y1696654I2016J0D01*
G01Y1699057D01*
G02X607552Y1699360I302J1D01*
G37*
G36*
G01X1237080D02*
X1240780D01*
G02X1241082Y1699057I-1J-303D01*
G01Y1689051D01*
G02X1240780Y1688748I-302J-1D01*
G01X1237080D01*
G02X1236778Y1689051I1J303D01*
G01Y1691455D01*
G02X1236764Y1691692I2002J237D01*
G02X1236778Y1691929I2016J0D01*
G01Y1696180D01*
G02X1236764Y1696417I2002J237D01*
G02X1236778Y1696654I2016J0D01*
G01Y1699057D01*
G02X1237080Y1699360I302J1D01*
G37*
G36*
G01X1252828D02*
X1256528D01*
G02X1256830Y1699057I-1J-303D01*
G01Y1689051D01*
G02X1256528Y1688748I-302J-1D01*
G01X1252828D01*
G02X1252526Y1689051I1J303D01*
G01Y1691455D01*
G02X1252512Y1691692I2002J237D01*
G02X1252526Y1691929I2016J0D01*
G01Y1696180D01*
G02X1252512Y1696417I2002J237D01*
G02X1252526Y1696654I2016J0D01*
G01Y1699057D01*
G02X1252828Y1699360I302J1D01*
G37*
G36*
G01X1268576D02*
X1272276D01*
G02X1272578Y1699057I-1J-303D01*
G01Y1689051D01*
G02X1272276Y1688748I-302J-1D01*
G01X1268576D01*
G02X1268274Y1689051I1J303D01*
G01Y1691455D01*
G02X1268260Y1691692I2002J237D01*
G02X1268274Y1691929I2016J0D01*
G01Y1696180D01*
G02X1268260Y1696417I2002J237D01*
G02X1268274Y1696654I2016J0D01*
G01Y1699057D01*
G02X1268576Y1699360I302J1D01*
G37*
G36*
G01X1284324D02*
X1288024D01*
G02X1288326Y1699057I-1J-303D01*
G01Y1689051D01*
G02X1288024Y1688748I-302J-1D01*
G01X1284324D01*
G02X1284022Y1689051I1J303D01*
G01Y1691455D01*
G02X1284008Y1691692I2002J237D01*
G02X1284022Y1691929I2016J0D01*
G01Y1696180D01*
G02X1284008Y1696417I2002J237D01*
G02X1284022Y1696654I2016J0D01*
G01Y1699057D01*
G02X1284324Y1699360I302J1D01*
G37*
G36*
G01X1304009D02*
X1307709D01*
G02X1308012Y1699057I0J-303D01*
G01Y1689051D01*
G02X1307709Y1688748I-303J0D01*
G01X1304009D01*
G02X1303706Y1689051I0J303D01*
G01Y1691463D01*
G02X1303693Y1691692I2003J229D01*
G02X1303706Y1691921I2016J0D01*
G01Y1696188D01*
G02X1303693Y1696417I2003J229D01*
G02X1303706Y1696646I2016J0D01*
G01Y1699057D01*
G02X1304009Y1699360I303J0D01*
G37*
G36*
G01X1319757D02*
X1323457D01*
G02X1323760Y1699057I0J-303D01*
G01Y1689051D01*
G02X1323457Y1688748I-303J0D01*
G01X1319757D01*
G02X1319454Y1689051I0J303D01*
G01Y1691463D01*
G02X1319441Y1691692I2003J229D01*
G02X1319454Y1691921I2016J0D01*
G01Y1696188D01*
G02X1319441Y1696417I2003J229D01*
G02X1319454Y1696646I2016J0D01*
G01Y1699057D01*
G02X1319757Y1699360I303J0D01*
G37*
G36*
G01X1335505D02*
X1339205D01*
G02X1339508Y1699057I0J-303D01*
G01Y1689051D01*
G02X1339205Y1688748I-303J0D01*
G01X1335505D01*
G02X1335202Y1689051I0J303D01*
G01Y1691463D01*
G02X1335189Y1691692I2003J229D01*
G02X1335202Y1691921I2016J0D01*
G01Y1696188D01*
G02X1335189Y1696417I2003J229D01*
G02X1335202Y1696646I2016J0D01*
G01Y1699057D01*
G02X1335505Y1699360I303J0D01*
G37*
G36*
G01X1351253D02*
X1354953D01*
G02X1355256Y1699057I0J-303D01*
G01Y1689051D01*
G02X1354953Y1688748I-303J0D01*
G01X1351253D01*
G02X1350950Y1689051I0J303D01*
G01Y1691463D01*
G02X1350937Y1691692I2003J229D01*
G02X1350950Y1691921I2016J0D01*
G01Y1696188D01*
G02X1350937Y1696417I2003J229D01*
G02X1350950Y1696646I2016J0D01*
G01Y1699057D01*
G02X1351253Y1699360I303J0D01*
G37*
G36*
G01X1501253D02*
X1504953D01*
G02X1505256Y1699057I0J-303D01*
G01Y1689051D01*
G02X1504953Y1688748I-303J0D01*
G01X1501253D01*
G02X1500950Y1689051I0J303D01*
G01Y1691463D01*
G02X1500937Y1691692I2003J229D01*
G02X1500950Y1691921I2016J0D01*
G01Y1696188D01*
G02X1500937Y1696417I2003J229D01*
G02X1500950Y1696646I2016J0D01*
G01Y1699057D01*
G02X1501253Y1699360I303J0D01*
G37*
G36*
G01X1517001D02*
X1520701D01*
G02X1521004Y1699057I0J-303D01*
G01Y1689051D01*
G02X1520701Y1688748I-303J0D01*
G01X1517001D01*
G02X1516698Y1689051I0J303D01*
G01Y1691463D01*
G02X1516685Y1691692I2003J229D01*
G02X1516698Y1691921I2016J0D01*
G01Y1696188D01*
G02X1516685Y1696417I2003J229D01*
G02X1516698Y1696646I2016J0D01*
G01Y1699057D01*
G02X1517001Y1699360I303J0D01*
G37*
G36*
G01X1532749D02*
X1536449D01*
G02X1536752Y1699057I0J-303D01*
G01Y1689051D01*
G02X1536449Y1688748I-303J0D01*
G01X1532749D01*
G02X1532446Y1689051I0J303D01*
G01Y1691463D01*
G02X1532433Y1691692I2003J229D01*
G02X1532446Y1691921I2016J0D01*
G01Y1696188D01*
G02X1532433Y1696417I2003J229D01*
G02X1532446Y1696646I2016J0D01*
G01Y1699057D01*
G02X1532749Y1699360I303J0D01*
G37*
G36*
G01X1548497D02*
X1552197D01*
G02X1552500Y1699057I0J-303D01*
G01Y1689051D01*
G02X1552197Y1688748I-303J0D01*
G01X1548497D01*
G02X1548194Y1689051I0J303D01*
G01Y1691463D01*
G02X1548181Y1691692I2003J229D01*
G02X1548194Y1691921I2016J0D01*
G01Y1696188D01*
G02X1548181Y1696417I2003J229D01*
G02X1548194Y1696646I2016J0D01*
G01Y1699057D01*
G02X1548497Y1699360I303J0D01*
G37*
G36*
G01X1568182D02*
X1571882D01*
G02X1572184Y1699057I-1J-303D01*
G01Y1689051D01*
G02X1571882Y1688748I-302J-1D01*
G01X1568182D01*
G02X1567880Y1689051I1J303D01*
G01Y1691455D01*
G02X1567866Y1691692I2002J237D01*
G02X1567880Y1691929I2016J0D01*
G01Y1696180D01*
G02X1567866Y1696417I2002J237D01*
G02X1567880Y1696654I2016J0D01*
G01Y1699057D01*
G02X1568182Y1699360I302J1D01*
G37*
G36*
G01X1583930D02*
X1587630D01*
G02X1587932Y1699057I-1J-303D01*
G01Y1689051D01*
G02X1587630Y1688748I-302J-1D01*
G01X1583930D01*
G02X1583628Y1689051I1J303D01*
G01Y1691455D01*
G02X1583614Y1691692I2002J237D01*
G02X1583628Y1691929I2016J0D01*
G01Y1696180D01*
G02X1583614Y1696417I2002J237D01*
G02X1583628Y1696654I2016J0D01*
G01Y1699057D01*
G02X1583930Y1699360I302J1D01*
G37*
G36*
G01X1599678D02*
X1603378D01*
G02X1603680Y1699057I-1J-303D01*
G01Y1689051D01*
G02X1603378Y1688748I-302J-1D01*
G01X1599678D01*
G02X1599376Y1689051I1J303D01*
G01Y1691455D01*
G02X1599362Y1691692I2002J237D01*
G02X1599376Y1691929I2016J0D01*
G01Y1696180D01*
G02X1599362Y1696417I2002J237D01*
G02X1599376Y1696654I2016J0D01*
G01Y1699057D01*
G02X1599678Y1699360I302J1D01*
G37*
G36*
G01X1615426D02*
X1619126D01*
G02X1619428Y1699057I-1J-303D01*
G01Y1689051D01*
G02X1619126Y1688748I-302J-1D01*
G01X1615426D01*
G02X1615124Y1689051I1J303D01*
G01Y1691455D01*
G02X1615110Y1691692I2002J237D01*
G02X1615124Y1691929I2016J0D01*
G01Y1696180D01*
G02X1615110Y1696417I2002J237D01*
G02X1615124Y1696654I2016J0D01*
G01Y1699057D01*
G02X1615426Y1699360I302J1D01*
G37*
G36*
G01X237080Y1703296D02*
X240780D01*
G02X241082Y1702994I0J-302D01*
G01Y1692988D01*
G02X240780Y1692686I-302J0D01*
G01X237080D01*
G02X236778Y1692988I0J302D01*
G01Y1695392D01*
G02X236764Y1695629I2002J237D01*
G02X236778Y1695866I2016J0D01*
G01Y1700117D01*
G02X236764Y1700354I2002J237D01*
G02X236778Y1700591I2016J0D01*
G01Y1702994D01*
G02X237080Y1703296I302J0D01*
G37*
G36*
G01X252828D02*
X256528D01*
G02X256830Y1702994I0J-302D01*
G01Y1692988D01*
G02X256528Y1692686I-302J0D01*
G01X252828D01*
G02X252526Y1692988I0J302D01*
G01Y1695392D01*
G02X252512Y1695629I2002J237D01*
G02X252526Y1695866I2016J0D01*
G01Y1700117D01*
G02X252512Y1700354I2002J237D01*
G02X252526Y1700591I2016J0D01*
G01Y1702994D01*
G02X252828Y1703296I302J0D01*
G37*
G36*
G01X268576D02*
X272276D01*
G02X272578Y1702994I0J-302D01*
G01Y1692988D01*
G02X272276Y1692686I-302J0D01*
G01X268576D01*
G02X268274Y1692988I0J302D01*
G01Y1695392D01*
G02X268260Y1695629I2002J237D01*
G02X268274Y1695866I2016J0D01*
G01Y1700117D01*
G02X268260Y1700354I2002J237D01*
G02X268274Y1700591I2016J0D01*
G01Y1702994D01*
G02X268576Y1703296I302J0D01*
G37*
G36*
G01X284324D02*
X288024D01*
G02X288326Y1702994I0J-302D01*
G01Y1692988D01*
G02X288024Y1692686I-302J0D01*
G01X284324D01*
G02X284022Y1692988I0J302D01*
G01Y1695392D01*
G02X284008Y1695629I2002J237D01*
G02X284022Y1695866I2016J0D01*
G01Y1700117D01*
G02X284008Y1700354I2002J237D01*
G02X284022Y1700591I2016J0D01*
G01Y1702994D01*
G02X284324Y1703296I302J0D01*
G37*
G36*
G01X568182D02*
X571882D01*
G02X572184Y1702994I0J-302D01*
G01Y1692988D01*
G02X571882Y1692686I-302J0D01*
G01X568182D01*
G02X567880Y1692988I0J302D01*
G01Y1695392D01*
G02X567866Y1695629I2002J237D01*
G02X567880Y1695866I2016J0D01*
G01Y1700117D01*
G02X567866Y1700354I2002J237D01*
G02X567880Y1700591I2016J0D01*
G01Y1702994D01*
G02X568182Y1703296I302J0D01*
G37*
G36*
G01X583930D02*
X587630D01*
G02X587932Y1702994I0J-302D01*
G01Y1692988D01*
G02X587630Y1692686I-302J0D01*
G01X583930D01*
G02X583628Y1692988I0J302D01*
G01Y1695392D01*
G02X583614Y1695629I2002J237D01*
G02X583628Y1695866I2016J0D01*
G01Y1700117D01*
G02X583614Y1700354I2002J237D01*
G02X583628Y1700591I2016J0D01*
G01Y1702994D01*
G02X583930Y1703296I302J0D01*
G37*
G36*
G01X599678D02*
X603378D01*
G02X603680Y1702994I0J-302D01*
G01Y1692988D01*
G02X603378Y1692686I-302J0D01*
G01X599678D01*
G02X599376Y1692988I0J302D01*
G01Y1695392D01*
G02X599362Y1695629I2002J237D01*
G02X599376Y1695866I2016J0D01*
G01Y1700117D01*
G02X599362Y1700354I2002J237D01*
G02X599376Y1700591I2016J0D01*
G01Y1702994D01*
G02X599678Y1703296I302J0D01*
G37*
G36*
G01X615426D02*
X619126D01*
G02X619428Y1702994I0J-302D01*
G01Y1692988D01*
G02X619126Y1692686I-302J0D01*
G01X615426D01*
G02X615124Y1692988I0J302D01*
G01Y1695392D01*
G02X615110Y1695629I2002J237D01*
G02X615124Y1695866I2016J0D01*
G01Y1700117D01*
G02X615110Y1700354I2002J237D01*
G02X615124Y1700591I2016J0D01*
G01Y1702994D01*
G02X615426Y1703296I302J0D01*
G37*
G36*
G01X1244954D02*
X1248654D01*
G02X1248956Y1702994I0J-302D01*
G01Y1692988D01*
G02X1248654Y1692686I-302J0D01*
G01X1244954D01*
G02X1244652Y1692988I0J302D01*
G01Y1695392D01*
G02X1244638Y1695629I2002J237D01*
G02X1244652Y1695866I2016J0D01*
G01Y1700117D01*
G02X1244638Y1700354I2002J237D01*
G02X1244652Y1700591I2016J0D01*
G01Y1702994D01*
G02X1244954Y1703296I302J0D01*
G37*
G36*
G01X1260702D02*
X1264402D01*
G02X1264704Y1702994I0J-302D01*
G01Y1692988D01*
G02X1264402Y1692686I-302J0D01*
G01X1260702D01*
G02X1260400Y1692988I0J302D01*
G01Y1695392D01*
G02X1260386Y1695629I2002J237D01*
G02X1260400Y1695866I2016J0D01*
G01Y1700117D01*
G02X1260386Y1700354I2002J237D01*
G02X1260400Y1700591I2016J0D01*
G01Y1702994D01*
G02X1260702Y1703296I302J0D01*
G37*
G36*
G01X1276450D02*
X1280150D01*
G02X1280452Y1702994I0J-302D01*
G01Y1692988D01*
G02X1280150Y1692686I-302J0D01*
G01X1276450D01*
G02X1276148Y1692988I0J302D01*
G01Y1695392D01*
G02X1276134Y1695629I2002J237D01*
G02X1276148Y1695866I2016J0D01*
G01Y1700117D01*
G02X1276134Y1700354I2002J237D01*
G02X1276148Y1700591I2016J0D01*
G01Y1702994D01*
G02X1276450Y1703296I302J0D01*
G37*
G36*
G01X1292198D02*
X1295898D01*
G02X1296200Y1702994I0J-302D01*
G01Y1692988D01*
G02X1295898Y1692686I-302J0D01*
G01X1292198D01*
G02X1291896Y1692988I0J302D01*
G01Y1695392D01*
G02X1291882Y1695629I2002J237D01*
G02X1291896Y1695866I2016J0D01*
G01Y1700117D01*
G02X1291882Y1700354I2002J237D01*
G02X1291896Y1700591I2016J0D01*
G01Y1702994D01*
G02X1292198Y1703296I302J0D01*
G37*
G36*
G01X1576056D02*
X1579756D01*
G02X1580058Y1702994I0J-302D01*
G01Y1692988D01*
G02X1579756Y1692686I-302J0D01*
G01X1576056D01*
G02X1575754Y1692988I0J302D01*
G01Y1695392D01*
G02X1575740Y1695629I2002J237D01*
G02X1575754Y1695866I2016J0D01*
G01Y1700117D01*
G02X1575740Y1700354I2002J237D01*
G02X1575754Y1700591I2016J0D01*
G01Y1702994D01*
G02X1576056Y1703296I302J0D01*
G37*
G36*
G01X1591804D02*
X1595504D01*
G02X1595806Y1702994I0J-302D01*
G01Y1692988D01*
G02X1595504Y1692686I-302J0D01*
G01X1591804D01*
G02X1591502Y1692988I0J302D01*
G01Y1695392D01*
G02X1591488Y1695629I2002J237D01*
G02X1591502Y1695866I2016J0D01*
G01Y1700117D01*
G02X1591488Y1700354I2002J237D01*
G02X1591502Y1700591I2016J0D01*
G01Y1702994D01*
G02X1591804Y1703296I302J0D01*
G37*
G36*
G01X1607552D02*
X1611252D01*
G02X1611554Y1702994I0J-302D01*
G01Y1692988D01*
G02X1611252Y1692686I-302J0D01*
G01X1607552D01*
G02X1607250Y1692988I0J302D01*
G01Y1695392D01*
G02X1607236Y1695629I2002J237D01*
G02X1607250Y1695866I2016J0D01*
G01Y1700117D01*
G02X1607236Y1700354I2002J237D01*
G02X1607250Y1700591I2016J0D01*
G01Y1702994D01*
G02X1607552Y1703296I302J0D01*
G37*
G36*
G01X1623300D02*
X1627000D01*
G02X1627302Y1702994I0J-302D01*
G01Y1692988D01*
G02X1627000Y1692686I-302J0D01*
G01X1623300D01*
G02X1622998Y1692988I0J302D01*
G01Y1695392D01*
G02X1622984Y1695629I2002J237D01*
G02X1622998Y1695866I2016J0D01*
G01Y1700117D01*
G02X1622984Y1700354I2002J237D01*
G02X1622998Y1700591I2016J0D01*
G01Y1702994D01*
G02X1623300Y1703296I302J0D01*
G37*
G36*
G01X304009D02*
X307709D01*
G02X308012Y1702994I1J-302D01*
G01Y1692988D01*
G02X307709Y1692686I-303J1D01*
G01X304009D01*
G02X303706Y1692988I-1J302D01*
G01Y1695400D01*
G02X303693Y1695629I2003J229D01*
G02X303706Y1695858I2016J0D01*
G01Y1700125D01*
G02X303693Y1700354I2003J229D01*
G02X303706Y1700583I2016J0D01*
G01Y1702994D01*
G02X304009Y1703296I303J-1D01*
G37*
G36*
G01X319757D02*
X323457D01*
G02X323760Y1702994I1J-302D01*
G01Y1692988D01*
G02X323457Y1692686I-303J1D01*
G01X319757D01*
G02X319454Y1692988I-1J302D01*
G01Y1695400D01*
G02X319441Y1695629I2003J229D01*
G02X319454Y1695858I2016J0D01*
G01Y1700125D01*
G02X319441Y1700354I2003J229D01*
G02X319454Y1700583I2016J0D01*
G01Y1702994D01*
G02X319757Y1703296I303J-1D01*
G37*
G36*
G01X335505D02*
X339205D01*
G02X339508Y1702994I1J-302D01*
G01Y1692988D01*
G02X339205Y1692686I-303J1D01*
G01X335505D01*
G02X335202Y1692988I-1J302D01*
G01Y1695400D01*
G02X335189Y1695629I2003J229D01*
G02X335202Y1695858I2016J0D01*
G01Y1700125D01*
G02X335189Y1700354I2003J229D01*
G02X335202Y1700583I2016J0D01*
G01Y1702994D01*
G02X335505Y1703296I303J-1D01*
G37*
G36*
G01X351253D02*
X354953D01*
G02X355256Y1702994I1J-302D01*
G01Y1692988D01*
G02X354953Y1692686I-303J1D01*
G01X351253D01*
G02X350950Y1692988I-1J302D01*
G01Y1695400D01*
G02X350937Y1695629I2003J229D01*
G02X350950Y1695858I2016J0D01*
G01Y1700125D01*
G02X350937Y1700354I2003J229D01*
G02X350950Y1700583I2016J0D01*
G01Y1702994D01*
G02X351253Y1703296I303J-1D01*
G37*
G36*
G01X501253D02*
X504953D01*
G02X505256Y1702994I1J-302D01*
G01Y1692988D01*
G02X504953Y1692686I-303J1D01*
G01X501253D01*
G02X500950Y1692988I-1J302D01*
G01Y1695400D01*
G02X500937Y1695629I2003J229D01*
G02X500950Y1695858I2016J0D01*
G01Y1700125D01*
G02X500937Y1700354I2003J229D01*
G02X500950Y1700583I2016J0D01*
G01Y1702994D01*
G02X501253Y1703296I303J-1D01*
G37*
G36*
G01X517001D02*
X520701D01*
G02X521004Y1702994I1J-302D01*
G01Y1692988D01*
G02X520701Y1692686I-303J1D01*
G01X517001D01*
G02X516698Y1692988I-1J302D01*
G01Y1695400D01*
G02X516685Y1695629I2003J229D01*
G02X516698Y1695858I2016J0D01*
G01Y1700125D01*
G02X516685Y1700354I2003J229D01*
G02X516698Y1700583I2016J0D01*
G01Y1702994D01*
G02X517001Y1703296I303J-1D01*
G37*
G36*
G01X532749D02*
X536449D01*
G02X536752Y1702994I1J-302D01*
G01Y1692988D01*
G02X536449Y1692686I-303J1D01*
G01X532749D01*
G02X532446Y1692988I-1J302D01*
G01Y1695400D01*
G02X532433Y1695629I2003J229D01*
G02X532446Y1695858I2016J0D01*
G01Y1700125D01*
G02X532433Y1700354I2003J229D01*
G02X532446Y1700583I2016J0D01*
G01Y1702994D01*
G02X532749Y1703296I303J-1D01*
G37*
G36*
G01X548497D02*
X552197D01*
G02X552500Y1702994I1J-302D01*
G01Y1692988D01*
G02X552197Y1692686I-303J1D01*
G01X548497D01*
G02X548194Y1692988I-1J302D01*
G01Y1695400D01*
G02X548181Y1695629I2003J229D01*
G02X548194Y1695858I2016J0D01*
G01Y1700125D01*
G02X548181Y1700354I2003J229D01*
G02X548194Y1700583I2016J0D01*
G01Y1702994D01*
G02X548497Y1703296I303J-1D01*
G37*
G36*
G01X1311883D02*
X1315583D01*
G02X1315886Y1702994I1J-302D01*
G01Y1692988D01*
G02X1315583Y1692686I-303J1D01*
G01X1311883D01*
G02X1311580Y1692988I-1J302D01*
G01Y1695400D01*
G02X1311567Y1695629I2003J229D01*
G02X1311580Y1695858I2016J0D01*
G01Y1700125D01*
G02X1311567Y1700354I2003J229D01*
G02X1311580Y1700583I2016J0D01*
G01Y1702994D01*
G02X1311883Y1703296I303J-1D01*
G37*
G36*
G01X1327631D02*
X1331331D01*
G02X1331634Y1702994I1J-302D01*
G01Y1692988D01*
G02X1331331Y1692686I-303J1D01*
G01X1327631D01*
G02X1327328Y1692988I-1J302D01*
G01Y1695400D01*
G02X1327315Y1695629I2003J229D01*
G02X1327328Y1695858I2016J0D01*
G01Y1700125D01*
G02X1327315Y1700354I2003J229D01*
G02X1327328Y1700583I2016J0D01*
G01Y1702994D01*
G02X1327631Y1703296I303J-1D01*
G37*
G36*
G01X1343379D02*
X1347079D01*
G02X1347382Y1702994I1J-302D01*
G01Y1692988D01*
G02X1347079Y1692686I-303J1D01*
G01X1343379D01*
G02X1343076Y1692988I-1J302D01*
G01Y1695400D01*
G02X1343063Y1695629I2003J229D01*
G02X1343076Y1695858I2016J0D01*
G01Y1700125D01*
G02X1343063Y1700354I2003J229D01*
G02X1343076Y1700583I2016J0D01*
G01Y1702994D01*
G02X1343379Y1703296I303J-1D01*
G37*
G36*
G01X1359127D02*
X1362827D01*
G02X1363130Y1702994I1J-302D01*
G01Y1692988D01*
G02X1362827Y1692686I-303J1D01*
G01X1359127D01*
G02X1358824Y1692988I-1J302D01*
G01Y1695400D01*
G02X1358811Y1695629I2003J229D01*
G02X1358824Y1695858I2016J0D01*
G01Y1700125D01*
G02X1358811Y1700354I2003J229D01*
G02X1358824Y1700583I2016J0D01*
G01Y1702994D01*
G02X1359127Y1703296I303J-1D01*
G37*
G36*
G01X1509127D02*
X1512827D01*
G02X1513130Y1702994I1J-302D01*
G01Y1692988D01*
G02X1512827Y1692686I-303J1D01*
G01X1509127D01*
G02X1508824Y1692988I-1J302D01*
G01Y1695400D01*
G02X1508811Y1695629I2003J229D01*
G02X1508824Y1695858I2016J0D01*
G01Y1700125D01*
G02X1508811Y1700354I2003J229D01*
G02X1508824Y1700583I2016J0D01*
G01Y1702994D01*
G02X1509127Y1703296I303J-1D01*
G37*
G36*
G01X1524875D02*
X1528575D01*
G02X1528878Y1702994I1J-302D01*
G01Y1692988D01*
G02X1528575Y1692686I-303J1D01*
G01X1524875D01*
G02X1524572Y1692988I-1J302D01*
G01Y1695400D01*
G02X1524559Y1695629I2003J229D01*
G02X1524572Y1695858I2016J0D01*
G01Y1700125D01*
G02X1524559Y1700354I2003J229D01*
G02X1524572Y1700583I2016J0D01*
G01Y1702994D01*
G02X1524875Y1703296I303J-1D01*
G37*
G36*
G01X1540623D02*
X1544323D01*
G02X1544626Y1702994I1J-302D01*
G01Y1692988D01*
G02X1544323Y1692686I-303J1D01*
G01X1540623D01*
G02X1540320Y1692988I-1J302D01*
G01Y1695400D01*
G02X1540307Y1695629I2003J229D01*
G02X1540320Y1695858I2016J0D01*
G01Y1700125D01*
G02X1540307Y1700354I2003J229D01*
G02X1540320Y1700583I2016J0D01*
G01Y1702994D01*
G02X1540623Y1703296I303J-1D01*
G37*
G36*
G01X1556371D02*
X1560071D01*
G02X1560374Y1702994I1J-302D01*
G01Y1692988D01*
G02X1560071Y1692686I-303J1D01*
G01X1556371D01*
G02X1556068Y1692988I-1J302D01*
G01Y1695400D01*
G02X1556055Y1695629I2003J229D01*
G02X1556068Y1695858I2016J0D01*
G01Y1700125D01*
G02X1556055Y1700354I2003J229D01*
G02X1556068Y1700583I2016J0D01*
G01Y1702994D01*
G02X1556371Y1703296I303J-1D01*
G37*
G36*
G01X229206Y1713532D02*
X232906D01*
G02X233208Y1713230I0J-302D01*
G01Y1703224D01*
G02X232906Y1702922I-302J0D01*
G01X229206D01*
G02X228904Y1703224I0J302D01*
G01Y1705629D01*
G02X228890Y1705866I2002J237D01*
G02X228904Y1706103I2016J0D01*
G01Y1710353D01*
G02X228890Y1710590I2002J237D01*
G02X228904Y1710827I2016J0D01*
G01Y1713230D01*
G02X229206Y1713532I302J0D01*
G37*
G36*
G01X244954D02*
X248654D01*
G02X248956Y1713230I0J-302D01*
G01Y1703224D01*
G02X248654Y1702922I-302J0D01*
G01X244954D01*
G02X244652Y1703224I0J302D01*
G01Y1705629D01*
G02X244638Y1705866I2002J237D01*
G02X244652Y1706103I2016J0D01*
G01Y1710353D01*
G02X244638Y1710590I2002J237D01*
G02X244652Y1710827I2016J0D01*
G01Y1713230D01*
G02X244954Y1713532I302J0D01*
G37*
G36*
G01X260702D02*
X264402D01*
G02X264704Y1713230I0J-302D01*
G01Y1703224D01*
G02X264402Y1702922I-302J0D01*
G01X260702D01*
G02X260400Y1703224I0J302D01*
G01Y1705629D01*
G02X260386Y1705866I2002J237D01*
G02X260400Y1706103I2016J0D01*
G01Y1710353D01*
G02X260386Y1710590I2002J237D01*
G02X260400Y1710827I2016J0D01*
G01Y1713230D01*
G02X260702Y1713532I302J0D01*
G37*
G36*
G01X276450D02*
X280150D01*
G02X280452Y1713230I0J-302D01*
G01Y1703224D01*
G02X280150Y1702922I-302J0D01*
G01X276450D01*
G02X276148Y1703224I0J302D01*
G01Y1705629D01*
G02X276134Y1705866I2002J237D01*
G02X276148Y1706103I2016J0D01*
G01Y1710353D01*
G02X276134Y1710590I2002J237D01*
G02X276148Y1710827I2016J0D01*
G01Y1713230D01*
G02X276450Y1713532I302J0D01*
G37*
G36*
G01X560308D02*
X564008D01*
G02X564310Y1713230I0J-302D01*
G01Y1703224D01*
G02X564008Y1702922I-302J0D01*
G01X560308D01*
G02X560006Y1703224I0J302D01*
G01Y1705629D01*
G02X559992Y1705866I2002J237D01*
G02X560006Y1706103I2016J0D01*
G01Y1710353D01*
G02X559992Y1710590I2002J237D01*
G02X560006Y1710827I2016J0D01*
G01Y1713230D01*
G02X560308Y1713532I302J0D01*
G37*
G36*
G01X576056D02*
X579756D01*
G02X580058Y1713230I0J-302D01*
G01Y1703224D01*
G02X579756Y1702922I-302J0D01*
G01X576056D01*
G02X575754Y1703224I0J302D01*
G01Y1705629D01*
G02X575740Y1705866I2002J237D01*
G02X575754Y1706103I2016J0D01*
G01Y1710353D01*
G02X575740Y1710590I2002J237D01*
G02X575754Y1710827I2016J0D01*
G01Y1713230D01*
G02X576056Y1713532I302J0D01*
G37*
G36*
G01X591804D02*
X595504D01*
G02X595806Y1713230I0J-302D01*
G01Y1703224D01*
G02X595504Y1702922I-302J0D01*
G01X591804D01*
G02X591502Y1703224I0J302D01*
G01Y1705629D01*
G02X591488Y1705866I2002J237D01*
G02X591502Y1706103I2016J0D01*
G01Y1710353D01*
G02X591488Y1710590I2002J237D01*
G02X591502Y1710827I2016J0D01*
G01Y1713230D01*
G02X591804Y1713532I302J0D01*
G37*
G36*
G01X607552D02*
X611252D01*
G02X611554Y1713230I0J-302D01*
G01Y1703224D01*
G02X611252Y1702922I-302J0D01*
G01X607552D01*
G02X607250Y1703224I0J302D01*
G01Y1705629D01*
G02X607236Y1705866I2002J237D01*
G02X607250Y1706103I2016J0D01*
G01Y1710353D01*
G02X607236Y1710590I2002J237D01*
G02X607250Y1710827I2016J0D01*
G01Y1713230D01*
G02X607552Y1713532I302J0D01*
G37*
G36*
G01X1237080D02*
X1240780D01*
G02X1241082Y1713230I0J-302D01*
G01Y1703224D01*
G02X1240780Y1702922I-302J0D01*
G01X1237080D01*
G02X1236778Y1703224I0J302D01*
G01Y1705629D01*
G02X1236764Y1705866I2002J237D01*
G02X1236778Y1706103I2016J0D01*
G01Y1710353D01*
G02X1236764Y1710590I2002J237D01*
G02X1236778Y1710827I2016J0D01*
G01Y1713230D01*
G02X1237080Y1713532I302J0D01*
G37*
G36*
G01X1252828D02*
X1256528D01*
G02X1256830Y1713230I0J-302D01*
G01Y1703224D01*
G02X1256528Y1702922I-302J0D01*
G01X1252828D01*
G02X1252526Y1703224I0J302D01*
G01Y1705629D01*
G02X1252512Y1705866I2002J237D01*
G02X1252526Y1706103I2016J0D01*
G01Y1710353D01*
G02X1252512Y1710590I2002J237D01*
G02X1252526Y1710827I2016J0D01*
G01Y1713230D01*
G02X1252828Y1713532I302J0D01*
G37*
G36*
G01X1268576D02*
X1272276D01*
G02X1272578Y1713230I0J-302D01*
G01Y1703224D01*
G02X1272276Y1702922I-302J0D01*
G01X1268576D01*
G02X1268274Y1703224I0J302D01*
G01Y1705629D01*
G02X1268260Y1705866I2002J237D01*
G02X1268274Y1706103I2016J0D01*
G01Y1710353D01*
G02X1268260Y1710590I2002J237D01*
G02X1268274Y1710827I2016J0D01*
G01Y1713230D01*
G02X1268576Y1713532I302J0D01*
G37*
G36*
G01X1284324D02*
X1288024D01*
G02X1288326Y1713230I0J-302D01*
G01Y1703224D01*
G02X1288024Y1702922I-302J0D01*
G01X1284324D01*
G02X1284022Y1703224I0J302D01*
G01Y1705629D01*
G02X1284008Y1705866I2002J237D01*
G02X1284022Y1706103I2016J0D01*
G01Y1710353D01*
G02X1284008Y1710590I2002J237D01*
G02X1284022Y1710827I2016J0D01*
G01Y1713230D01*
G02X1284324Y1713532I302J0D01*
G37*
G36*
G01X1568182D02*
X1571882D01*
G02X1572184Y1713230I0J-302D01*
G01Y1703224D01*
G02X1571882Y1702922I-302J0D01*
G01X1568182D01*
G02X1567880Y1703224I0J302D01*
G01Y1705629D01*
G02X1567866Y1705866I2002J237D01*
G02X1567880Y1706103I2016J0D01*
G01Y1710353D01*
G02X1567866Y1710590I2002J237D01*
G02X1567880Y1710827I2016J0D01*
G01Y1713230D01*
G02X1568182Y1713532I302J0D01*
G37*
G36*
G01X1583930D02*
X1587630D01*
G02X1587932Y1713230I0J-302D01*
G01Y1703224D01*
G02X1587630Y1702922I-302J0D01*
G01X1583930D01*
G02X1583628Y1703224I0J302D01*
G01Y1705629D01*
G02X1583614Y1705866I2002J237D01*
G02X1583628Y1706103I2016J0D01*
G01Y1710353D01*
G02X1583614Y1710590I2002J237D01*
G02X1583628Y1710827I2016J0D01*
G01Y1713230D01*
G02X1583930Y1713532I302J0D01*
G37*
G36*
G01X1599678D02*
X1603378D01*
G02X1603680Y1713230I0J-302D01*
G01Y1703224D01*
G02X1603378Y1702922I-302J0D01*
G01X1599678D01*
G02X1599376Y1703224I0J302D01*
G01Y1705629D01*
G02X1599362Y1705866I2002J237D01*
G02X1599376Y1706103I2016J0D01*
G01Y1710353D01*
G02X1599362Y1710590I2002J237D01*
G02X1599376Y1710827I2016J0D01*
G01Y1713230D01*
G02X1599678Y1713532I302J0D01*
G37*
G36*
G01X1615426D02*
X1619126D01*
G02X1619428Y1713230I0J-302D01*
G01Y1703224D01*
G02X1619126Y1702922I-302J0D01*
G01X1615426D01*
G02X1615124Y1703224I0J302D01*
G01Y1705629D01*
G02X1615110Y1705866I2002J237D01*
G02X1615124Y1706103I2016J0D01*
G01Y1710353D01*
G02X1615110Y1710590I2002J237D01*
G02X1615124Y1710827I2016J0D01*
G01Y1713230D01*
G02X1615426Y1713532I302J0D01*
G37*
G36*
G01X296135D02*
X299835D01*
G02X300138Y1713230I1J-302D01*
G01Y1703224D01*
G02X299835Y1702922I-303J1D01*
G01X296135D01*
G02X295832Y1703224I-1J302D01*
G01Y1705637D01*
G02X295819Y1705866I2003J229D01*
G02X295832Y1706095I2016J0D01*
G01Y1710361D01*
G02X295819Y1710590I2003J229D01*
G02X295832Y1710819I2016J0D01*
G01Y1713230D01*
G02X296135Y1713532I303J-1D01*
G37*
G36*
G01X311883D02*
X315583D01*
G02X315886Y1713230I1J-302D01*
G01Y1703224D01*
G02X315583Y1702922I-303J1D01*
G01X311883D01*
G02X311580Y1703224I-1J302D01*
G01Y1705637D01*
G02X311567Y1705866I2003J229D01*
G02X311580Y1706095I2016J0D01*
G01Y1710361D01*
G02X311567Y1710590I2003J229D01*
G02X311580Y1710819I2016J0D01*
G01Y1713230D01*
G02X311883Y1713532I303J-1D01*
G37*
G36*
G01X327631D02*
X331331D01*
G02X331634Y1713230I1J-302D01*
G01Y1703224D01*
G02X331331Y1702922I-303J1D01*
G01X327631D01*
G02X327328Y1703224I-1J302D01*
G01Y1705637D01*
G02X327315Y1705866I2003J229D01*
G02X327328Y1706095I2016J0D01*
G01Y1710361D01*
G02X327315Y1710590I2003J229D01*
G02X327328Y1710819I2016J0D01*
G01Y1713230D01*
G02X327631Y1713532I303J-1D01*
G37*
G36*
G01X343379D02*
X347079D01*
G02X347382Y1713230I1J-302D01*
G01Y1703224D01*
G02X347079Y1702922I-303J1D01*
G01X343379D01*
G02X343076Y1703224I-1J302D01*
G01Y1705637D01*
G02X343063Y1705866I2003J229D01*
G02X343076Y1706095I2016J0D01*
G01Y1710361D01*
G02X343063Y1710590I2003J229D01*
G02X343076Y1710819I2016J0D01*
G01Y1713230D01*
G02X343379Y1713532I303J-1D01*
G37*
G36*
G01X493379D02*
X497079D01*
G02X497382Y1713230I1J-302D01*
G01Y1703224D01*
G02X497079Y1702922I-303J1D01*
G01X493379D01*
G02X493076Y1703224I-1J302D01*
G01Y1705637D01*
G02X493063Y1705866I2003J229D01*
G02X493076Y1706095I2016J0D01*
G01Y1710361D01*
G02X493063Y1710590I2003J229D01*
G02X493076Y1710819I2016J0D01*
G01Y1713230D01*
G02X493379Y1713532I303J-1D01*
G37*
G36*
G01X509127D02*
X512827D01*
G02X513130Y1713230I1J-302D01*
G01Y1703224D01*
G02X512827Y1702922I-303J1D01*
G01X509127D01*
G02X508824Y1703224I-1J302D01*
G01Y1705637D01*
G02X508811Y1705866I2003J229D01*
G02X508824Y1706095I2016J0D01*
G01Y1710361D01*
G02X508811Y1710590I2003J229D01*
G02X508824Y1710819I2016J0D01*
G01Y1713230D01*
G02X509127Y1713532I303J-1D01*
G37*
G36*
G01X524875D02*
X528575D01*
G02X528878Y1713230I1J-302D01*
G01Y1703224D01*
G02X528575Y1702922I-303J1D01*
G01X524875D01*
G02X524572Y1703224I-1J302D01*
G01Y1705637D01*
G02X524559Y1705866I2003J229D01*
G02X524572Y1706095I2016J0D01*
G01Y1710361D01*
G02X524559Y1710590I2003J229D01*
G02X524572Y1710819I2016J0D01*
G01Y1713230D01*
G02X524875Y1713532I303J-1D01*
G37*
G36*
G01X540623D02*
X544323D01*
G02X544626Y1713230I1J-302D01*
G01Y1703224D01*
G02X544323Y1702922I-303J1D01*
G01X540623D01*
G02X540320Y1703224I-1J302D01*
G01Y1705637D01*
G02X540307Y1705866I2003J229D01*
G02X540320Y1706095I2016J0D01*
G01Y1710361D01*
G02X540307Y1710590I2003J229D01*
G02X540320Y1710819I2016J0D01*
G01Y1713230D01*
G02X540623Y1713532I303J-1D01*
G37*
G36*
G01X1304009D02*
X1307709D01*
G02X1308012Y1713230I1J-302D01*
G01Y1703224D01*
G02X1307709Y1702922I-303J1D01*
G01X1304009D01*
G02X1303706Y1703224I-1J302D01*
G01Y1705637D01*
G02X1303693Y1705866I2003J229D01*
G02X1303706Y1706095I2016J0D01*
G01Y1710361D01*
G02X1303693Y1710590I2003J229D01*
G02X1303706Y1710819I2016J0D01*
G01Y1713230D01*
G02X1304009Y1713532I303J-1D01*
G37*
G36*
G01X1319757D02*
X1323457D01*
G02X1323760Y1713230I1J-302D01*
G01Y1703224D01*
G02X1323457Y1702922I-303J1D01*
G01X1319757D01*
G02X1319454Y1703224I-1J302D01*
G01Y1705637D01*
G02X1319441Y1705866I2003J229D01*
G02X1319454Y1706095I2016J0D01*
G01Y1710361D01*
G02X1319441Y1710590I2003J229D01*
G02X1319454Y1710819I2016J0D01*
G01Y1713230D01*
G02X1319757Y1713532I303J-1D01*
G37*
G36*
G01X1335505D02*
X1339205D01*
G02X1339508Y1713230I1J-302D01*
G01Y1703224D01*
G02X1339205Y1702922I-303J1D01*
G01X1335505D01*
G02X1335202Y1703224I-1J302D01*
G01Y1705637D01*
G02X1335189Y1705866I2003J229D01*
G02X1335202Y1706095I2016J0D01*
G01Y1710361D01*
G02X1335189Y1710590I2003J229D01*
G02X1335202Y1710819I2016J0D01*
G01Y1713230D01*
G02X1335505Y1713532I303J-1D01*
G37*
G36*
G01X1351253D02*
X1354953D01*
G02X1355256Y1713230I1J-302D01*
G01Y1703224D01*
G02X1354953Y1702922I-303J1D01*
G01X1351253D01*
G02X1350950Y1703224I-1J302D01*
G01Y1705637D01*
G02X1350937Y1705866I2003J229D01*
G02X1350950Y1706095I2016J0D01*
G01Y1710361D01*
G02X1350937Y1710590I2003J229D01*
G02X1350950Y1710819I2016J0D01*
G01Y1713230D01*
G02X1351253Y1713532I303J-1D01*
G37*
G36*
G01X1501253D02*
X1504953D01*
G02X1505256Y1713230I1J-302D01*
G01Y1703224D01*
G02X1504953Y1702922I-303J1D01*
G01X1501253D01*
G02X1500950Y1703224I-1J302D01*
G01Y1705637D01*
G02X1500937Y1705866I2003J229D01*
G02X1500950Y1706095I2016J0D01*
G01Y1710361D01*
G02X1500937Y1710590I2003J229D01*
G02X1500950Y1710819I2016J0D01*
G01Y1713230D01*
G02X1501253Y1713532I303J-1D01*
G37*
G36*
G01X1517001D02*
X1520701D01*
G02X1521004Y1713230I1J-302D01*
G01Y1703224D01*
G02X1520701Y1702922I-303J1D01*
G01X1517001D01*
G02X1516698Y1703224I-1J302D01*
G01Y1705637D01*
G02X1516685Y1705866I2003J229D01*
G02X1516698Y1706095I2016J0D01*
G01Y1710361D01*
G02X1516685Y1710590I2003J229D01*
G02X1516698Y1710819I2016J0D01*
G01Y1713230D01*
G02X1517001Y1713532I303J-1D01*
G37*
G36*
G01X1532749D02*
X1536449D01*
G02X1536752Y1713230I1J-302D01*
G01Y1703224D01*
G02X1536449Y1702922I-303J1D01*
G01X1532749D01*
G02X1532446Y1703224I-1J302D01*
G01Y1705637D01*
G02X1532433Y1705866I2003J229D01*
G02X1532446Y1706095I2016J0D01*
G01Y1710361D01*
G02X1532433Y1710590I2003J229D01*
G02X1532446Y1710819I2016J0D01*
G01Y1713230D01*
G02X1532749Y1713532I303J-1D01*
G37*
G36*
G01X1548497D02*
X1552197D01*
G02X1552500Y1713230I1J-302D01*
G01Y1703224D01*
G02X1552197Y1702922I-303J1D01*
G01X1548497D01*
G02X1548194Y1703224I-1J302D01*
G01Y1705637D01*
G02X1548181Y1705866I2003J229D01*
G02X1548194Y1706095I2016J0D01*
G01Y1710361D01*
G02X1548181Y1710590I2003J229D01*
G02X1548194Y1710819I2016J0D01*
G01Y1713230D01*
G02X1548497Y1713532I303J-1D01*
G37*
G36*
G01X237080Y1717470D02*
X240780D01*
G02X241082Y1717167I-1J-303D01*
G01Y1707161D01*
G02X240780Y1706858I-302J-1D01*
G01X237080D01*
G02X236778Y1707161I1J303D01*
G01Y1709566D01*
G02X236764Y1709803I2002J237D01*
G02X236778Y1710040I2016J0D01*
G01Y1714290D01*
G02X236764Y1714527I2002J237D01*
G02X236778Y1714764I2016J0D01*
G01Y1717167D01*
G02X237080Y1717470I302J1D01*
G37*
G36*
G01X252828D02*
X256528D01*
G02X256830Y1717167I-1J-303D01*
G01Y1707161D01*
G02X256528Y1706858I-302J-1D01*
G01X252828D01*
G02X252526Y1707161I1J303D01*
G01Y1709566D01*
G02X252512Y1709803I2002J237D01*
G02X252526Y1710040I2016J0D01*
G01Y1714290D01*
G02X252512Y1714527I2002J237D01*
G02X252526Y1714764I2016J0D01*
G01Y1717167D01*
G02X252828Y1717470I302J1D01*
G37*
G36*
G01X268576D02*
X272276D01*
G02X272578Y1717167I-1J-303D01*
G01Y1707161D01*
G02X272276Y1706858I-302J-1D01*
G01X268576D01*
G02X268274Y1707161I1J303D01*
G01Y1709566D01*
G02X268260Y1709803I2002J237D01*
G02X268274Y1710040I2016J0D01*
G01Y1714290D01*
G02X268260Y1714527I2002J237D01*
G02X268274Y1714764I2016J0D01*
G01Y1717167D01*
G02X268576Y1717470I302J1D01*
G37*
G36*
G01X284324D02*
X288024D01*
G02X288326Y1717167I-1J-303D01*
G01Y1707161D01*
G02X288024Y1706858I-302J-1D01*
G01X284324D01*
G02X284022Y1707161I1J303D01*
G01Y1709566D01*
G02X284008Y1709803I2002J237D01*
G02X284022Y1710040I2016J0D01*
G01Y1714290D01*
G02X284008Y1714527I2002J237D01*
G02X284022Y1714764I2016J0D01*
G01Y1717167D01*
G02X284324Y1717470I302J1D01*
G37*
G36*
G01X304009D02*
X307709D01*
G02X308012Y1717167I0J-303D01*
G01Y1707161D01*
G02X307709Y1706858I-303J0D01*
G01X304009D01*
G02X303706Y1707161I0J303D01*
G01Y1709574D01*
G02X303693Y1709803I2003J229D01*
G02X303706Y1710032I2016J0D01*
G01Y1714298D01*
G02X303693Y1714527I2003J229D01*
G02X303706Y1714756I2016J0D01*
G01Y1717167D01*
G02X304009Y1717470I303J0D01*
G37*
G36*
G01X319757D02*
X323457D01*
G02X323760Y1717167I0J-303D01*
G01Y1707161D01*
G02X323457Y1706858I-303J0D01*
G01X319757D01*
G02X319454Y1707161I0J303D01*
G01Y1709574D01*
G02X319441Y1709803I2003J229D01*
G02X319454Y1710032I2016J0D01*
G01Y1714298D01*
G02X319441Y1714527I2003J229D01*
G02X319454Y1714756I2016J0D01*
G01Y1717167D01*
G02X319757Y1717470I303J0D01*
G37*
G36*
G01X335505D02*
X339205D01*
G02X339508Y1717167I0J-303D01*
G01Y1707161D01*
G02X339205Y1706858I-303J0D01*
G01X335505D01*
G02X335202Y1707161I0J303D01*
G01Y1709574D01*
G02X335189Y1709803I2003J229D01*
G02X335202Y1710032I2016J0D01*
G01Y1714298D01*
G02X335189Y1714527I2003J229D01*
G02X335202Y1714756I2016J0D01*
G01Y1717167D01*
G02X335505Y1717470I303J0D01*
G37*
G36*
G01X351253D02*
X354953D01*
G02X355256Y1717167I0J-303D01*
G01Y1707161D01*
G02X354953Y1706858I-303J0D01*
G01X351253D01*
G02X350950Y1707161I0J303D01*
G01Y1709574D01*
G02X350937Y1709803I2003J229D01*
G02X350950Y1710032I2016J0D01*
G01Y1714298D01*
G02X350937Y1714527I2003J229D01*
G02X350950Y1714756I2016J0D01*
G01Y1717167D01*
G02X351253Y1717470I303J0D01*
G37*
G36*
G01X501253D02*
X504953D01*
G02X505256Y1717167I0J-303D01*
G01Y1707161D01*
G02X504953Y1706858I-303J0D01*
G01X501253D01*
G02X500950Y1707161I0J303D01*
G01Y1709574D01*
G02X500937Y1709803I2003J229D01*
G02X500950Y1710032I2016J0D01*
G01Y1714298D01*
G02X500937Y1714527I2003J229D01*
G02X500950Y1714756I2016J0D01*
G01Y1717167D01*
G02X501253Y1717470I303J0D01*
G37*
G36*
G01X517001D02*
X520701D01*
G02X521004Y1717167I0J-303D01*
G01Y1707161D01*
G02X520701Y1706858I-303J0D01*
G01X517001D01*
G02X516698Y1707161I0J303D01*
G01Y1709574D01*
G02X516685Y1709803I2003J229D01*
G02X516698Y1710032I2016J0D01*
G01Y1714298D01*
G02X516685Y1714527I2003J229D01*
G02X516698Y1714756I2016J0D01*
G01Y1717167D01*
G02X517001Y1717470I303J0D01*
G37*
G36*
G01X532749D02*
X536449D01*
G02X536752Y1717167I0J-303D01*
G01Y1707161D01*
G02X536449Y1706858I-303J0D01*
G01X532749D01*
G02X532446Y1707161I0J303D01*
G01Y1709574D01*
G02X532433Y1709803I2003J229D01*
G02X532446Y1710032I2016J0D01*
G01Y1714298D01*
G02X532433Y1714527I2003J229D01*
G02X532446Y1714756I2016J0D01*
G01Y1717167D01*
G02X532749Y1717470I303J0D01*
G37*
G36*
G01X548497D02*
X552197D01*
G02X552500Y1717167I0J-303D01*
G01Y1707161D01*
G02X552197Y1706858I-303J0D01*
G01X548497D01*
G02X548194Y1707161I0J303D01*
G01Y1709574D01*
G02X548181Y1709803I2003J229D01*
G02X548194Y1710032I2016J0D01*
G01Y1714298D01*
G02X548181Y1714527I2003J229D01*
G02X548194Y1714756I2016J0D01*
G01Y1717167D01*
G02X548497Y1717470I303J0D01*
G37*
G36*
G01X568182D02*
X571882D01*
G02X572184Y1717167I-1J-303D01*
G01Y1707161D01*
G02X571882Y1706858I-302J-1D01*
G01X568182D01*
G02X567880Y1707161I1J303D01*
G01Y1709566D01*
G02X567866Y1709803I2002J237D01*
G02X567880Y1710040I2016J0D01*
G01Y1714290D01*
G02X567866Y1714527I2002J237D01*
G02X567880Y1714764I2016J0D01*
G01Y1717167D01*
G02X568182Y1717470I302J1D01*
G37*
G36*
G01X583930D02*
X587630D01*
G02X587932Y1717167I-1J-303D01*
G01Y1707161D01*
G02X587630Y1706858I-302J-1D01*
G01X583930D01*
G02X583628Y1707161I1J303D01*
G01Y1709566D01*
G02X583614Y1709803I2002J237D01*
G02X583628Y1710040I2016J0D01*
G01Y1714290D01*
G02X583614Y1714527I2002J237D01*
G02X583628Y1714764I2016J0D01*
G01Y1717167D01*
G02X583930Y1717470I302J1D01*
G37*
G36*
G01X599678D02*
X603378D01*
G02X603680Y1717167I-1J-303D01*
G01Y1707161D01*
G02X603378Y1706858I-302J-1D01*
G01X599678D01*
G02X599376Y1707161I1J303D01*
G01Y1709566D01*
G02X599362Y1709803I2002J237D01*
G02X599376Y1710040I2016J0D01*
G01Y1714290D01*
G02X599362Y1714527I2002J237D01*
G02X599376Y1714764I2016J0D01*
G01Y1717167D01*
G02X599678Y1717470I302J1D01*
G37*
G36*
G01X615426D02*
X619126D01*
G02X619428Y1717167I-1J-303D01*
G01Y1707161D01*
G02X619126Y1706858I-302J-1D01*
G01X615426D01*
G02X615124Y1707161I1J303D01*
G01Y1709566D01*
G02X615110Y1709803I2002J237D01*
G02X615124Y1710040I2016J0D01*
G01Y1714290D01*
G02X615110Y1714527I2002J237D01*
G02X615124Y1714764I2016J0D01*
G01Y1717167D01*
G02X615426Y1717470I302J1D01*
G37*
G36*
G01X1244954D02*
X1248654D01*
G02X1248956Y1717167I-1J-303D01*
G01Y1707161D01*
G02X1248654Y1706858I-302J-1D01*
G01X1244954D01*
G02X1244652Y1707161I1J303D01*
G01Y1709566D01*
G02X1244638Y1709803I2002J237D01*
G02X1244652Y1710040I2016J0D01*
G01Y1714290D01*
G02X1244638Y1714527I2002J237D01*
G02X1244652Y1714764I2016J0D01*
G01Y1717167D01*
G02X1244954Y1717470I302J1D01*
G37*
G36*
G01X1260702D02*
X1264402D01*
G02X1264704Y1717167I-1J-303D01*
G01Y1707161D01*
G02X1264402Y1706858I-302J-1D01*
G01X1260702D01*
G02X1260400Y1707161I1J303D01*
G01Y1709566D01*
G02X1260386Y1709803I2002J237D01*
G02X1260400Y1710040I2016J0D01*
G01Y1714290D01*
G02X1260386Y1714527I2002J237D01*
G02X1260400Y1714764I2016J0D01*
G01Y1717167D01*
G02X1260702Y1717470I302J1D01*
G37*
G36*
G01X1276450D02*
X1280150D01*
G02X1280452Y1717167I-1J-303D01*
G01Y1707161D01*
G02X1280150Y1706858I-302J-1D01*
G01X1276450D01*
G02X1276148Y1707161I1J303D01*
G01Y1709566D01*
G02X1276134Y1709803I2002J237D01*
G02X1276148Y1710040I2016J0D01*
G01Y1714290D01*
G02X1276134Y1714527I2002J237D01*
G02X1276148Y1714764I2016J0D01*
G01Y1717167D01*
G02X1276450Y1717470I302J1D01*
G37*
G36*
G01X1292198D02*
X1295898D01*
G02X1296200Y1717167I-1J-303D01*
G01Y1707161D01*
G02X1295898Y1706858I-302J-1D01*
G01X1292198D01*
G02X1291896Y1707161I1J303D01*
G01Y1709566D01*
G02X1291882Y1709803I2002J237D01*
G02X1291896Y1710040I2016J0D01*
G01Y1714290D01*
G02X1291882Y1714527I2002J237D01*
G02X1291896Y1714764I2016J0D01*
G01Y1717167D01*
G02X1292198Y1717470I302J1D01*
G37*
G36*
G01X1311883D02*
X1315583D01*
G02X1315886Y1717167I0J-303D01*
G01Y1707161D01*
G02X1315583Y1706858I-303J0D01*
G01X1311883D01*
G02X1311580Y1707161I0J303D01*
G01Y1709574D01*
G02X1311567Y1709803I2003J229D01*
G02X1311580Y1710032I2016J0D01*
G01Y1714298D01*
G02X1311567Y1714527I2003J229D01*
G02X1311580Y1714756I2016J0D01*
G01Y1717167D01*
G02X1311883Y1717470I303J0D01*
G37*
G36*
G01X1327631D02*
X1331331D01*
G02X1331634Y1717167I0J-303D01*
G01Y1707161D01*
G02X1331331Y1706858I-303J0D01*
G01X1327631D01*
G02X1327328Y1707161I0J303D01*
G01Y1709574D01*
G02X1327315Y1709803I2003J229D01*
G02X1327328Y1710032I2016J0D01*
G01Y1714298D01*
G02X1327315Y1714527I2003J229D01*
G02X1327328Y1714756I2016J0D01*
G01Y1717167D01*
G02X1327631Y1717470I303J0D01*
G37*
G36*
G01X1343379D02*
X1347079D01*
G02X1347382Y1717167I0J-303D01*
G01Y1707161D01*
G02X1347079Y1706858I-303J0D01*
G01X1343379D01*
G02X1343076Y1707161I0J303D01*
G01Y1709574D01*
G02X1343063Y1709803I2003J229D01*
G02X1343076Y1710032I2016J0D01*
G01Y1714298D01*
G02X1343063Y1714527I2003J229D01*
G02X1343076Y1714756I2016J0D01*
G01Y1717167D01*
G02X1343379Y1717470I303J0D01*
G37*
G36*
G01X1359127D02*
X1362827D01*
G02X1363130Y1717167I0J-303D01*
G01Y1707161D01*
G02X1362827Y1706858I-303J0D01*
G01X1359127D01*
G02X1358824Y1707161I0J303D01*
G01Y1709574D01*
G02X1358811Y1709803I2003J229D01*
G02X1358824Y1710032I2016J0D01*
G01Y1714298D01*
G02X1358811Y1714527I2003J229D01*
G02X1358824Y1714756I2016J0D01*
G01Y1717167D01*
G02X1359127Y1717470I303J0D01*
G37*
G36*
G01X1509127D02*
X1512827D01*
G02X1513130Y1717167I0J-303D01*
G01Y1707161D01*
G02X1512827Y1706858I-303J0D01*
G01X1509127D01*
G02X1508824Y1707161I0J303D01*
G01Y1709574D01*
G02X1508811Y1709803I2003J229D01*
G02X1508824Y1710032I2016J0D01*
G01Y1714298D01*
G02X1508811Y1714527I2003J229D01*
G02X1508824Y1714756I2016J0D01*
G01Y1717167D01*
G02X1509127Y1717470I303J0D01*
G37*
G36*
G01X1524875D02*
X1528575D01*
G02X1528878Y1717167I0J-303D01*
G01Y1707161D01*
G02X1528575Y1706858I-303J0D01*
G01X1524875D01*
G02X1524572Y1707161I0J303D01*
G01Y1709574D01*
G02X1524559Y1709803I2003J229D01*
G02X1524572Y1710032I2016J0D01*
G01Y1714298D01*
G02X1524559Y1714527I2003J229D01*
G02X1524572Y1714756I2016J0D01*
G01Y1717167D01*
G02X1524875Y1717470I303J0D01*
G37*
G36*
G01X1540623D02*
X1544323D01*
G02X1544626Y1717167I0J-303D01*
G01Y1707161D01*
G02X1544323Y1706858I-303J0D01*
G01X1540623D01*
G02X1540320Y1707161I0J303D01*
G01Y1709574D01*
G02X1540307Y1709803I2003J229D01*
G02X1540320Y1710032I2016J0D01*
G01Y1714298D01*
G02X1540307Y1714527I2003J229D01*
G02X1540320Y1714756I2016J0D01*
G01Y1717167D01*
G02X1540623Y1717470I303J0D01*
G37*
G36*
G01X1556371D02*
X1560071D01*
G02X1560374Y1717167I0J-303D01*
G01Y1707161D01*
G02X1560071Y1706858I-303J0D01*
G01X1556371D01*
G02X1556068Y1707161I0J303D01*
G01Y1709574D01*
G02X1556055Y1709803I2003J229D01*
G02X1556068Y1710032I2016J0D01*
G01Y1714298D01*
G02X1556055Y1714527I2003J229D01*
G02X1556068Y1714756I2016J0D01*
G01Y1717167D01*
G02X1556371Y1717470I303J0D01*
G37*
G36*
G01X1576056D02*
X1579756D01*
G02X1580058Y1717167I-1J-303D01*
G01Y1707161D01*
G02X1579756Y1706858I-302J-1D01*
G01X1576056D01*
G02X1575754Y1707161I1J303D01*
G01Y1709566D01*
G02X1575740Y1709803I2002J237D01*
G02X1575754Y1710040I2016J0D01*
G01Y1714290D01*
G02X1575740Y1714527I2002J237D01*
G02X1575754Y1714764I2016J0D01*
G01Y1717167D01*
G02X1576056Y1717470I302J1D01*
G37*
G36*
G01X1591804D02*
X1595504D01*
G02X1595806Y1717167I-1J-303D01*
G01Y1707161D01*
G02X1595504Y1706858I-302J-1D01*
G01X1591804D01*
G02X1591502Y1707161I1J303D01*
G01Y1709566D01*
G02X1591488Y1709803I2002J237D01*
G02X1591502Y1710040I2016J0D01*
G01Y1714290D01*
G02X1591488Y1714527I2002J237D01*
G02X1591502Y1714764I2016J0D01*
G01Y1717167D01*
G02X1591804Y1717470I302J1D01*
G37*
G36*
G01X1607552D02*
X1611252D01*
G02X1611554Y1717167I-1J-303D01*
G01Y1707161D01*
G02X1611252Y1706858I-302J-1D01*
G01X1607552D01*
G02X1607250Y1707161I1J303D01*
G01Y1709566D01*
G02X1607236Y1709803I2002J237D01*
G02X1607250Y1710040I2016J0D01*
G01Y1714290D01*
G02X1607236Y1714527I2002J237D01*
G02X1607250Y1714764I2016J0D01*
G01Y1717167D01*
G02X1607552Y1717470I302J1D01*
G37*
G36*
G01X1623300D02*
X1627000D01*
G02X1627302Y1717167I-1J-303D01*
G01Y1707161D01*
G02X1627000Y1706858I-302J-1D01*
G01X1623300D01*
G02X1622998Y1707161I1J303D01*
G01Y1709566D01*
G02X1622984Y1709803I2002J237D01*
G02X1622998Y1710040I2016J0D01*
G01Y1714290D01*
G02X1622984Y1714527I2002J237D01*
G02X1622998Y1714764I2016J0D01*
G01Y1717167D01*
G02X1623300Y1717470I302J1D01*
G37*
G36*
G01X229206Y1727706D02*
X232906D01*
G02X233208Y1727404I0J-302D01*
G01Y1717398D01*
G02X232906Y1717096I-302J0D01*
G01X229206D01*
G02X228904Y1717398I0J302D01*
G01Y1719802D01*
G02X228890Y1720039I2002J237D01*
G02X228904Y1720276I2016J0D01*
G01Y1724526D01*
G02X228890Y1724763I2002J237D01*
G02X228904Y1725000I2016J0D01*
G01Y1727404D01*
G02X229206Y1727706I302J0D01*
G37*
G36*
G01X244954D02*
X248654D01*
G02X248956Y1727404I0J-302D01*
G01Y1717398D01*
G02X248654Y1717096I-302J0D01*
G01X244954D01*
G02X244652Y1717398I0J302D01*
G01Y1719802D01*
G02X244638Y1720039I2002J237D01*
G02X244652Y1720276I2016J0D01*
G01Y1724526D01*
G02X244638Y1724763I2002J237D01*
G02X244652Y1725000I2016J0D01*
G01Y1727404D01*
G02X244954Y1727706I302J0D01*
G37*
G36*
G01X260702D02*
X264402D01*
G02X264704Y1727404I0J-302D01*
G01Y1717398D01*
G02X264402Y1717096I-302J0D01*
G01X260702D01*
G02X260400Y1717398I0J302D01*
G01Y1719802D01*
G02X260386Y1720039I2002J237D01*
G02X260400Y1720276I2016J0D01*
G01Y1724526D01*
G02X260386Y1724763I2002J237D01*
G02X260400Y1725000I2016J0D01*
G01Y1727404D01*
G02X260702Y1727706I302J0D01*
G37*
G36*
G01X276450D02*
X280150D01*
G02X280452Y1727404I0J-302D01*
G01Y1717398D01*
G02X280150Y1717096I-302J0D01*
G01X276450D01*
G02X276148Y1717398I0J302D01*
G01Y1719802D01*
G02X276134Y1720039I2002J237D01*
G02X276148Y1720276I2016J0D01*
G01Y1724526D01*
G02X276134Y1724763I2002J237D01*
G02X276148Y1725000I2016J0D01*
G01Y1727404D01*
G02X276450Y1727706I302J0D01*
G37*
G36*
G01X560308D02*
X564008D01*
G02X564310Y1727404I0J-302D01*
G01Y1717398D01*
G02X564008Y1717096I-302J0D01*
G01X560308D01*
G02X560006Y1717398I0J302D01*
G01Y1719802D01*
G02X559992Y1720039I2002J237D01*
G02X560006Y1720276I2016J0D01*
G01Y1724526D01*
G02X559992Y1724763I2002J237D01*
G02X560006Y1725000I2016J0D01*
G01Y1727404D01*
G02X560308Y1727706I302J0D01*
G37*
G36*
G01X576056D02*
X579756D01*
G02X580058Y1727404I0J-302D01*
G01Y1717398D01*
G02X579756Y1717096I-302J0D01*
G01X576056D01*
G02X575754Y1717398I0J302D01*
G01Y1719802D01*
G02X575740Y1720039I2002J237D01*
G02X575754Y1720276I2016J0D01*
G01Y1724526D01*
G02X575740Y1724763I2002J237D01*
G02X575754Y1725000I2016J0D01*
G01Y1727404D01*
G02X576056Y1727706I302J0D01*
G37*
G36*
G01X591804D02*
X595504D01*
G02X595806Y1727404I0J-302D01*
G01Y1717398D01*
G02X595504Y1717096I-302J0D01*
G01X591804D01*
G02X591502Y1717398I0J302D01*
G01Y1719802D01*
G02X591488Y1720039I2002J237D01*
G02X591502Y1720276I2016J0D01*
G01Y1724526D01*
G02X591488Y1724763I2002J237D01*
G02X591502Y1725000I2016J0D01*
G01Y1727404D01*
G02X591804Y1727706I302J0D01*
G37*
G36*
G01X607552D02*
X611252D01*
G02X611554Y1727404I0J-302D01*
G01Y1717398D01*
G02X611252Y1717096I-302J0D01*
G01X607552D01*
G02X607250Y1717398I0J302D01*
G01Y1719802D01*
G02X607236Y1720039I2002J237D01*
G02X607250Y1720276I2016J0D01*
G01Y1724526D01*
G02X607236Y1724763I2002J237D01*
G02X607250Y1725000I2016J0D01*
G01Y1727404D01*
G02X607552Y1727706I302J0D01*
G37*
G36*
G01X1237080D02*
X1240780D01*
G02X1241082Y1727404I0J-302D01*
G01Y1717398D01*
G02X1240780Y1717096I-302J0D01*
G01X1237080D01*
G02X1236778Y1717398I0J302D01*
G01Y1719802D01*
G02X1236764Y1720039I2002J237D01*
G02X1236778Y1720276I2016J0D01*
G01Y1724526D01*
G02X1236764Y1724763I2002J237D01*
G02X1236778Y1725000I2016J0D01*
G01Y1727404D01*
G02X1237080Y1727706I302J0D01*
G37*
G36*
G01X1252828D02*
X1256528D01*
G02X1256830Y1727404I0J-302D01*
G01Y1717398D01*
G02X1256528Y1717096I-302J0D01*
G01X1252828D01*
G02X1252526Y1717398I0J302D01*
G01Y1719802D01*
G02X1252512Y1720039I2002J237D01*
G02X1252526Y1720276I2016J0D01*
G01Y1724526D01*
G02X1252512Y1724763I2002J237D01*
G02X1252526Y1725000I2016J0D01*
G01Y1727404D01*
G02X1252828Y1727706I302J0D01*
G37*
G36*
G01X1268576D02*
X1272276D01*
G02X1272578Y1727404I0J-302D01*
G01Y1717398D01*
G02X1272276Y1717096I-302J0D01*
G01X1268576D01*
G02X1268274Y1717398I0J302D01*
G01Y1719802D01*
G02X1268260Y1720039I2002J237D01*
G02X1268274Y1720276I2016J0D01*
G01Y1724526D01*
G02X1268260Y1724763I2002J237D01*
G02X1268274Y1725000I2016J0D01*
G01Y1727404D01*
G02X1268576Y1727706I302J0D01*
G37*
G36*
G01X1284324D02*
X1288024D01*
G02X1288326Y1727404I0J-302D01*
G01Y1717398D01*
G02X1288024Y1717096I-302J0D01*
G01X1284324D01*
G02X1284022Y1717398I0J302D01*
G01Y1719802D01*
G02X1284008Y1720039I2002J237D01*
G02X1284022Y1720276I2016J0D01*
G01Y1724526D01*
G02X1284008Y1724763I2002J237D01*
G02X1284022Y1725000I2016J0D01*
G01Y1727404D01*
G02X1284324Y1727706I302J0D01*
G37*
G36*
G01X1568182D02*
X1571882D01*
G02X1572184Y1727404I0J-302D01*
G01Y1717398D01*
G02X1571882Y1717096I-302J0D01*
G01X1568182D01*
G02X1567880Y1717398I0J302D01*
G01Y1719802D01*
G02X1567866Y1720039I2002J237D01*
G02X1567880Y1720276I2016J0D01*
G01Y1724526D01*
G02X1567866Y1724763I2002J237D01*
G02X1567880Y1725000I2016J0D01*
G01Y1727404D01*
G02X1568182Y1727706I302J0D01*
G37*
G36*
G01X1583930D02*
X1587630D01*
G02X1587932Y1727404I0J-302D01*
G01Y1717398D01*
G02X1587630Y1717096I-302J0D01*
G01X1583930D01*
G02X1583628Y1717398I0J302D01*
G01Y1719802D01*
G02X1583614Y1720039I2002J237D01*
G02X1583628Y1720276I2016J0D01*
G01Y1724526D01*
G02X1583614Y1724763I2002J237D01*
G02X1583628Y1725000I2016J0D01*
G01Y1727404D01*
G02X1583930Y1727706I302J0D01*
G37*
G36*
G01X1599678D02*
X1603378D01*
G02X1603680Y1727404I0J-302D01*
G01Y1717398D01*
G02X1603378Y1717096I-302J0D01*
G01X1599678D01*
G02X1599376Y1717398I0J302D01*
G01Y1719802D01*
G02X1599362Y1720039I2002J237D01*
G02X1599376Y1720276I2016J0D01*
G01Y1724526D01*
G02X1599362Y1724763I2002J237D01*
G02X1599376Y1725000I2016J0D01*
G01Y1727404D01*
G02X1599678Y1727706I302J0D01*
G37*
G36*
G01X1615426D02*
X1619126D01*
G02X1619428Y1727404I0J-302D01*
G01Y1717398D01*
G02X1619126Y1717096I-302J0D01*
G01X1615426D01*
G02X1615124Y1717398I0J302D01*
G01Y1719802D01*
G02X1615110Y1720039I2002J237D01*
G02X1615124Y1720276I2016J0D01*
G01Y1724526D01*
G02X1615110Y1724763I2002J237D01*
G02X1615124Y1725000I2016J0D01*
G01Y1727404D01*
G02X1615426Y1727706I302J0D01*
G37*
G36*
G01X296135D02*
X299835D01*
G02X300138Y1727404I1J-302D01*
G01Y1717398D01*
G02X299835Y1717096I-303J1D01*
G01X296135D01*
G02X295832Y1717398I-1J302D01*
G01Y1719810D01*
G02X295819Y1720039I2003J229D01*
G02X295832Y1720268I2016J0D01*
G01Y1724534D01*
G02X295819Y1724763I2003J229D01*
G02X295832Y1724992I2016J0D01*
G01Y1727404D01*
G02X296135Y1727706I303J-1D01*
G37*
G36*
G01X311883D02*
X315583D01*
G02X315886Y1727404I1J-302D01*
G01Y1717398D01*
G02X315583Y1717096I-303J1D01*
G01X311883D01*
G02X311580Y1717398I-1J302D01*
G01Y1719810D01*
G02X311567Y1720039I2003J229D01*
G02X311580Y1720268I2016J0D01*
G01Y1724534D01*
G02X311567Y1724763I2003J229D01*
G02X311580Y1724992I2016J0D01*
G01Y1727404D01*
G02X311883Y1727706I303J-1D01*
G37*
G36*
G01X327631D02*
X331331D01*
G02X331634Y1727404I1J-302D01*
G01Y1717398D01*
G02X331331Y1717096I-303J1D01*
G01X327631D01*
G02X327328Y1717398I-1J302D01*
G01Y1719810D01*
G02X327315Y1720039I2003J229D01*
G02X327328Y1720268I2016J0D01*
G01Y1724534D01*
G02X327315Y1724763I2003J229D01*
G02X327328Y1724992I2016J0D01*
G01Y1727404D01*
G02X327631Y1727706I303J-1D01*
G37*
G36*
G01X343379D02*
X347079D01*
G02X347382Y1727404I1J-302D01*
G01Y1717398D01*
G02X347079Y1717096I-303J1D01*
G01X343379D01*
G02X343076Y1717398I-1J302D01*
G01Y1719810D01*
G02X343063Y1720039I2003J229D01*
G02X343076Y1720268I2016J0D01*
G01Y1724534D01*
G02X343063Y1724763I2003J229D01*
G02X343076Y1724992I2016J0D01*
G01Y1727404D01*
G02X343379Y1727706I303J-1D01*
G37*
G36*
G01X493379D02*
X497079D01*
G02X497382Y1727404I1J-302D01*
G01Y1717398D01*
G02X497079Y1717096I-303J1D01*
G01X493379D01*
G02X493076Y1717398I-1J302D01*
G01Y1719810D01*
G02X493063Y1720039I2003J229D01*
G02X493076Y1720268I2016J0D01*
G01Y1724534D01*
G02X493063Y1724763I2003J229D01*
G02X493076Y1724992I2016J0D01*
G01Y1727404D01*
G02X493379Y1727706I303J-1D01*
G37*
G36*
G01X509127D02*
X512827D01*
G02X513130Y1727404I1J-302D01*
G01Y1717398D01*
G02X512827Y1717096I-303J1D01*
G01X509127D01*
G02X508824Y1717398I-1J302D01*
G01Y1719810D01*
G02X508811Y1720039I2003J229D01*
G02X508824Y1720268I2016J0D01*
G01Y1724534D01*
G02X508811Y1724763I2003J229D01*
G02X508824Y1724992I2016J0D01*
G01Y1727404D01*
G02X509127Y1727706I303J-1D01*
G37*
G36*
G01X524875D02*
X528575D01*
G02X528878Y1727404I1J-302D01*
G01Y1717398D01*
G02X528575Y1717096I-303J1D01*
G01X524875D01*
G02X524572Y1717398I-1J302D01*
G01Y1719810D01*
G02X524559Y1720039I2003J229D01*
G02X524572Y1720268I2016J0D01*
G01Y1724534D01*
G02X524559Y1724763I2003J229D01*
G02X524572Y1724992I2016J0D01*
G01Y1727404D01*
G02X524875Y1727706I303J-1D01*
G37*
G36*
G01X540623D02*
X544323D01*
G02X544626Y1727404I1J-302D01*
G01Y1717398D01*
G02X544323Y1717096I-303J1D01*
G01X540623D01*
G02X540320Y1717398I-1J302D01*
G01Y1719810D01*
G02X540307Y1720039I2003J229D01*
G02X540320Y1720268I2016J0D01*
G01Y1724534D01*
G02X540307Y1724763I2003J229D01*
G02X540320Y1724992I2016J0D01*
G01Y1727404D01*
G02X540623Y1727706I303J-1D01*
G37*
G36*
G01X1304009D02*
X1307709D01*
G02X1308012Y1727404I1J-302D01*
G01Y1717398D01*
G02X1307709Y1717096I-303J1D01*
G01X1304009D01*
G02X1303706Y1717398I-1J302D01*
G01Y1719810D01*
G02X1303693Y1720039I2003J229D01*
G02X1303706Y1720268I2016J0D01*
G01Y1724534D01*
G02X1303693Y1724763I2003J229D01*
G02X1303706Y1724992I2016J0D01*
G01Y1727404D01*
G02X1304009Y1727706I303J-1D01*
G37*
G36*
G01X1319757D02*
X1323457D01*
G02X1323760Y1727404I1J-302D01*
G01Y1717398D01*
G02X1323457Y1717096I-303J1D01*
G01X1319757D01*
G02X1319454Y1717398I-1J302D01*
G01Y1719810D01*
G02X1319441Y1720039I2003J229D01*
G02X1319454Y1720268I2016J0D01*
G01Y1724534D01*
G02X1319441Y1724763I2003J229D01*
G02X1319454Y1724992I2016J0D01*
G01Y1727404D01*
G02X1319757Y1727706I303J-1D01*
G37*
G36*
G01X1335505D02*
X1339205D01*
G02X1339508Y1727404I1J-302D01*
G01Y1717398D01*
G02X1339205Y1717096I-303J1D01*
G01X1335505D01*
G02X1335202Y1717398I-1J302D01*
G01Y1719810D01*
G02X1335189Y1720039I2003J229D01*
G02X1335202Y1720268I2016J0D01*
G01Y1724534D01*
G02X1335189Y1724763I2003J229D01*
G02X1335202Y1724992I2016J0D01*
G01Y1727404D01*
G02X1335505Y1727706I303J-1D01*
G37*
G36*
G01X1351253D02*
X1354953D01*
G02X1355256Y1727404I1J-302D01*
G01Y1717398D01*
G02X1354953Y1717096I-303J1D01*
G01X1351253D01*
G02X1350950Y1717398I-1J302D01*
G01Y1719810D01*
G02X1350937Y1720039I2003J229D01*
G02X1350950Y1720268I2016J0D01*
G01Y1724534D01*
G02X1350937Y1724763I2003J229D01*
G02X1350950Y1724992I2016J0D01*
G01Y1727404D01*
G02X1351253Y1727706I303J-1D01*
G37*
G36*
G01X1501253D02*
X1504953D01*
G02X1505256Y1727404I1J-302D01*
G01Y1717398D01*
G02X1504953Y1717096I-303J1D01*
G01X1501253D01*
G02X1500950Y1717398I-1J302D01*
G01Y1719810D01*
G02X1500937Y1720039I2003J229D01*
G02X1500950Y1720268I2016J0D01*
G01Y1724534D01*
G02X1500937Y1724763I2003J229D01*
G02X1500950Y1724992I2016J0D01*
G01Y1727404D01*
G02X1501253Y1727706I303J-1D01*
G37*
G36*
G01X1517001D02*
X1520701D01*
G02X1521004Y1727404I1J-302D01*
G01Y1717398D01*
G02X1520701Y1717096I-303J1D01*
G01X1517001D01*
G02X1516698Y1717398I-1J302D01*
G01Y1719810D01*
G02X1516685Y1720039I2003J229D01*
G02X1516698Y1720268I2016J0D01*
G01Y1724534D01*
G02X1516685Y1724763I2003J229D01*
G02X1516698Y1724992I2016J0D01*
G01Y1727404D01*
G02X1517001Y1727706I303J-1D01*
G37*
G36*
G01X1532749D02*
X1536449D01*
G02X1536752Y1727404I1J-302D01*
G01Y1717398D01*
G02X1536449Y1717096I-303J1D01*
G01X1532749D01*
G02X1532446Y1717398I-1J302D01*
G01Y1719810D01*
G02X1532433Y1720039I2003J229D01*
G02X1532446Y1720268I2016J0D01*
G01Y1724534D01*
G02X1532433Y1724763I2003J229D01*
G02X1532446Y1724992I2016J0D01*
G01Y1727404D01*
G02X1532749Y1727706I303J-1D01*
G37*
G36*
G01X1548497D02*
X1552197D01*
G02X1552500Y1727404I1J-302D01*
G01Y1717398D01*
G02X1552197Y1717096I-303J1D01*
G01X1548497D01*
G02X1548194Y1717398I-1J302D01*
G01Y1719810D01*
G02X1548181Y1720039I2003J229D01*
G02X1548194Y1720268I2016J0D01*
G01Y1724534D01*
G02X1548181Y1724763I2003J229D01*
G02X1548194Y1724992I2016J0D01*
G01Y1727404D01*
G02X1548497Y1727706I303J-1D01*
G37*
G36*
G01X237080Y1731644D02*
X240780D01*
G02X241082Y1731341I-1J-303D01*
G01Y1721335D01*
G02X240780Y1721032I-302J-1D01*
G01X237080D01*
G02X236778Y1721335I1J303D01*
G01Y1723739D01*
G02X236764Y1723976I2002J237D01*
G02X236778Y1724213I2016J0D01*
G01Y1728463D01*
G02X236764Y1728700I2002J237D01*
G02X236778Y1728937I2016J0D01*
G01Y1731341D01*
G02X237080Y1731644I302J1D01*
G37*
G36*
G01X252828D02*
X256528D01*
G02X256830Y1731341I-1J-303D01*
G01Y1721335D01*
G02X256528Y1721032I-302J-1D01*
G01X252828D01*
G02X252526Y1721335I1J303D01*
G01Y1723739D01*
G02X252512Y1723976I2002J237D01*
G02X252526Y1724213I2016J0D01*
G01Y1728463D01*
G02X252512Y1728700I2002J237D01*
G02X252526Y1728937I2016J0D01*
G01Y1731341D01*
G02X252828Y1731644I302J1D01*
G37*
G36*
G01X268576D02*
X272276D01*
G02X272578Y1731341I-1J-303D01*
G01Y1721335D01*
G02X272276Y1721032I-302J-1D01*
G01X268576D01*
G02X268274Y1721335I1J303D01*
G01Y1723739D01*
G02X268260Y1723976I2002J237D01*
G02X268274Y1724213I2016J0D01*
G01Y1728463D01*
G02X268260Y1728700I2002J237D01*
G02X268274Y1728937I2016J0D01*
G01Y1731341D01*
G02X268576Y1731644I302J1D01*
G37*
G36*
G01X284324D02*
X288024D01*
G02X288326Y1731341I-1J-303D01*
G01Y1721335D01*
G02X288024Y1721032I-302J-1D01*
G01X284324D01*
G02X284022Y1721335I1J303D01*
G01Y1723739D01*
G02X284008Y1723976I2002J237D01*
G02X284022Y1724213I2016J0D01*
G01Y1728463D01*
G02X284008Y1728700I2002J237D01*
G02X284022Y1728937I2016J0D01*
G01Y1731341D01*
G02X284324Y1731644I302J1D01*
G37*
G36*
G01X304009D02*
X307709D01*
G02X308012Y1731341I0J-303D01*
G01Y1721335D01*
G02X307709Y1721032I-303J0D01*
G01X304009D01*
G02X303706Y1721335I0J303D01*
G01Y1723747D01*
G02X303693Y1723976I2003J229D01*
G02X303706Y1724205I2016J0D01*
G01Y1728471D01*
G02X303693Y1728700I2003J229D01*
G02X303706Y1728929I2016J0D01*
G01Y1731341D01*
G02X304009Y1731644I303J0D01*
G37*
G36*
G01X319757D02*
X323457D01*
G02X323760Y1731341I0J-303D01*
G01Y1721335D01*
G02X323457Y1721032I-303J0D01*
G01X319757D01*
G02X319454Y1721335I0J303D01*
G01Y1723747D01*
G02X319441Y1723976I2003J229D01*
G02X319454Y1724205I2016J0D01*
G01Y1728471D01*
G02X319441Y1728700I2003J229D01*
G02X319454Y1728929I2016J0D01*
G01Y1731341D01*
G02X319757Y1731644I303J0D01*
G37*
G36*
G01X335505D02*
X339205D01*
G02X339508Y1731341I0J-303D01*
G01Y1721335D01*
G02X339205Y1721032I-303J0D01*
G01X335505D01*
G02X335202Y1721335I0J303D01*
G01Y1723747D01*
G02X335189Y1723976I2003J229D01*
G02X335202Y1724205I2016J0D01*
G01Y1728471D01*
G02X335189Y1728700I2003J229D01*
G02X335202Y1728929I2016J0D01*
G01Y1731341D01*
G02X335505Y1731644I303J0D01*
G37*
G36*
G01X351253D02*
X354953D01*
G02X355256Y1731341I0J-303D01*
G01Y1721335D01*
G02X354953Y1721032I-303J0D01*
G01X351253D01*
G02X350950Y1721335I0J303D01*
G01Y1723747D01*
G02X350937Y1723976I2003J229D01*
G02X350950Y1724205I2016J0D01*
G01Y1728471D01*
G02X350937Y1728700I2003J229D01*
G02X350950Y1728929I2016J0D01*
G01Y1731341D01*
G02X351253Y1731644I303J0D01*
G37*
G36*
G01X501253D02*
X504953D01*
G02X505256Y1731341I0J-303D01*
G01Y1721335D01*
G02X504953Y1721032I-303J0D01*
G01X501253D01*
G02X500950Y1721335I0J303D01*
G01Y1723747D01*
G02X500937Y1723976I2003J229D01*
G02X500950Y1724205I2016J0D01*
G01Y1728471D01*
G02X500937Y1728700I2003J229D01*
G02X500950Y1728929I2016J0D01*
G01Y1731341D01*
G02X501253Y1731644I303J0D01*
G37*
G36*
G01X517001D02*
X520701D01*
G02X521004Y1731341I0J-303D01*
G01Y1721335D01*
G02X520701Y1721032I-303J0D01*
G01X517001D01*
G02X516698Y1721335I0J303D01*
G01Y1723747D01*
G02X516685Y1723976I2003J229D01*
G02X516698Y1724205I2016J0D01*
G01Y1728471D01*
G02X516685Y1728700I2003J229D01*
G02X516698Y1728929I2016J0D01*
G01Y1731341D01*
G02X517001Y1731644I303J0D01*
G37*
G36*
G01X532749D02*
X536449D01*
G02X536752Y1731341I0J-303D01*
G01Y1721335D01*
G02X536449Y1721032I-303J0D01*
G01X532749D01*
G02X532446Y1721335I0J303D01*
G01Y1723747D01*
G02X532433Y1723976I2003J229D01*
G02X532446Y1724205I2016J0D01*
G01Y1728471D01*
G02X532433Y1728700I2003J229D01*
G02X532446Y1728929I2016J0D01*
G01Y1731341D01*
G02X532749Y1731644I303J0D01*
G37*
G36*
G01X548497D02*
X552197D01*
G02X552500Y1731341I0J-303D01*
G01Y1721335D01*
G02X552197Y1721032I-303J0D01*
G01X548497D01*
G02X548194Y1721335I0J303D01*
G01Y1723747D01*
G02X548181Y1723976I2003J229D01*
G02X548194Y1724205I2016J0D01*
G01Y1728471D01*
G02X548181Y1728700I2003J229D01*
G02X548194Y1728929I2016J0D01*
G01Y1731341D01*
G02X548497Y1731644I303J0D01*
G37*
G36*
G01X568182D02*
X571882D01*
G02X572184Y1731341I-1J-303D01*
G01Y1721335D01*
G02X571882Y1721032I-302J-1D01*
G01X568182D01*
G02X567880Y1721335I1J303D01*
G01Y1723739D01*
G02X567866Y1723976I2002J237D01*
G02X567880Y1724213I2016J0D01*
G01Y1728463D01*
G02X567866Y1728700I2002J237D01*
G02X567880Y1728937I2016J0D01*
G01Y1731341D01*
G02X568182Y1731644I302J1D01*
G37*
G36*
G01X583930D02*
X587630D01*
G02X587932Y1731341I-1J-303D01*
G01Y1721335D01*
G02X587630Y1721032I-302J-1D01*
G01X583930D01*
G02X583628Y1721335I1J303D01*
G01Y1723739D01*
G02X583614Y1723976I2002J237D01*
G02X583628Y1724213I2016J0D01*
G01Y1728463D01*
G02X583614Y1728700I2002J237D01*
G02X583628Y1728937I2016J0D01*
G01Y1731341D01*
G02X583930Y1731644I302J1D01*
G37*
G36*
G01X599678D02*
X603378D01*
G02X603680Y1731341I-1J-303D01*
G01Y1721335D01*
G02X603378Y1721032I-302J-1D01*
G01X599678D01*
G02X599376Y1721335I1J303D01*
G01Y1723739D01*
G02X599362Y1723976I2002J237D01*
G02X599376Y1724213I2016J0D01*
G01Y1728463D01*
G02X599362Y1728700I2002J237D01*
G02X599376Y1728937I2016J0D01*
G01Y1731341D01*
G02X599678Y1731644I302J1D01*
G37*
G36*
G01X615426D02*
X619126D01*
G02X619428Y1731341I-1J-303D01*
G01Y1721335D01*
G02X619126Y1721032I-302J-1D01*
G01X615426D01*
G02X615124Y1721335I1J303D01*
G01Y1723739D01*
G02X615110Y1723976I2002J237D01*
G02X615124Y1724213I2016J0D01*
G01Y1728463D01*
G02X615110Y1728700I2002J237D01*
G02X615124Y1728937I2016J0D01*
G01Y1731341D01*
G02X615426Y1731644I302J1D01*
G37*
G36*
G01X1244954D02*
X1248654D01*
G02X1248956Y1731341I-1J-303D01*
G01Y1721335D01*
G02X1248654Y1721032I-302J-1D01*
G01X1244954D01*
G02X1244652Y1721335I1J303D01*
G01Y1723739D01*
G02X1244638Y1723976I2002J237D01*
G02X1244652Y1724213I2016J0D01*
G01Y1728463D01*
G02X1244638Y1728700I2002J237D01*
G02X1244652Y1728937I2016J0D01*
G01Y1731341D01*
G02X1244954Y1731644I302J1D01*
G37*
G36*
G01X1260702D02*
X1264402D01*
G02X1264704Y1731341I-1J-303D01*
G01Y1721335D01*
G02X1264402Y1721032I-302J-1D01*
G01X1260702D01*
G02X1260400Y1721335I1J303D01*
G01Y1723739D01*
G02X1260386Y1723976I2002J237D01*
G02X1260400Y1724213I2016J0D01*
G01Y1728463D01*
G02X1260386Y1728700I2002J237D01*
G02X1260400Y1728937I2016J0D01*
G01Y1731341D01*
G02X1260702Y1731644I302J1D01*
G37*
G36*
G01X1276450D02*
X1280150D01*
G02X1280452Y1731341I-1J-303D01*
G01Y1721335D01*
G02X1280150Y1721032I-302J-1D01*
G01X1276450D01*
G02X1276148Y1721335I1J303D01*
G01Y1723739D01*
G02X1276134Y1723976I2002J237D01*
G02X1276148Y1724213I2016J0D01*
G01Y1728463D01*
G02X1276134Y1728700I2002J237D01*
G02X1276148Y1728937I2016J0D01*
G01Y1731341D01*
G02X1276450Y1731644I302J1D01*
G37*
G36*
G01X1292198D02*
X1295898D01*
G02X1296200Y1731341I-1J-303D01*
G01Y1721335D01*
G02X1295898Y1721032I-302J-1D01*
G01X1292198D01*
G02X1291896Y1721335I1J303D01*
G01Y1723739D01*
G02X1291882Y1723976I2002J237D01*
G02X1291896Y1724213I2016J0D01*
G01Y1728463D01*
G02X1291882Y1728700I2002J237D01*
G02X1291896Y1728937I2016J0D01*
G01Y1731341D01*
G02X1292198Y1731644I302J1D01*
G37*
G36*
G01X1311883D02*
X1315583D01*
G02X1315886Y1731341I0J-303D01*
G01Y1721335D01*
G02X1315583Y1721032I-303J0D01*
G01X1311883D01*
G02X1311580Y1721335I0J303D01*
G01Y1723747D01*
G02X1311567Y1723976I2003J229D01*
G02X1311580Y1724205I2016J0D01*
G01Y1728471D01*
G02X1311567Y1728700I2003J229D01*
G02X1311580Y1728929I2016J0D01*
G01Y1731341D01*
G02X1311883Y1731644I303J0D01*
G37*
G36*
G01X1327631D02*
X1331331D01*
G02X1331634Y1731341I0J-303D01*
G01Y1721335D01*
G02X1331331Y1721032I-303J0D01*
G01X1327631D01*
G02X1327328Y1721335I0J303D01*
G01Y1723747D01*
G02X1327315Y1723976I2003J229D01*
G02X1327328Y1724205I2016J0D01*
G01Y1728471D01*
G02X1327315Y1728700I2003J229D01*
G02X1327328Y1728929I2016J0D01*
G01Y1731341D01*
G02X1327631Y1731644I303J0D01*
G37*
G36*
G01X1343379D02*
X1347079D01*
G02X1347382Y1731341I0J-303D01*
G01Y1721335D01*
G02X1347079Y1721032I-303J0D01*
G01X1343379D01*
G02X1343076Y1721335I0J303D01*
G01Y1723747D01*
G02X1343063Y1723976I2003J229D01*
G02X1343076Y1724205I2016J0D01*
G01Y1728471D01*
G02X1343063Y1728700I2003J229D01*
G02X1343076Y1728929I2016J0D01*
G01Y1731341D01*
G02X1343379Y1731644I303J0D01*
G37*
G36*
G01X1359127D02*
X1362827D01*
G02X1363130Y1731341I0J-303D01*
G01Y1721335D01*
G02X1362827Y1721032I-303J0D01*
G01X1359127D01*
G02X1358824Y1721335I0J303D01*
G01Y1723747D01*
G02X1358811Y1723976I2003J229D01*
G02X1358824Y1724205I2016J0D01*
G01Y1728471D01*
G02X1358811Y1728700I2003J229D01*
G02X1358824Y1728929I2016J0D01*
G01Y1731341D01*
G02X1359127Y1731644I303J0D01*
G37*
G36*
G01X1509127D02*
X1512827D01*
G02X1513130Y1731341I0J-303D01*
G01Y1721335D01*
G02X1512827Y1721032I-303J0D01*
G01X1509127D01*
G02X1508824Y1721335I0J303D01*
G01Y1723747D01*
G02X1508811Y1723976I2003J229D01*
G02X1508824Y1724205I2016J0D01*
G01Y1728471D01*
G02X1508811Y1728700I2003J229D01*
G02X1508824Y1728929I2016J0D01*
G01Y1731341D01*
G02X1509127Y1731644I303J0D01*
G37*
G36*
G01X1524875D02*
X1528575D01*
G02X1528878Y1731341I0J-303D01*
G01Y1721335D01*
G02X1528575Y1721032I-303J0D01*
G01X1524875D01*
G02X1524572Y1721335I0J303D01*
G01Y1723747D01*
G02X1524559Y1723976I2003J229D01*
G02X1524572Y1724205I2016J0D01*
G01Y1728471D01*
G02X1524559Y1728700I2003J229D01*
G02X1524572Y1728929I2016J0D01*
G01Y1731341D01*
G02X1524875Y1731644I303J0D01*
G37*
G36*
G01X1540623D02*
X1544323D01*
G02X1544626Y1731341I0J-303D01*
G01Y1721335D01*
G02X1544323Y1721032I-303J0D01*
G01X1540623D01*
G02X1540320Y1721335I0J303D01*
G01Y1723747D01*
G02X1540307Y1723976I2003J229D01*
G02X1540320Y1724205I2016J0D01*
G01Y1728471D01*
G02X1540307Y1728700I2003J229D01*
G02X1540320Y1728929I2016J0D01*
G01Y1731341D01*
G02X1540623Y1731644I303J0D01*
G37*
G36*
G01X1556371D02*
X1560071D01*
G02X1560374Y1731341I0J-303D01*
G01Y1721335D01*
G02X1560071Y1721032I-303J0D01*
G01X1556371D01*
G02X1556068Y1721335I0J303D01*
G01Y1723747D01*
G02X1556055Y1723976I2003J229D01*
G02X1556068Y1724205I2016J0D01*
G01Y1728471D01*
G02X1556055Y1728700I2003J229D01*
G02X1556068Y1728929I2016J0D01*
G01Y1731341D01*
G02X1556371Y1731644I303J0D01*
G37*
G36*
G01X1576056D02*
X1579756D01*
G02X1580058Y1731341I-1J-303D01*
G01Y1721335D01*
G02X1579756Y1721032I-302J-1D01*
G01X1576056D01*
G02X1575754Y1721335I1J303D01*
G01Y1723739D01*
G02X1575740Y1723976I2002J237D01*
G02X1575754Y1724213I2016J0D01*
G01Y1728463D01*
G02X1575740Y1728700I2002J237D01*
G02X1575754Y1728937I2016J0D01*
G01Y1731341D01*
G02X1576056Y1731644I302J1D01*
G37*
G36*
G01X1591804D02*
X1595504D01*
G02X1595806Y1731341I-1J-303D01*
G01Y1721335D01*
G02X1595504Y1721032I-302J-1D01*
G01X1591804D01*
G02X1591502Y1721335I1J303D01*
G01Y1723739D01*
G02X1591488Y1723976I2002J237D01*
G02X1591502Y1724213I2016J0D01*
G01Y1728463D01*
G02X1591488Y1728700I2002J237D01*
G02X1591502Y1728937I2016J0D01*
G01Y1731341D01*
G02X1591804Y1731644I302J1D01*
G37*
G36*
G01X1607552D02*
X1611252D01*
G02X1611554Y1731341I-1J-303D01*
G01Y1721335D01*
G02X1611252Y1721032I-302J-1D01*
G01X1607552D01*
G02X1607250Y1721335I1J303D01*
G01Y1723739D01*
G02X1607236Y1723976I2002J237D01*
G02X1607250Y1724213I2016J0D01*
G01Y1728463D01*
G02X1607236Y1728700I2002J237D01*
G02X1607250Y1728937I2016J0D01*
G01Y1731341D01*
G02X1607552Y1731644I302J1D01*
G37*
G36*
G01X1623300D02*
X1627000D01*
G02X1627302Y1731341I-1J-303D01*
G01Y1721335D01*
G02X1627000Y1721032I-302J-1D01*
G01X1623300D01*
G02X1622998Y1721335I1J303D01*
G01Y1723739D01*
G02X1622984Y1723976I2002J237D01*
G02X1622998Y1724213I2016J0D01*
G01Y1728463D01*
G02X1622984Y1728700I2002J237D01*
G02X1622998Y1728937I2016J0D01*
G01Y1731341D01*
G02X1623300Y1731644I302J1D01*
G37*
G36*
G01X105651Y1575002D02*
X102251D01*
G02Y1578006I0J1502D01*
G01X105651D01*
G02Y1575002I0J-1502D01*
G37*
G36*
G01X74218Y1574006D02*
X77618D01*
G02Y1571002I0J-1502D01*
G01X74218D01*
G02Y1574006I0J1502D01*
G37*
G36*
G01X76369Y1508958D02*
X79769D01*
G02Y1505954I0J-1502D01*
G01X76369D01*
G02Y1508958I0J1502D01*
G37*
G36*
G01X391330Y1583652D02*
X387930D01*
G02Y1586658I0J1503D01*
G01X391330D01*
G02Y1583652I0J-1503D01*
G37*
G36*
G01X148938Y1515872D02*
X145538D01*
G02Y1518876I0J1502D01*
G01X148938D01*
G02Y1515872I0J-1502D01*
G37*
G36*
G01X164710Y1519516D02*
X168110D01*
G02Y1516512I0J-1502D01*
G01X164710D01*
G02Y1519516I0J1502D01*
G37*
G36*
G01X89264Y1509114D02*
X92664D01*
G02Y1506108I0J-1503D01*
G01X89264D01*
G02Y1509114I0J1503D01*
G37*
G36*
G01X167266Y1571470D02*
X170666D01*
G02Y1568466I0J-1502D01*
G01X167266D01*
G02Y1571470I0J1502D01*
G37*
G36*
G01X524914Y114816D02*
G02X525284Y115178I388J-27D01*
G01X526492D01*
Y115179D01*
G02X526777Y115059I2J-395D01*
G02X526886Y114795I-285J-272D01*
G01Y110585D01*
X526883Y110559D01*
G02X526516Y110222I-386J52D01*
G01X525308D01*
Y110221D01*
G02X525023Y110341I-2J395D01*
G02X524914Y110605I285J272D01*
G01Y114816D01*
G37*
G36*
G01Y107916D02*
G02X525284Y108278I388J-27D01*
G01X526492D01*
Y108279D01*
G02X526777Y108159I2J-395D01*
G02X526886Y107895I-285J-272D01*
G01Y103685D01*
X526883Y103659D01*
G02X526516Y103322I-386J52D01*
G01X525308D01*
Y103321D01*
G02X525023Y103441I-2J395D01*
G02X524914Y103705I285J272D01*
G01Y107916D01*
G37*
G36*
G01X1346792Y1615794D02*
X1350192D01*
G02Y1612790I0J-1502D01*
G01X1346792D01*
G02Y1615794I0J1502D01*
G37*
G36*
G01X1358852D02*
X1362252D01*
G02Y1612790I0J-1502D01*
G01X1358852D01*
G02Y1615794I0J1502D01*
G37*
G36*
G01X1365612Y1591596D02*
X1369012D01*
G02Y1588592I0J-1502D01*
G01X1365612D01*
G02Y1591596I0J1502D01*
G37*
G36*
G01Y1579684D02*
X1369012D01*
G02Y1576680I0J-1502D01*
G01X1365612D01*
G02Y1579684I0J1502D01*
G37*
G36*
G01X1305312D02*
X1308712D01*
G02Y1576680I0J-1502D01*
G01X1305312D01*
G02Y1579684I0J1502D01*
G37*
G36*
G01X1293252Y1591596D02*
X1296652D01*
G02Y1588592I0J-1502D01*
G01X1293252D01*
G02Y1591596I0J1502D01*
G37*
G36*
G01X1310612Y1615794D02*
X1314012D01*
G02Y1612790I0J-1502D01*
G01X1310612D01*
G02Y1615794I0J1502D01*
G37*
G36*
G01X1262372Y1603882D02*
X1265772D01*
G02Y1600878I0J-1502D01*
G01X1262372D01*
G02Y1603882I0J1502D01*
G37*
G36*
G01X1286492Y1615794D02*
X1289892D01*
G02Y1612790I0J-1502D01*
G01X1286492D01*
G02Y1615794I0J1502D01*
G37*
G36*
G01X1262372D02*
X1265772D01*
G02Y1612790I0J-1502D01*
G01X1262372D01*
G02Y1615794I0J1502D01*
G37*
G36*
G01X1334732Y1603882D02*
X1338132D01*
G02Y1600878I0J-1502D01*
G01X1334732D01*
G02Y1603882I0J1502D01*
G37*
G36*
G01X1220892Y1579684D02*
X1224292D01*
G02Y1576680I0J-1502D01*
G01X1220892D01*
G02Y1579684I0J1502D01*
G37*
G36*
G01X1334732Y1615794D02*
X1338132D01*
G02Y1612790I0J-1502D01*
G01X1334732D01*
G02Y1615794I0J1502D01*
G37*
G36*
G01X1370912Y1603882D02*
X1374312D01*
G02Y1600878I0J-1502D01*
G01X1370912D01*
G02Y1603882I0J1502D01*
G37*
G36*
G01X1214132D02*
X1217532D01*
G02Y1600878I0J-1502D01*
G01X1214132D01*
G02Y1603882I0J1502D01*
G37*
G36*
G01X1286492D02*
X1289892D01*
G02Y1600878I0J-1502D01*
G01X1286492D01*
G02Y1603882I0J1502D01*
G37*
G36*
G01X1298552D02*
X1301952D01*
G02Y1600878I0J-1502D01*
G01X1298552D01*
G02Y1603882I0J1502D01*
G37*
G36*
G01X1353552Y1579684D02*
X1356952D01*
G02Y1576680I0J-1502D01*
G01X1353552D01*
G02Y1579684I0J1502D01*
G37*
G36*
G01X1341492Y1591596D02*
X1344892D01*
G02Y1588592I0J-1502D01*
G01X1341492D01*
G02Y1591596I0J1502D01*
G37*
G36*
G01X1370912Y1615794D02*
X1374312D01*
G02Y1612790I0J-1502D01*
G01X1370912D01*
G02Y1615794I0J1502D01*
G37*
G36*
G01X1269132Y1591596D02*
X1272532D01*
G02Y1588592I0J-1502D01*
G01X1269132D01*
G02Y1591596I0J1502D01*
G37*
G36*
G01X1238252Y1603882D02*
X1241652D01*
G02Y1600878I0J-1502D01*
G01X1238252D01*
G02Y1603882I0J1502D01*
G37*
G36*
G01X1353552Y1591596D02*
X1356952D01*
G02Y1588592I0J-1502D01*
G01X1353552D01*
G02Y1591596I0J1502D01*
G37*
G36*
G01X1214132Y1615794D02*
X1217532D01*
G02Y1612790I0J-1502D01*
G01X1214132D01*
G02Y1615794I0J1502D01*
G37*
G36*
G01X1226192Y1603882D02*
X1229592D01*
G02Y1600878I0J-1502D01*
G01X1226192D01*
G02Y1603882I0J1502D01*
G37*
G36*
G01X1208832Y1579684D02*
X1212232D01*
G02Y1576680I0J-1502D01*
G01X1208832D01*
G02Y1579684I0J1502D01*
G37*
G36*
G01Y1591596D02*
X1212232D01*
G02Y1588592I0J-1502D01*
G01X1208832D01*
G02Y1591596I0J1502D01*
G37*
G36*
G01X1341492Y1579684D02*
X1344892D01*
G02Y1576680I0J-1502D01*
G01X1341492D01*
G02Y1579684I0J1502D01*
G37*
G36*
G01X1250312Y1615794D02*
X1253712D01*
G02Y1612790I0J-1502D01*
G01X1250312D01*
G02Y1615794I0J1502D01*
G37*
G36*
G01X1232952Y1579684D02*
X1236352D01*
G02Y1576680I0J-1502D01*
G01X1232952D01*
G02Y1579684I0J1502D01*
G37*
G36*
G01Y1591596D02*
X1236352D01*
G02Y1588592I0J-1502D01*
G01X1232952D01*
G02Y1591596I0J1502D01*
G37*
G36*
G01X1196772Y1579684D02*
X1200172D01*
G02Y1576680I0J-1502D01*
G01X1196772D01*
G02Y1579684I0J1502D01*
G37*
G36*
G01X1257072D02*
X1260472D01*
G02Y1576680I0J-1502D01*
G01X1257072D01*
G02Y1579684I0J1502D01*
G37*
G36*
G01X1220892Y1591596D02*
X1224292D01*
G02Y1588592I0J-1502D01*
G01X1220892D01*
G02Y1591596I0J1502D01*
G37*
G36*
G01X1269132Y1579684D02*
X1272532D01*
G02Y1576680I0J-1502D01*
G01X1269132D01*
G02Y1579684I0J1502D01*
G37*
G36*
G01X1305312Y1591596D02*
X1308712D01*
G02Y1588592I0J-1502D01*
G01X1305312D01*
G02Y1591596I0J1502D01*
G37*
G36*
G01X1245012D02*
X1248412D01*
G02Y1588592I0J-1502D01*
G01X1245012D01*
G02Y1591596I0J1502D01*
G37*
G36*
G01X1250312Y1603882D02*
X1253712D01*
G02Y1600878I0J-1502D01*
G01X1250312D01*
G02Y1603882I0J1502D01*
G37*
G36*
G01X1317372Y1579684D02*
X1320772D01*
G02Y1576680I0J-1502D01*
G01X1317372D01*
G02Y1579684I0J1502D01*
G37*
G36*
G01X1358852Y1603882D02*
X1362252D01*
G02Y1600878I0J-1502D01*
G01X1358852D01*
G02Y1603882I0J1502D01*
G37*
G36*
G01X1202072D02*
X1205472D01*
G02Y1600878I0J-1502D01*
G01X1202072D01*
G02Y1603882I0J1502D01*
G37*
G36*
G01Y1615794D02*
X1205472D01*
G02Y1612790I0J-1502D01*
G01X1202072D01*
G02Y1615794I0J1502D01*
G37*
G36*
G01X1322672Y1603882D02*
X1326072D01*
G02Y1600878I0J-1502D01*
G01X1322672D01*
G02Y1603882I0J1502D01*
G37*
G36*
G01X1310612D02*
X1314012D01*
G02Y1600878I0J-1502D01*
G01X1310612D01*
G02Y1603882I0J1502D01*
G37*
G36*
G01X1274432Y1615794D02*
X1277832D01*
G02Y1612790I0J-1502D01*
G01X1274432D01*
G02Y1615794I0J1502D01*
G37*
G36*
G01X1329432Y1579684D02*
X1332832D01*
G02Y1576680I0J-1502D01*
G01X1329432D01*
G02Y1579684I0J1502D01*
G37*
G36*
G01X1346792Y1603882D02*
X1350192D01*
G02Y1600878I0J-1502D01*
G01X1346792D01*
G02Y1603882I0J1502D01*
G37*
G36*
G01X1317372Y1591596D02*
X1320772D01*
G02Y1588592I0J-1502D01*
G01X1317372D01*
G02Y1591596I0J1502D01*
G37*
G36*
G01X1329432D02*
X1332832D01*
G02Y1588592I0J-1502D01*
G01X1329432D01*
G02Y1591596I0J1502D01*
G37*
G36*
G01X1322672Y1615794D02*
X1326072D01*
G02Y1612790I0J-1502D01*
G01X1322672D01*
G02Y1615794I0J1502D01*
G37*
G36*
G01X1281192Y1591596D02*
X1284592D01*
G02Y1588592I0J-1502D01*
G01X1281192D01*
G02Y1591596I0J1502D01*
G37*
G36*
G01X1196772D02*
X1200172D01*
G02Y1588592I0J-1502D01*
G01X1196772D01*
G02Y1591596I0J1502D01*
G37*
G36*
G01X1226192Y1615794D02*
X1229592D01*
G02Y1612790I0J-1502D01*
G01X1226192D01*
G02Y1615794I0J1502D01*
G37*
G36*
G01X1293252Y1579684D02*
X1296652D01*
G02Y1576680I0J-1502D01*
G01X1293252D01*
G02Y1579684I0J1502D01*
G37*
G36*
G01X1298552Y1615794D02*
X1301952D01*
G02Y1612790I0J-1502D01*
G01X1298552D01*
G02Y1615794I0J1502D01*
G37*
G36*
G01X1281192Y1579684D02*
X1284592D01*
G02Y1576680I0J-1502D01*
G01X1281192D01*
G02Y1579684I0J1502D01*
G37*
G36*
G01X1245012D02*
X1248412D01*
G02Y1576680I0J-1502D01*
G01X1245012D01*
G02Y1579684I0J1502D01*
G37*
G36*
G01X1257072Y1591596D02*
X1260472D01*
G02Y1588592I0J-1502D01*
G01X1257072D01*
G02Y1591596I0J1502D01*
G37*
G36*
G01X1274432Y1603882D02*
X1277832D01*
G02Y1600878I0J-1502D01*
G01X1274432D01*
G02Y1603882I0J1502D01*
G37*
G36*
G01X1238252Y1615794D02*
X1241652D01*
G02Y1612790I0J-1502D01*
G01X1238252D01*
G02Y1615794I0J1502D01*
G37*
G36*
G01X1474516Y730492D02*
G02X1473515Y728758I-2002J0D01*
G01X1469877Y726657D01*
G02X1468878Y726390I-999J1736D01*
G01X1468876D01*
G02X1466874Y728392I0J2002D01*
G02X1467875Y730126I2002J0D01*
G01X1471513Y732227D01*
G02X1472512Y732494I999J-1736D01*
G01X1472514D01*
G02X1474516Y730492I0J-2002D01*
G37*
G36*
G01X1477716Y717492D02*
G02X1476715Y715758I-2002J0D01*
G01X1473077Y713657D01*
G02X1472078Y713390I-999J1736D01*
G01X1472076D01*
G02X1470074Y715392I0J2002D01*
G02X1471075Y717126I2002J0D01*
G01X1474713Y719227D01*
G02X1475712Y719494I999J-1736D01*
G01X1475714D01*
G02X1477716Y717492I0J-2002D01*
G37*
G36*
G01Y702992D02*
G02X1476715Y701258I-2002J0D01*
G01X1473077Y699157D01*
G02X1472078Y698890I-999J1736D01*
G01X1472076D01*
G02X1470074Y700892I0J2002D01*
G02X1471075Y702626I2002J0D01*
G01X1474713Y704727D01*
G02X1475712Y704994I999J-1736D01*
G01X1475714D01*
G02X1477716Y702992I0J-2002D01*
G37*
G36*
G01Y688492D02*
G02X1476715Y686758I-2002J0D01*
G01X1473077Y684657D01*
G02X1472078Y684390I-999J1736D01*
G01X1472076D01*
G02X1470074Y686392I0J2002D01*
G02X1471075Y688126I2002J0D01*
G01X1474713Y690227D01*
G02X1475712Y690494I999J-1736D01*
G01X1475714D01*
G02X1477716Y688492I0J-2002D01*
G37*
G36*
G01Y673992D02*
G02X1476715Y672258I-2002J0D01*
G01X1473077Y670157D01*
G02X1472078Y669890I-999J1736D01*
G01X1472076D01*
G02X1470074Y671892I0J2002D01*
G02X1471075Y673626I2002J0D01*
G01X1474713Y675727D01*
G02X1475712Y675994I999J-1736D01*
G01X1475714D01*
G02X1477716Y673992I0J-2002D01*
G37*
G36*
G01Y659492D02*
G02X1476715Y657758I-2002J0D01*
G01X1473077Y655657D01*
G02X1472078Y655390I-999J1736D01*
G01X1472076D01*
G02X1470074Y657392I0J2002D01*
G02X1471075Y659126I2002J0D01*
G01X1474713Y661227D01*
G02X1475712Y661494I999J-1736D01*
G01X1475714D01*
G02X1477716Y659492I0J-2002D01*
G37*
G36*
G01X1455174Y716992D02*
G02X1457176Y718994I2002J0D01*
G01X1457178D01*
G02X1458177Y718727I0J-2003D01*
G01X1461815Y716626D01*
G02X1462816Y714892I-1001J-1734D01*
G02X1460814Y712890I-2002J0D01*
G01X1460812D01*
G02X1459813Y713157I0J2003D01*
G01X1456175Y715258D01*
G02X1455174Y716992I1001J1734D01*
G37*
G36*
G01Y704992D02*
G02X1457176Y706994I2002J0D01*
G01X1457178D01*
G02X1458177Y706727I0J-2003D01*
G01X1461815Y704626D01*
G02X1462816Y702892I-1001J-1734D01*
G02X1460814Y700890I-2002J0D01*
G01X1460812D01*
G02X1459813Y701157I0J2003D01*
G01X1456175Y703258D01*
G02X1455174Y704992I1001J1734D01*
G37*
G36*
G01Y692992D02*
G02X1457176Y694994I2002J0D01*
G01X1457178D01*
G02X1458177Y694727I0J-2003D01*
G01X1461815Y692626D01*
G02X1462816Y690892I-1001J-1734D01*
G02X1460814Y688890I-2002J0D01*
G01X1460812D01*
G02X1459813Y689157I0J2003D01*
G01X1456175Y691258D01*
G02X1455174Y692992I1001J1734D01*
G37*
G36*
G01Y680992D02*
G02X1457176Y682994I2002J0D01*
G01X1457178D01*
G02X1458177Y682727I0J-2003D01*
G01X1461815Y680626D01*
G02X1462816Y678892I-1001J-1734D01*
G02X1460814Y676890I-2002J0D01*
G01X1460812D01*
G02X1459813Y677157I0J2003D01*
G01X1456175Y679258D01*
G02X1455174Y680992I1001J1734D01*
G37*
G36*
G01Y668992D02*
G02X1457176Y670994I2002J0D01*
G01X1457178D01*
G02X1458177Y670727I0J-2003D01*
G01X1461815Y668626D01*
G02X1462816Y666892I-1001J-1734D01*
G02X1460814Y664890I-2002J0D01*
G01X1460812D01*
G02X1459813Y665157I0J2003D01*
G01X1456175Y667258D01*
G02X1455174Y668992I1001J1734D01*
G37*
G36*
G01Y656992D02*
G02X1457176Y658994I2002J0D01*
G01X1457178D01*
G02X1458177Y658727I0J-2003D01*
G01X1461815Y656626D01*
G02X1462816Y654892I-1001J-1734D01*
G02X1460814Y652890I-2002J0D01*
G01X1460812D01*
G02X1459813Y653157I0J2003D01*
G01X1456175Y655258D01*
G02X1455174Y656992I1001J1734D01*
G37*
G36*
G01X1390978Y737198D02*
G02X1389977Y735464I-2002J0D01*
G01X1386339Y733363D01*
G02X1385340Y733096I-999J1736D01*
G01X1385338D01*
G02X1383336Y735098I0J2002D01*
G02X1384337Y736832I2002J0D01*
G01X1387975Y738933D01*
G02X1388974Y739200I999J-1736D01*
G01X1388976D01*
G02X1390978Y737198I0J-2002D01*
G37*
G36*
G01X1395208Y722735D02*
G02X1394207Y721001I-2002J0D01*
G01X1390569Y718900D01*
G02X1389570Y718632I-1001J1735D01*
G01X1389568D01*
G02X1387566Y720635I1J2003D01*
G02X1388567Y722369I2002J0D01*
G01X1392205Y724470D01*
G02X1393204Y724738I1001J-1735D01*
G01X1393206D01*
G02X1395208Y722735I-1J-2003D01*
G37*
G36*
G01Y693708D02*
G02X1394207Y691974I-2002J0D01*
G01X1390569Y689873D01*
G02X1389570Y689606I-999J1736D01*
G01X1389568D01*
G02X1387566Y691608I0J2002D01*
G02X1388567Y693342I2002J0D01*
G01X1392205Y695443D01*
G02X1393204Y695710I999J-1736D01*
G01X1393206D01*
G02X1395208Y693708I0J-2002D01*
G37*
G36*
G01Y708208D02*
G02X1394207Y706474I-2002J0D01*
G01X1390569Y704373D01*
G02X1389570Y704106I-999J1736D01*
G01X1389568D01*
G02X1387566Y706108I0J2002D01*
G02X1388567Y707842I2002J0D01*
G01X1392205Y709943D01*
G02X1393204Y710210I999J-1736D01*
G01X1393206D01*
G02X1395208Y708208I0J-2002D01*
G37*
G36*
G01Y679208D02*
G02X1394207Y677474I-2002J0D01*
G01X1390569Y675373D01*
G02X1389570Y675106I-999J1736D01*
G01X1389568D01*
G02X1387566Y677108I0J2002D01*
G02X1388567Y678842I2002J0D01*
G01X1392205Y680943D01*
G02X1393204Y681210I999J-1736D01*
G01X1393206D01*
G02X1395208Y679208I0J-2002D01*
G37*
G36*
G01Y664708D02*
G02X1394207Y662974I-2002J0D01*
G01X1390569Y660873D01*
G02X1389570Y660606I-999J1736D01*
G01X1389568D01*
G02X1387566Y662608I0J2002D01*
G02X1388567Y664342I2002J0D01*
G01X1392205Y666443D01*
G02X1393204Y666710I999J-1736D01*
G01X1393206D01*
G02X1395208Y664708I0J-2002D01*
G37*
G36*
G01X1372666Y719708D02*
G02X1374668Y721710I2002J0D01*
G01X1374670D01*
G02X1375669Y721443I0J-2003D01*
G01X1379307Y719342D01*
G02X1380308Y717608I-1001J-1734D01*
G02X1378306Y715606I-2002J0D01*
G01X1378304D01*
G02X1377305Y715873I0J2003D01*
G01X1373667Y717974D01*
G02X1372666Y719708I1001J1734D01*
G37*
G36*
G01Y695708D02*
G02X1374668Y697710I2002J0D01*
G01X1374670D01*
G02X1375669Y697443I0J-2003D01*
G01X1379307Y695342D01*
G02X1380308Y693608I-1001J-1734D01*
G02X1378306Y691606I-2002J0D01*
G01X1378304D01*
G02X1377305Y691873I0J2003D01*
G01X1373667Y693974D01*
G02X1372666Y695708I1001J1734D01*
G37*
G36*
G01Y707708D02*
G02X1374668Y709710I2002J0D01*
G01X1374670D01*
G02X1375669Y709443I0J-2003D01*
G01X1379307Y707342D01*
G02X1380308Y705608I-1001J-1734D01*
G02X1378306Y703606I-2002J0D01*
G01X1378304D01*
G02X1377305Y703873I0J2003D01*
G01X1373667Y705974D01*
G02X1372666Y707708I1001J1734D01*
G37*
G36*
G01Y683708D02*
G02X1374668Y685710I2002J0D01*
G01X1374670D01*
G02X1375669Y685443I0J-2003D01*
G01X1379307Y683342D01*
G02X1380308Y681608I-1001J-1734D01*
G02X1378306Y679606I-2002J0D01*
G01X1378304D01*
G02X1377305Y679873I0J2003D01*
G01X1373667Y681974D01*
G02X1372666Y683708I1001J1734D01*
G37*
G36*
G01Y671708D02*
G02X1374668Y673710I2002J0D01*
G01X1374670D01*
G02X1375669Y673443I0J-2003D01*
G01X1379307Y671342D01*
G02X1380308Y669608I-1001J-1734D01*
G02X1378306Y667606I-2002J0D01*
G01X1378304D01*
G02X1377305Y667873I0J2003D01*
G01X1373667Y669974D01*
G02X1372666Y671708I1001J1734D01*
G37*
G36*
G01Y659708D02*
G02X1374668Y661710I2002J0D01*
G01X1374670D01*
G02X1375669Y661443I0J-2003D01*
G01X1379307Y659342D01*
G02X1380308Y657608I-1001J-1734D01*
G02X1378306Y655606I-2002J0D01*
G01X1378304D01*
G02X1377305Y655873I0J2003D01*
G01X1373667Y657974D01*
G02X1372666Y659708I1001J1734D01*
G37*
G36*
G01X146312Y1571028D02*
X149712D01*
G02Y1568022I0J-1503D01*
G01X146312D01*
G02Y1571028I0J1503D01*
G37*
G36*
G01X1360544Y230631D02*
X1359625Y231551D01*
G02Y231979I214J214D01*
G01X1360332Y232686D01*
G02X1360760I214J-214D01*
G01X1361680Y231767D01*
G02Y231338I-214J-215D01*
G01X1360973Y230631D01*
G02X1360544I-214J214D01*
G37*
G36*
G01X1362029Y232116D02*
X1361110Y233035D01*
G02Y233464I214J214D01*
G01X1361817Y234171D01*
G02X1362245I214J-214D01*
G01X1363165Y233252D01*
G02Y232823I-214J-215D01*
G01X1362458Y232116D01*
G02X1362029I-215J214D01*
G37*
G36*
G01X1364575Y229571D02*
X1363656Y230490D01*
G02Y230918I214J214D01*
G01X1364363Y231625D01*
G02X1364791I214J-214D01*
G01X1365710Y230706D01*
G02Y230278I-214J-214D01*
G01X1365003Y229571D01*
G02X1364575I-214J214D01*
G37*
G36*
G01X1363090Y228086D02*
X1362171Y229005D01*
G02Y229433I214J214D01*
G01X1362878Y230140D01*
G02X1363306I214J-214D01*
G01X1364225Y229221D01*
G02Y228793I-214J-214D01*
G01X1363518Y228086D01*
G02X1363090I-214J214D01*
G37*
G36*
G01X1701934Y76800D02*
X1705334D01*
G02Y73794I0J-1503D01*
G01X1701934D01*
G02Y76800I0J1503D01*
G37*
G36*
G01X1690934Y70800D02*
X1694334D01*
G02Y67794I0J-1503D01*
G01X1690934D01*
G02Y70800I0J1503D01*
G37*
G36*
G01X1679934Y76800D02*
X1683334D01*
G02Y73794I0J-1503D01*
G01X1679934D01*
G02Y76800I0J1503D01*
G37*
G36*
G01X1657800D02*
X1661200D01*
G02Y73794I0J-1503D01*
G01X1657800D01*
G02Y76800I0J1503D01*
G37*
G36*
G01X1668800Y70800D02*
X1672200D01*
G02Y67794I0J-1503D01*
G01X1668800D01*
G02Y70800I0J1503D01*
G37*
G36*
G01X1646800D02*
X1650200D01*
G02Y67794I0J-1503D01*
G01X1646800D01*
G02Y70800I0J1503D01*
G37*
G36*
G01X1635800Y76800D02*
X1639200D01*
G02Y73794I0J-1503D01*
G01X1635800D01*
G02Y76800I0J1503D01*
G37*
G36*
G01X1612596D02*
X1615996D01*
G02Y73794I0J-1503D01*
G01X1612596D01*
G02Y76800I0J1503D01*
G37*
G36*
G01X1623596Y70800D02*
X1626996D01*
G02Y67794I0J-1503D01*
G01X1623596D01*
G02Y70800I0J1503D01*
G37*
G36*
G01X1601596D02*
X1604996D01*
G02Y67794I0J-1503D01*
G01X1601596D01*
G02Y70800I0J1503D01*
G37*
G36*
G01X1590596Y76800D02*
X1593996D01*
G02Y73794I0J-1503D01*
G01X1590596D01*
G02Y76800I0J1503D01*
G37*
G36*
G01X1579596Y70800D02*
X1582996D01*
G02Y67794I0J-1503D01*
G01X1579596D01*
G02Y70800I0J1503D01*
G37*
G36*
G01X1568596Y76800D02*
X1571996D01*
G02Y73794I0J-1503D01*
G01X1568596D01*
G02Y76800I0J1503D01*
G37*
G36*
G01X1546596D02*
X1549996D01*
G02Y73794I0J-1503D01*
G01X1546596D01*
G02Y76800I0J1503D01*
G37*
G36*
G01X1557596Y70800D02*
X1560996D01*
G02Y67794I0J-1503D01*
G01X1557596D01*
G02Y70800I0J1503D01*
G37*
G36*
G01X1535596D02*
X1538996D01*
G02Y67794I0J-1503D01*
G01X1535596D01*
G02Y70800I0J1503D01*
G37*
G36*
G01X230895Y73838D02*
X227495D01*
G02Y76842I0J1502D01*
G01X230895D01*
G02Y73838I0J-1502D01*
G37*
G36*
G01X219895Y67838D02*
X216495D01*
G02Y70842I0J1502D01*
G01X219895D01*
G02Y67838I0J-1502D01*
G37*
G36*
G01X208895Y73838D02*
X205495D01*
G02Y76842I0J1502D01*
G01X208895D01*
G02Y73838I0J-1502D01*
G37*
G36*
G01X194361Y70842D02*
X197761D01*
G02Y67838I0J-1502D01*
G01X194361D01*
G02Y70842I0J1502D01*
G37*
G36*
G01X183361Y76842D02*
X186761D01*
G02Y73838I0J-1502D01*
G01X183361D01*
G02Y76842I0J1502D01*
G37*
G36*
G01X161361D02*
X164761D01*
G02Y73838I0J-1502D01*
G01X161361D01*
G02Y76842I0J1502D01*
G37*
G36*
G01X172361Y70842D02*
X175761D01*
G02Y67838I0J-1502D01*
G01X172361D01*
G02Y70842I0J1502D01*
G37*
G36*
G01X149157D02*
X152557D01*
G02Y67838I0J-1502D01*
G01X149157D01*
G02Y70842I0J1502D01*
G37*
G36*
G01X138157Y76842D02*
X141557D01*
G02Y73838I0J-1502D01*
G01X138157D01*
G02Y76842I0J1502D01*
G37*
G36*
G01X116157D02*
X119557D01*
G02Y73838I0J-1502D01*
G01X116157D01*
G02Y76842I0J1502D01*
G37*
G36*
G01X127157Y70842D02*
X130557D01*
G02Y67838I0J-1502D01*
G01X127157D01*
G02Y70842I0J1502D01*
G37*
G36*
G01X105157D02*
X108557D01*
G02Y67838I0J-1502D01*
G01X105157D01*
G02Y70842I0J1502D01*
G37*
G36*
G01X94157Y76842D02*
X97557D01*
G02Y73838I0J-1502D01*
G01X94157D01*
G02Y76842I0J1502D01*
G37*
G36*
G01X83157Y70842D02*
X86557D01*
G02Y67838I0J-1502D01*
G01X83157D01*
G02Y70842I0J1502D01*
G37*
G36*
G01X72157Y76842D02*
X75557D01*
G02Y73838I0J-1502D01*
G01X72157D01*
G02Y76842I0J1502D01*
G37*
G36*
G01X61157Y70842D02*
X64557D01*
G02Y67838I0J-1502D01*
G01X61157D01*
G02Y70842I0J1502D01*
G37*
G36*
G01X1619075Y1579684D02*
X1622475D01*
G02Y1576680I0J-1502D01*
G01X1619075D01*
G02Y1579684I0J1502D01*
G37*
G36*
G01X326857Y1603882D02*
X330257D01*
G02Y1600878I0J-1502D01*
G01X326857D01*
G02Y1603882I0J1502D01*
G37*
G36*
G01X363037Y1615794D02*
X366437D01*
G02Y1612790I0J-1502D01*
G01X363037D01*
G02Y1615794I0J1502D01*
G37*
G36*
G01X545411Y1579684D02*
X548811D01*
G02Y1576680I0J-1502D01*
G01X545411D01*
G02Y1579684I0J1502D01*
G37*
G36*
G01Y1591596D02*
X548811D01*
G02Y1588592I0J-1502D01*
G01X545411D01*
G02Y1591596I0J1502D01*
G37*
G36*
G01X1377672D02*
X1381072D01*
G02Y1588592I0J-1502D01*
G01X1377672D01*
G02Y1591596I0J1502D01*
G37*
G36*
G01X533351D02*
X536751D01*
G02Y1588592I0J-1502D01*
G01X533351D01*
G02Y1591596I0J1502D01*
G37*
G36*
G01Y1579684D02*
X536751D01*
G02Y1576680I0J-1502D01*
G01X533351D01*
G02Y1579684I0J1502D01*
G37*
G36*
G01X1594955Y1591596D02*
X1598355D01*
G02Y1588592I0J-1502D01*
G01X1594955D01*
G02Y1591596I0J1502D01*
G37*
G36*
G01X581591D02*
X584991D01*
G02Y1588592I0J-1502D01*
G01X581591D01*
G02Y1591596I0J1502D01*
G37*
G36*
G01Y1579684D02*
X584991D01*
G02Y1576680I0J-1502D01*
G01X581591D01*
G02Y1579684I0J1502D01*
G37*
G36*
G01X1594955D02*
X1598355D01*
G02Y1576680I0J-1502D01*
G01X1594955D01*
G02Y1579684I0J1502D01*
G37*
G36*
G01X605711Y1591596D02*
X609111D01*
G02Y1588592I0J-1502D01*
G01X605711D01*
G02Y1591596I0J1502D01*
G37*
G36*
G01X333617Y1579684D02*
X337017D01*
G02Y1576680I0J-1502D01*
G01X333617D01*
G02Y1579684I0J1502D01*
G37*
G36*
G01X345677D02*
X349077D01*
G02Y1576680I0J-1502D01*
G01X345677D01*
G02Y1579684I0J1502D01*
G37*
G36*
G01X617771D02*
X621171D01*
G02Y1576680I0J-1502D01*
G01X617771D01*
G02Y1579684I0J1502D01*
G37*
G36*
G01Y1591596D02*
X621171D01*
G02Y1588592I0J-1502D01*
G01X617771D01*
G02Y1591596I0J1502D01*
G37*
G36*
G01X629831Y1579684D02*
X633231D01*
G02Y1576680I0J-1502D01*
G01X629831D01*
G02Y1579684I0J1502D01*
G37*
G36*
G01X1582895D02*
X1586295D01*
G02Y1576680I0J-1502D01*
G01X1582895D01*
G02Y1579684I0J1502D01*
G37*
G36*
G01X1570835D02*
X1574235D01*
G02Y1576680I0J-1502D01*
G01X1570835D01*
G02Y1579684I0J1502D01*
G37*
G36*
G01X1558775D02*
X1562175D01*
G02Y1576680I0J-1502D01*
G01X1558775D01*
G02Y1579684I0J1502D01*
G37*
G36*
G01X321557D02*
X324957D01*
G02Y1576680I0J-1502D01*
G01X321557D01*
G02Y1579684I0J1502D01*
G37*
G36*
G01X278617Y1603882D02*
X282017D01*
G02Y1600878I0J-1502D01*
G01X278617D01*
G02Y1603882I0J1502D01*
G37*
G36*
G01X1534655Y1591596D02*
X1538055D01*
G02Y1588592I0J-1502D01*
G01X1534655D01*
G02Y1591596I0J1502D01*
G37*
G36*
G01Y1579684D02*
X1538055D01*
G02Y1576680I0J-1502D01*
G01X1534655D01*
G02Y1579684I0J1502D01*
G37*
G36*
G01X1510535Y1591596D02*
X1513935D01*
G02Y1588592I0J-1502D01*
G01X1510535D01*
G02Y1591596I0J1502D01*
G37*
G36*
G01X1522595D02*
X1525995D01*
G02Y1588592I0J-1502D01*
G01X1522595D01*
G02Y1591596I0J1502D01*
G37*
G36*
G01X309497Y1579684D02*
X312897D01*
G02Y1576680I0J-1502D01*
G01X309497D01*
G02Y1579684I0J1502D01*
G37*
G36*
G01X302737Y1603882D02*
X306137D01*
G02Y1600878I0J-1502D01*
G01X302737D01*
G02Y1603882I0J1502D01*
G37*
G36*
G01X1498475Y1579684D02*
X1501875D01*
G02Y1576680I0J-1502D01*
G01X1498475D01*
G02Y1579684I0J1502D01*
G37*
G36*
G01X314797Y1615794D02*
X318197D01*
G02Y1612790I0J-1502D01*
G01X314797D01*
G02Y1615794I0J1502D01*
G37*
G36*
G01X278617D02*
X282017D01*
G02Y1612790I0J-1502D01*
G01X278617D01*
G02Y1615794I0J1502D01*
G37*
G36*
G01X497171Y1591596D02*
X500571D01*
G02Y1588592I0J-1502D01*
G01X497171D01*
G02Y1591596I0J1502D01*
G37*
G36*
G01X509231D02*
X512631D01*
G02Y1588592I0J-1502D01*
G01X509231D01*
G02Y1591596I0J1502D01*
G37*
G36*
G01Y1579684D02*
X512631D01*
G02Y1576680I0J-1502D01*
G01X509231D01*
G02Y1579684I0J1502D01*
G37*
G36*
G01X1486415Y1591596D02*
X1489815D01*
G02Y1588592I0J-1502D01*
G01X1486415D01*
G02Y1591596I0J1502D01*
G37*
G36*
G01Y1579684D02*
X1489815D01*
G02Y1576680I0J-1502D01*
G01X1486415D01*
G02Y1579684I0J1502D01*
G37*
G36*
G01X321557Y1591596D02*
X324957D01*
G02Y1588592I0J-1502D01*
G01X321557D01*
G02Y1591596I0J1502D01*
G37*
G36*
G01X1462295D02*
X1465695D01*
G02Y1588592I0J-1502D01*
G01X1462295D01*
G02Y1591596I0J1502D01*
G37*
G36*
G01X1474355D02*
X1477755D01*
G02Y1588592I0J-1502D01*
G01X1474355D01*
G02Y1591596I0J1502D01*
G37*
G36*
G01X641891Y1579684D02*
X645291D01*
G02Y1576680I0J-1502D01*
G01X641891D01*
G02Y1579684I0J1502D01*
G37*
G36*
G01Y1591596D02*
X645291D01*
G02Y1588592I0J-1502D01*
G01X641891D01*
G02Y1591596I0J1502D01*
G37*
G36*
G01X285377Y1579684D02*
X288777D01*
G02Y1576680I0J-1502D01*
G01X285377D01*
G02Y1579684I0J1502D01*
G37*
G36*
G01X1462295D02*
X1465695D01*
G02Y1576680I0J-1502D01*
G01X1462295D01*
G02Y1579684I0J1502D01*
G37*
G36*
G01X206257Y1615794D02*
X209657D01*
G02Y1612790I0J-1502D01*
G01X206257D01*
G02Y1615794I0J1502D01*
G37*
G36*
G01X338917D02*
X342317D01*
G02Y1612790I0J-1502D01*
G01X338917D01*
G02Y1615794I0J1502D01*
G37*
G36*
G01X1474355Y1579684D02*
X1477755D01*
G02Y1576680I0J-1502D01*
G01X1474355D01*
G02Y1579684I0J1502D01*
G37*
G36*
G01X261257D02*
X264657D01*
G02Y1576680I0J-1502D01*
G01X261257D01*
G02Y1579684I0J1502D01*
G37*
G36*
G01X485111D02*
X488511D01*
G02Y1576680I0J-1502D01*
G01X485111D01*
G02Y1579684I0J1502D01*
G37*
G36*
G01Y1591596D02*
X488511D01*
G02Y1588592I0J-1502D01*
G01X485111D01*
G02Y1591596I0J1502D01*
G37*
G36*
G01X338917Y1603882D02*
X342317D01*
G02Y1600878I0J-1502D01*
G01X338917D01*
G02Y1603882I0J1502D01*
G37*
G36*
G01X1648495Y1615794D02*
X1651895D01*
G02Y1612790I0J-1502D01*
G01X1648495D01*
G02Y1615794I0J1502D01*
G37*
G36*
G01Y1603882D02*
X1651895D01*
G02Y1600878I0J-1502D01*
G01X1648495D01*
G02Y1603882I0J1502D01*
G37*
G36*
G01X1624375Y1615794D02*
X1627775D01*
G02Y1612790I0J-1502D01*
G01X1624375D01*
G02Y1615794I0J1502D01*
G37*
G36*
G01X266557D02*
X269957D01*
G02Y1612790I0J-1502D01*
G01X266557D01*
G02Y1615794I0J1502D01*
G37*
G36*
G01X254497Y1603882D02*
X257897D01*
G02Y1600878I0J-1502D01*
G01X254497D01*
G02Y1603882I0J1502D01*
G37*
G36*
G01X653951Y1591596D02*
X657351D01*
G02Y1588592I0J-1502D01*
G01X653951D01*
G02Y1591596I0J1502D01*
G37*
G36*
G01Y1579684D02*
X657351D01*
G02Y1576680I0J-1502D01*
G01X653951D01*
G02Y1579684I0J1502D01*
G37*
G36*
G01X369797Y1591596D02*
X373197D01*
G02Y1588592I0J-1502D01*
G01X369797D01*
G02Y1591596I0J1502D01*
G37*
G36*
G01X1636435Y1603882D02*
X1639835D01*
G02Y1600878I0J-1502D01*
G01X1636435D01*
G02Y1603882I0J1502D01*
G37*
G36*
G01X266557D02*
X269957D01*
G02Y1600878I0J-1502D01*
G01X266557D01*
G02Y1603882I0J1502D01*
G37*
G36*
G01X1624375D02*
X1627775D01*
G02Y1600878I0J-1502D01*
G01X1624375D01*
G02Y1603882I0J1502D01*
G37*
G36*
G01X254497Y1615794D02*
X257897D01*
G02Y1612790I0J-1502D01*
G01X254497D01*
G02Y1615794I0J1502D01*
G37*
G36*
G01X194197Y1603882D02*
X197597D01*
G02Y1600878I0J-1502D01*
G01X194197D01*
G02Y1603882I0J1502D01*
G37*
G36*
G01X242437D02*
X245837D01*
G02Y1600878I0J-1502D01*
G01X242437D01*
G02Y1603882I0J1502D01*
G37*
G36*
G01X1612315D02*
X1615715D01*
G02Y1600878I0J-1502D01*
G01X1612315D01*
G02Y1603882I0J1502D01*
G37*
G36*
G01Y1615794D02*
X1615715D01*
G02Y1612790I0J-1502D01*
G01X1612315D01*
G02Y1615794I0J1502D01*
G37*
G36*
G01X230377D02*
X233777D01*
G02Y1612790I0J-1502D01*
G01X230377D01*
G02Y1615794I0J1502D01*
G37*
G36*
G01X521291Y1579684D02*
X524691D01*
G02Y1576680I0J-1502D01*
G01X521291D01*
G02Y1579684I0J1502D01*
G37*
G36*
G01Y1591596D02*
X524691D01*
G02Y1588592I0J-1502D01*
G01X521291D01*
G02Y1591596I0J1502D01*
G37*
G36*
G01X497171Y1579684D02*
X500571D01*
G02Y1576680I0J-1502D01*
G01X497171D01*
G02Y1579684I0J1502D01*
G37*
G36*
G01X593651D02*
X597051D01*
G02Y1576680I0J-1502D01*
G01X593651D01*
G02Y1579684I0J1502D01*
G37*
G36*
G01Y1591596D02*
X597051D01*
G02Y1588592I0J-1502D01*
G01X593651D01*
G02Y1591596I0J1502D01*
G37*
G36*
G01X1600255Y1603882D02*
X1603655D01*
G02Y1600878I0J-1502D01*
G01X1600255D01*
G02Y1603882I0J1502D01*
G37*
G36*
G01Y1615794D02*
X1603655D01*
G02Y1612790I0J-1502D01*
G01X1600255D01*
G02Y1615794I0J1502D01*
G37*
G36*
G01X557471Y1579684D02*
X560871D01*
G02Y1576680I0J-1502D01*
G01X557471D01*
G02Y1579684I0J1502D01*
G37*
G36*
G01X569531D02*
X572931D01*
G02Y1576680I0J-1502D01*
G01X569531D01*
G02Y1579684I0J1502D01*
G37*
G36*
G01Y1591596D02*
X572931D01*
G02Y1588592I0J-1502D01*
G01X569531D01*
G02Y1591596I0J1502D01*
G37*
G36*
G01X557471D02*
X560871D01*
G02Y1588592I0J-1502D01*
G01X557471D01*
G02Y1591596I0J1502D01*
G37*
G36*
G01X333617D02*
X337017D01*
G02Y1588592I0J-1502D01*
G01X333617D01*
G02Y1591596I0J1502D01*
G37*
G36*
G01X345677D02*
X349077D01*
G02Y1588592I0J-1502D01*
G01X345677D01*
G02Y1591596I0J1502D01*
G37*
G36*
G01X1607015Y1579684D02*
X1610415D01*
G02Y1576680I0J-1502D01*
G01X1607015D01*
G02Y1579684I0J1502D01*
G37*
G36*
G01X1576135Y1615794D02*
X1579535D01*
G02Y1612790I0J-1502D01*
G01X1576135D01*
G02Y1615794I0J1502D01*
G37*
G36*
G01X314797Y1603882D02*
X318197D01*
G02Y1600878I0J-1502D01*
G01X314797D01*
G02Y1603882I0J1502D01*
G37*
G36*
G01X1576135D02*
X1579535D01*
G02Y1600878I0J-1502D01*
G01X1576135D01*
G02Y1603882I0J1502D01*
G37*
G36*
G01X261257Y1591596D02*
X264657D01*
G02Y1588592I0J-1502D01*
G01X261257D01*
G02Y1591596I0J1502D01*
G37*
G36*
G01X357737Y1579684D02*
X361137D01*
G02Y1576680I0J-1502D01*
G01X357737D01*
G02Y1579684I0J1502D01*
G37*
G36*
G01X1546715Y1591596D02*
X1550115D01*
G02Y1588592I0J-1502D01*
G01X1546715D01*
G02Y1591596I0J1502D01*
G37*
G36*
G01Y1579684D02*
X1550115D01*
G02Y1576680I0J-1502D01*
G01X1546715D01*
G02Y1579684I0J1502D01*
G37*
G36*
G01X326857Y1615794D02*
X330257D01*
G02Y1612790I0J-1502D01*
G01X326857D01*
G02Y1615794I0J1502D01*
G37*
G36*
G01X249197Y1591596D02*
X252597D01*
G02Y1588592I0J-1502D01*
G01X249197D01*
G02Y1591596I0J1502D01*
G37*
G36*
G01X309497D02*
X312897D01*
G02Y1588592I0J-1502D01*
G01X309497D01*
G02Y1591596I0J1502D01*
G37*
G36*
G01X1564075Y1603882D02*
X1567475D01*
G02Y1600878I0J-1502D01*
G01X1564075D01*
G02Y1603882I0J1502D01*
G37*
G36*
G01Y1615794D02*
X1567475D01*
G02Y1612790I0J-1502D01*
G01X1564075D01*
G02Y1615794I0J1502D01*
G37*
G36*
G01X1552015D02*
X1555415D01*
G02Y1612790I0J-1502D01*
G01X1552015D01*
G02Y1615794I0J1502D01*
G37*
G36*
G01X1503775D02*
X1507175D01*
G02Y1612790I0J-1502D01*
G01X1503775D01*
G02Y1615794I0J1502D01*
G37*
G36*
G01X1552015Y1603882D02*
X1555415D01*
G02Y1600878I0J-1502D01*
G01X1552015D01*
G02Y1603882I0J1502D01*
G37*
G36*
G01X629831Y1591596D02*
X633231D01*
G02Y1588592I0J-1502D01*
G01X629831D01*
G02Y1591596I0J1502D01*
G37*
G36*
G01X1377672Y1579684D02*
X1381072D01*
G02Y1576680I0J-1502D01*
G01X1377672D01*
G02Y1579684I0J1502D01*
G37*
G36*
G01X218317Y1603882D02*
X221717D01*
G02Y1600878I0J-1502D01*
G01X218317D01*
G02Y1603882I0J1502D01*
G37*
G36*
G01X206257D02*
X209657D01*
G02Y1600878I0J-1502D01*
G01X206257D01*
G02Y1603882I0J1502D01*
G37*
G36*
G01X1527895Y1615794D02*
X1531295D01*
G02Y1612790I0J-1502D01*
G01X1527895D01*
G02Y1615794I0J1502D01*
G37*
G36*
G01X200957Y1591596D02*
X204357D01*
G02Y1588592I0J-1502D01*
G01X200957D01*
G02Y1591596I0J1502D01*
G37*
G36*
G01X1631135D02*
X1634535D01*
G02Y1588592I0J-1502D01*
G01X1631135D01*
G02Y1591596I0J1502D01*
G37*
G36*
G01X1539955Y1615794D02*
X1543355D01*
G02Y1612790I0J-1502D01*
G01X1539955D01*
G02Y1615794I0J1502D01*
G37*
G36*
G01Y1603882D02*
X1543355D01*
G02Y1600878I0J-1502D01*
G01X1539955D01*
G02Y1603882I0J1502D01*
G37*
G36*
G01X1527895D02*
X1531295D01*
G02Y1600878I0J-1502D01*
G01X1527895D01*
G02Y1603882I0J1502D01*
G37*
G36*
G01X302737Y1615794D02*
X306137D01*
G02Y1612790I0J-1502D01*
G01X302737D01*
G02Y1615794I0J1502D01*
G37*
G36*
G01X1522595Y1579684D02*
X1525995D01*
G02Y1576680I0J-1502D01*
G01X1522595D01*
G02Y1579684I0J1502D01*
G37*
G36*
G01X1515835Y1615794D02*
X1519235D01*
G02Y1612790I0J-1502D01*
G01X1515835D01*
G02Y1615794I0J1502D01*
G37*
G36*
G01X1636435D02*
X1639835D01*
G02Y1612790I0J-1502D01*
G01X1636435D01*
G02Y1615794I0J1502D01*
G37*
G36*
G01X1498475Y1591596D02*
X1501875D01*
G02Y1588592I0J-1502D01*
G01X1498475D01*
G02Y1591596I0J1502D01*
G37*
G36*
G01X1643195D02*
X1646595D01*
G02Y1588592I0J-1502D01*
G01X1643195D01*
G02Y1591596I0J1502D01*
G37*
G36*
G01X1515835Y1603882D02*
X1519235D01*
G02Y1600878I0J-1502D01*
G01X1515835D01*
G02Y1603882I0J1502D01*
G37*
G36*
G01X357737Y1591596D02*
X361137D01*
G02Y1588592I0J-1502D01*
G01X357737D01*
G02Y1591596I0J1502D01*
G37*
G36*
G01X194197Y1615794D02*
X197597D01*
G02Y1612790I0J-1502D01*
G01X194197D01*
G02Y1615794I0J1502D01*
G37*
G36*
G01X1510535Y1579684D02*
X1513935D01*
G02Y1576680I0J-1502D01*
G01X1510535D01*
G02Y1579684I0J1502D01*
G37*
G36*
G01X1570835Y1591596D02*
X1574235D01*
G02Y1588592I0J-1502D01*
G01X1570835D01*
G02Y1591596I0J1502D01*
G37*
G36*
G01X273317D02*
X276717D01*
G02Y1588592I0J-1502D01*
G01X273317D01*
G02Y1591596I0J1502D01*
G37*
G36*
G01Y1579684D02*
X276717D01*
G02Y1576680I0J-1502D01*
G01X273317D01*
G02Y1579684I0J1502D01*
G37*
G36*
G01X1491715Y1603882D02*
X1495115D01*
G02Y1600878I0J-1502D01*
G01X1491715D01*
G02Y1603882I0J1502D01*
G37*
G36*
G01Y1615794D02*
X1495115D01*
G02Y1612790I0J-1502D01*
G01X1491715D01*
G02Y1615794I0J1502D01*
G37*
G36*
G01X1631135Y1579684D02*
X1634535D01*
G02Y1576680I0J-1502D01*
G01X1631135D01*
G02Y1579684I0J1502D01*
G37*
G36*
G01X213017Y1591596D02*
X216417D01*
G02Y1588592I0J-1502D01*
G01X213017D01*
G02Y1591596I0J1502D01*
G37*
G36*
G01X188897Y1579684D02*
X192297D01*
G02Y1576680I0J-1502D01*
G01X188897D01*
G02Y1579684I0J1502D01*
G37*
G36*
G01X1503775Y1603882D02*
X1507175D01*
G02Y1600878I0J-1502D01*
G01X1503775D01*
G02Y1603882I0J1502D01*
G37*
G36*
G01X200957Y1579684D02*
X204357D01*
G02Y1576680I0J-1502D01*
G01X200957D01*
G02Y1579684I0J1502D01*
G37*
G36*
G01X605711D02*
X609111D01*
G02Y1576680I0J-1502D01*
G01X605711D01*
G02Y1579684I0J1502D01*
G37*
G36*
G01X1479655Y1603882D02*
X1483055D01*
G02Y1600878I0J-1502D01*
G01X1479655D01*
G02Y1603882I0J1502D01*
G37*
G36*
G01Y1615794D02*
X1483055D01*
G02Y1612790I0J-1502D01*
G01X1479655D01*
G02Y1615794I0J1502D01*
G37*
G36*
G01X249197Y1579684D02*
X252597D01*
G02Y1576680I0J-1502D01*
G01X249197D01*
G02Y1579684I0J1502D01*
G37*
G36*
G01X1467595Y1615794D02*
X1470995D01*
G02Y1612790I0J-1502D01*
G01X1467595D01*
G02Y1615794I0J1502D01*
G37*
G36*
G01Y1603882D02*
X1470995D01*
G02Y1600878I0J-1502D01*
G01X1467595D01*
G02Y1603882I0J1502D01*
G37*
G36*
G01X1558775Y1591596D02*
X1562175D01*
G02Y1588592I0J-1502D01*
G01X1558775D01*
G02Y1591596I0J1502D01*
G37*
G36*
G01X1643195Y1579684D02*
X1646595D01*
G02Y1576680I0J-1502D01*
G01X1643195D01*
G02Y1579684I0J1502D01*
G37*
G36*
G01X188897Y1591596D02*
X192297D01*
G02Y1588592I0J-1502D01*
G01X188897D01*
G02Y1591596I0J1502D01*
G37*
G36*
G01X1607015D02*
X1610415D01*
G02Y1588592I0J-1502D01*
G01X1607015D01*
G02Y1591596I0J1502D01*
G37*
G36*
G01X1582895D02*
X1586295D01*
G02Y1588592I0J-1502D01*
G01X1582895D01*
G02Y1591596I0J1502D01*
G37*
G36*
G01X225077Y1579684D02*
X228477D01*
G02Y1576680I0J-1502D01*
G01X225077D01*
G02Y1579684I0J1502D01*
G37*
G36*
G01Y1591596D02*
X228477D01*
G02Y1588592I0J-1502D01*
G01X225077D01*
G02Y1591596I0J1502D01*
G37*
G36*
G01X218317Y1615794D02*
X221717D01*
G02Y1612790I0J-1502D01*
G01X218317D01*
G02Y1615794I0J1502D01*
G37*
G36*
G01X290677Y1603882D02*
X294077D01*
G02Y1600878I0J-1502D01*
G01X290677D01*
G02Y1603882I0J1502D01*
G37*
G36*
G01Y1615794D02*
X294077D01*
G02Y1612790I0J-1502D01*
G01X290677D01*
G02Y1615794I0J1502D01*
G37*
G36*
G01X237137Y1579684D02*
X240537D01*
G02Y1576680I0J-1502D01*
G01X237137D01*
G02Y1579684I0J1502D01*
G37*
G36*
G01X213017D02*
X216417D01*
G02Y1576680I0J-1502D01*
G01X213017D01*
G02Y1579684I0J1502D01*
G37*
G36*
G01X230377Y1603882D02*
X233777D01*
G02Y1600878I0J-1502D01*
G01X230377D01*
G02Y1603882I0J1502D01*
G37*
G36*
G01X1619075Y1591596D02*
X1622475D01*
G02Y1588592I0J-1502D01*
G01X1619075D01*
G02Y1591596I0J1502D01*
G37*
G36*
G01X242437Y1615794D02*
X245837D01*
G02Y1612790I0J-1502D01*
G01X242437D01*
G02Y1615794I0J1502D01*
G37*
G36*
G01X369797Y1579684D02*
X373197D01*
G02Y1576680I0J-1502D01*
G01X369797D01*
G02Y1579684I0J1502D01*
G37*
G36*
G01X473051Y1591596D02*
X476451D01*
G02Y1588592I0J-1502D01*
G01X473051D01*
G02Y1591596I0J1502D01*
G37*
G36*
G01Y1579684D02*
X476451D01*
G02Y1576680I0J-1502D01*
G01X473051D01*
G02Y1579684I0J1502D01*
G37*
G36*
G01X1588195Y1603882D02*
X1591595D01*
G02Y1600878I0J-1502D01*
G01X1588195D01*
G02Y1603882I0J1502D01*
G37*
G36*
G01Y1615794D02*
X1591595D01*
G02Y1612790I0J-1502D01*
G01X1588195D01*
G02Y1615794I0J1502D01*
G37*
G36*
G01X542356Y88211D02*
G02X541986Y87848I-389J26D01*
G01X540778D01*
G02X540493Y87968I-2J395D01*
G02X540384Y88232I285J272D01*
G01Y92442D01*
X540387Y92468D01*
G02X540754Y92806I386J-51D01*
G01X541962D01*
G02X542247Y92686I2J-395D01*
G02X542356Y92422I-285J-272D01*
G01Y88211D01*
G37*
G36*
G01X146015Y1597278D02*
G02X145751Y1597168I-273J284D01*
G01X145188D01*
Y1597170D01*
X141540D01*
G02X141178Y1597539I27J388D01*
G01Y1598747D01*
X141177D01*
G02X141297Y1599032I395J2D01*
G02X141561Y1599142I273J-284D01*
G01X145771D01*
X145797Y1599138D01*
G02X146134Y1598771I-52J-386D01*
G01Y1597563D01*
X146135D01*
G02X146015Y1597278I-395J-2D01*
G37*
G36*
G01X141540Y1601680D02*
G02X141178Y1602050I27J388D01*
G01Y1603258D01*
X141177D01*
G02X141297Y1603543I395J2D01*
G02X141561Y1603652I272J-285D01*
G01X145771D01*
X145797Y1603649D01*
G02X146134Y1603282I-52J-386D01*
G01Y1602074D01*
X146135D01*
G02X146015Y1601789I-395J-2D01*
G02X145751Y1601680I-272J285D01*
G01X141540D01*
G37*
G36*
G01X546436Y88211D02*
G02X546066Y87848I-389J26D01*
G01X544858D01*
G02X544573Y87968I-2J395D01*
G02X544464Y88232I285J272D01*
G01Y92442D01*
X544467Y92468D01*
G02X544834Y92806I386J-51D01*
G01X546042D01*
G02X546327Y92686I2J-395D01*
G02X546436Y92422I-285J-272D01*
G01Y88211D01*
G37*
G36*
G01X61470Y86124D02*
X64870D01*
G02Y83120I0J-1502D01*
G01X61470D01*
G02Y86124I0J1502D01*
G37*
G36*
G01X297437Y1579684D02*
X300837D01*
G02Y1576680I0J-1502D01*
G01X297437D01*
G02Y1579684I0J1502D01*
G37*
G36*
G01X350977Y1615794D02*
X354377D01*
G02Y1612790I0J-1502D01*
G01X350977D01*
G02Y1615794I0J1502D01*
G37*
G36*
G01X375097Y1603882D02*
X378497D01*
G02Y1600878I0J-1502D01*
G01X375097D01*
G02Y1603882I0J1502D01*
G37*
G36*
G01Y1615794D02*
X378497D01*
G02Y1612790I0J-1502D01*
G01X375097D01*
G02Y1615794I0J1502D01*
G37*
G36*
G01X363037Y1603882D02*
X366437D01*
G02Y1600878I0J-1502D01*
G01X363037D01*
G02Y1603882I0J1502D01*
G37*
G36*
G01X360532Y883423D02*
G02X363126I1297J0D01*
G01Y883421D01*
G02X363054Y882994I-1298J-1D01*
G01X363024Y882908D01*
X363830Y881511D01*
X363920Y881494D01*
G02X364976Y880219I-242J-1275D01*
G02X362380I-1298J0D01*
G02X362453Y880647I1299J-1D01*
G01X362483Y880733D01*
X361677Y882131D01*
X361587Y882148D01*
G02X360532Y883423I243J1275D01*
G37*
G36*
G01X366080Y886625D02*
Y886627D01*
G02X368676I1298J0D01*
G02X367620Y885352I-1298J0D01*
G01X367530Y885335D01*
X366724Y883938D01*
X366754Y883852D01*
G02X366826Y883425I-1226J-426D01*
G01Y883423D01*
G02X364232I-1297J0D01*
G02X365287Y884698I1298J0D01*
G01X365377Y884715D01*
X366183Y886112D01*
X366153Y886198D01*
G02X366080Y886625I1225J429D01*
G37*
G36*
G01X1320456Y1124651D02*
G02X1323050I1297J0D01*
G02X1322978Y1124223I-1298J-2D01*
G01X1322948Y1124137D01*
X1323755Y1122739D01*
X1323845Y1122722D01*
G02X1324900Y1121447I-243J-1275D01*
G02X1322306I-1297J0D01*
G02X1322378Y1121875I1298J2D01*
G01X1322408Y1121961D01*
X1321601Y1123359D01*
X1321511Y1123376D01*
G02X1320456Y1124651I243J1275D01*
G37*
G36*
G01X1313541Y1122224D02*
X1315165D01*
G02X1316203Y1122744I1038J-776D01*
G02Y1120150I0J-1297D01*
G02X1315165Y1120670I0J1296D01*
G01X1313541D01*
G02X1312503Y1120150I-1038J776D01*
G02Y1122744I0J1297D01*
G02X1313541Y1122224I0J-1296D01*
G37*
G36*
G01X1336674Y883423D02*
G02X1339268I1297J0D01*
G01Y883421D01*
G02X1339196Y882994I-1298J-1D01*
G01X1339166Y882908D01*
X1339972Y881511D01*
X1340062Y881494D01*
G02X1341118Y880219I-242J-1275D01*
G02X1338522I-1298J0D01*
G02X1338595Y880647I1299J-1D01*
G01X1338625Y880733D01*
X1337819Y882131D01*
X1337729Y882148D01*
G02X1336674Y883423I243J1275D01*
G37*
G36*
G01X1505024Y886625D02*
Y886627D01*
G02X1507618I1297J0D01*
G02X1506563Y885352I-1298J0D01*
G01X1506473Y885335D01*
X1505666Y883937D01*
X1505696Y883851D01*
G02X1505768Y883423I-1226J-426D01*
G02X1503174I-1297J0D01*
G02X1504230Y884698I1298J0D01*
G01X1504320Y884715D01*
X1505126Y886112D01*
X1505096Y886198D01*
G02X1505024Y886625I1226J426D01*
G37*
G36*
G01X1505022Y873810D02*
G02X1507618I1298J0D01*
G01Y873808D01*
G02X1507545Y873381I-1298J2D01*
G01X1507515Y873295D01*
X1508321Y871898D01*
X1508411Y871881D01*
G02X1509468Y870606I-240J-1275D01*
G02X1506874I-1297J0D01*
G01Y870607D01*
G02X1506945Y871032I1297J2D01*
G01X1506975Y871118D01*
X1506168Y872518D01*
X1506078Y872535D01*
G02X1505022Y873810I242J1275D01*
G37*
G36*
G01X1499474Y883423D02*
G02X1502068I1297J0D01*
G01Y883421D01*
G02X1501996Y882994I-1298J-1D01*
G01X1501966Y882908D01*
X1502772Y881511D01*
X1502862Y881494D01*
G02X1503918Y880219I-242J-1275D01*
G02X1501324I-1297J0D01*
G01Y880221D01*
G02X1501396Y880646I1297J-1D01*
G01X1501426Y880732D01*
X1500619Y882131D01*
X1500529Y882148D01*
G02X1499474Y883423I243J1275D01*
G37*
G36*
G01X344314Y1124651D02*
G02X346908I1297J0D01*
G02X346836Y1124223I-1298J-2D01*
G01X346806Y1124137D01*
X347613Y1122739D01*
X347703Y1122722D01*
G02X348758Y1121447I-243J-1275D01*
G02X346164I-1297J0D01*
G02X346236Y1121875I1298J2D01*
G01X346266Y1121961D01*
X345459Y1123359D01*
X345369Y1123376D01*
G02X344314Y1124651I243J1275D01*
G37*
G36*
G01X350350Y1112612D02*
X351974D01*
G02X353012Y1113132I1038J-776D01*
G02Y1110536I0J-1298D01*
G02X351974Y1111056I0J1296D01*
G01X350350D01*
G02X349312Y1110536I-1038J776D01*
G02Y1113132I0J1298D01*
G02X350350Y1112612I0J-1296D01*
G37*
G36*
G01X337399Y1122224D02*
X339023D01*
G02X340061Y1122744I1038J-776D01*
G02Y1120150I0J-1297D01*
G02X339023Y1120670I0J1296D01*
G01X337399D01*
G02X336361Y1120150I-1038J776D01*
G02Y1122744I0J1297D01*
G02X337399Y1122224I0J-1296D01*
G37*
G36*
G01X1329274Y883423D02*
G02X1331868I1297J0D01*
G01Y883421D01*
G02X1331796Y882994I-1298J-1D01*
G01X1331766Y882908D01*
X1332572Y881511D01*
X1332662Y881494D01*
G02X1333718Y880219I-242J-1275D01*
G02X1331122I-1298J0D01*
G02X1331195Y880647I1299J-1D01*
G01X1331225Y880733D01*
X1330419Y882131D01*
X1330329Y882148D01*
G02X1329274Y883423I243J1275D01*
G37*
G36*
G01X364664Y1108630D02*
G02X367258I1297J0D01*
G02X366203Y1107355I-1298J0D01*
G01X366113Y1107338D01*
X365306Y1105941D01*
X365336Y1105855D01*
G02X365409Y1105426I-1224J-429D01*
G01Y1105424D01*
G02X364112Y1104128I-1297J1D01*
G02X362814Y1105426I0J1298D01*
G02X363869Y1106701I1298J0D01*
G01X363959Y1106718D01*
X364766Y1108116D01*
X364736Y1108202D01*
G02X364664Y1108630I1226J426D01*
G37*
G36*
G01X357264Y1115039D02*
G02X359858I1297J0D01*
G01Y1115037D01*
G02X359786Y1114610I-1298J-1D01*
G01X359756Y1114524D01*
X360563Y1113126D01*
X360653Y1113109D01*
G02X361710Y1111834I-240J-1275D01*
G02X359114I-1298J0D01*
G02X359187Y1112262I1299J-1D01*
G01X359217Y1112348D01*
X358409Y1113747D01*
X358319Y1113764D01*
G02X357264Y1115039I243J1275D01*
G37*
G36*
G01X523332Y883423D02*
G02X525926I1297J0D01*
G01Y883421D01*
G02X525854Y882994I-1298J-1D01*
G01X525824Y882908D01*
X526630Y881511D01*
X526720Y881494D01*
G02X527776Y880219I-242J-1275D01*
G02X525182I-1297J0D01*
G01Y880221D01*
G02X525254Y880646I1297J-1D01*
G01X525284Y880732D01*
X524477Y882131D01*
X524387Y882148D01*
G02X523332Y883423I243J1275D01*
G37*
G36*
G01X1342222Y886625D02*
Y886627D01*
G02X1344818I1298J0D01*
G02X1343762Y885352I-1298J0D01*
G01X1343672Y885335D01*
X1342866Y883938D01*
X1342896Y883852D01*
G02X1342968Y883425I-1226J-426D01*
G01Y883423D01*
G02X1340374I-1297J0D01*
G02X1341429Y884698I1298J0D01*
G01X1341519Y884715D01*
X1342325Y886112D01*
X1342295Y886198D01*
G02X1342222Y886625I1225J429D01*
G37*
G36*
G01X340614Y1111834D02*
G02X343210I1298J0D01*
G02X343137Y1111406I-1299J1D01*
G01X343107Y1111320D01*
X343914Y1109922D01*
X344004Y1109905D01*
G02X345060Y1108630I-242J-1275D01*
G02X342464I-1298J0D01*
G02X342537Y1109058I1299J-1D01*
G01X342567Y1109144D01*
X341760Y1110542D01*
X341670Y1110559D01*
G02X340614Y1111834I242J1275D01*
G37*
G36*
G01X1326006Y1108630D02*
G02X1328602I1298J0D01*
G01Y1108628D01*
G02X1328529Y1108201I-1298J2D01*
G01X1328499Y1108115D01*
X1329306Y1106718D01*
X1329396Y1106701D01*
G02X1330450Y1105426I-244J-1275D01*
G01Y1105424D01*
G02X1329153Y1104128I-1297J1D01*
G02X1327856Y1105426I1J1298D01*
G02X1327929Y1105855I1297J0D01*
G01X1327959Y1105941D01*
X1327152Y1107338D01*
X1327062Y1107355D01*
G02X1326006Y1108630I242J1275D01*
G37*
G36*
G01X1319091Y1106204D02*
X1320715D01*
G02X1321753Y1106724I1038J-776D01*
G02Y1104128I0J-1298D01*
G02X1320715Y1104648I0J1296D01*
G01X1319091D01*
G02X1318053Y1104128I-1038J776D01*
G02Y1106724I0J1298D01*
G02X1319091Y1106204I0J-1296D01*
G37*
G36*
G01X1333406Y1115039D02*
G02X1336000I1297J0D01*
G01Y1115037D01*
G02X1335928Y1114610I-1298J-1D01*
G01X1335898Y1114524D01*
X1336705Y1113126D01*
X1336795Y1113109D01*
G02X1337852Y1111834I-240J-1275D01*
G02X1335256I-1298J0D01*
G02X1335329Y1112262I1299J-1D01*
G01X1335359Y1112348D01*
X1334551Y1113747D01*
X1334461Y1113764D01*
G02X1333406Y1115039I243J1275D01*
G37*
G36*
G01X1340806Y1108630D02*
G02X1343400I1297J0D01*
G02X1342345Y1107355I-1298J0D01*
G01X1342255Y1107338D01*
X1341448Y1105941D01*
X1341478Y1105855D01*
G02X1341551Y1105426I-1224J-429D01*
G01Y1105424D01*
G02X1340254Y1104128I-1297J1D01*
G02X1338956Y1105426I0J1298D01*
G02X1340011Y1106701I1298J0D01*
G01X1340101Y1106718D01*
X1340908Y1108116D01*
X1340878Y1108202D01*
G02X1340806Y1108630I1226J426D01*
G37*
G36*
G01X1326492Y1112612D02*
X1328116D01*
G02X1329154Y1113132I1038J-776D01*
G02Y1110536I0J-1298D01*
G02X1328116Y1111056I0J1296D01*
G01X1326492D01*
G02X1325454Y1110536I-1038J776D01*
G02Y1113132I0J1298D01*
G02X1326492Y1112612I0J-1296D01*
G37*
G36*
G01X528882Y886625D02*
Y886627D01*
G02X531476I1297J0D01*
G02X530421Y885352I-1298J0D01*
G01X530331Y885335D01*
X529524Y883937D01*
X529554Y883851D01*
G02X529626Y883423I-1226J-426D01*
G02X527032I-1297J0D01*
G02X528088Y884698I1298J0D01*
G01X528178Y884715D01*
X528984Y886112D01*
X528954Y886198D01*
G02X528882Y886625I1226J426D01*
G37*
G36*
G01X1316756Y1111834D02*
G02X1319352I1298J0D01*
G02X1319279Y1111406I-1299J1D01*
G01X1319249Y1111320D01*
X1320056Y1109922D01*
X1320146Y1109905D01*
G02X1321202Y1108630I-242J-1275D01*
G02X1318606I-1298J0D01*
G02X1318679Y1109058I1299J-1D01*
G01X1318709Y1109144D01*
X1317902Y1110542D01*
X1317812Y1110559D01*
G02X1316756Y1111834I242J1275D01*
G37*
G36*
G01X358680Y886625D02*
Y886627D01*
G02X361276I1298J0D01*
G02X360220Y885352I-1298J0D01*
G01X360130Y885335D01*
X359324Y883938D01*
X359354Y883852D01*
G02X359426Y883425I-1226J-426D01*
G01Y883423D01*
G02X356832I-1297J0D01*
G02X357887Y884698I1298J0D01*
G01X357977Y884715D01*
X358783Y886112D01*
X358753Y886198D01*
G02X358680Y886625I1225J429D01*
G37*
G36*
G01X1334822D02*
Y886627D01*
G02X1337418I1298J0D01*
G02X1336362Y885352I-1298J0D01*
G01X1336272Y885335D01*
X1335466Y883938D01*
X1335496Y883852D01*
G02X1335568Y883425I-1226J-426D01*
G01Y883423D01*
G02X1332974I-1297J0D01*
G02X1334029Y884698I1298J0D01*
G01X1334119Y884715D01*
X1334925Y886112D01*
X1334895Y886198D01*
G02X1334822Y886625I1225J429D01*
G37*
G36*
G01X349864Y1108630D02*
G02X352460I1298J0D01*
G01Y1108628D01*
G02X352387Y1108201I-1298J2D01*
G01X352357Y1108115D01*
X353164Y1106718D01*
X353254Y1106701D01*
G02X354308Y1105426I-244J-1275D01*
G01Y1105424D01*
G02X353011Y1104128I-1297J1D01*
G02X351714Y1105426I1J1298D01*
G02X351787Y1105855I1297J0D01*
G01X351817Y1105941D01*
X351010Y1107338D01*
X350920Y1107355D01*
G02X349864Y1108630I242J1275D01*
G37*
G36*
G01X342949Y1106204D02*
X344573D01*
G02X345611Y1106724I1038J-776D01*
G02Y1104128I0J-1298D01*
G02X344573Y1104648I0J1296D01*
G01X342949D01*
G02X341911Y1104128I-1038J776D01*
G02Y1106724I0J1298D01*
G02X342949Y1106204I0J-1296D01*
G37*
G36*
G01X1330101Y541552D02*
X1333143D01*
G02Y538546I0J-1503D01*
G01X1330101D01*
G02Y541552I0J1503D01*
G37*
G36*
G01X521480Y873810D02*
G02X524076I1298J0D01*
G01Y873808D01*
G02X524003Y873381I-1298J2D01*
G01X523973Y873295D01*
X524779Y871898D01*
X524869Y871881D01*
G02X525926Y870606I-240J-1275D01*
G02X523332I-1297J0D01*
G01Y870607D01*
G02X523403Y871032I1297J2D01*
G01X523433Y871118D01*
X522626Y872518D01*
X522536Y872535D01*
G02X521480Y873810I242J1275D01*
G37*
G36*
G01X353132Y883423D02*
G02X355726I1297J0D01*
G01Y883421D01*
G02X355654Y882994I-1298J-1D01*
G01X355624Y882908D01*
X356430Y881511D01*
X356520Y881494D01*
G02X357576Y880219I-242J-1275D01*
G02X354980I-1298J0D01*
G02X355053Y880647I1299J-1D01*
G01X355083Y880733D01*
X354277Y882131D01*
X354187Y882148D01*
G02X353132Y883423I243J1275D01*
G37*
G36*
G01X528880Y873810D02*
G02X531476I1298J0D01*
G01Y873808D01*
G02X531403Y873381I-1298J2D01*
G01X531373Y873295D01*
X532179Y871898D01*
X532269Y871881D01*
G02X533326Y870606I-240J-1275D01*
G02X530732I-1297J0D01*
G01Y870607D01*
G02X530803Y871032I1297J2D01*
G01X530833Y871118D01*
X530026Y872518D01*
X529936Y872535D01*
G02X528880Y873810I242J1275D01*
G37*
G36*
G01X1492074Y883423D02*
G02X1494668I1297J0D01*
G01Y883421D01*
G02X1494596Y882994I-1298J-1D01*
G01X1494566Y882908D01*
X1495372Y881511D01*
X1495462Y881494D01*
G02X1496518Y880219I-242J-1275D01*
G02X1493922I-1298J0D01*
G02X1493995Y880647I1299J-1D01*
G01X1494025Y880733D01*
X1493219Y882131D01*
X1493129Y882148D01*
G02X1492074Y883423I243J1275D01*
G37*
G36*
G01X1497622Y873810D02*
G02X1500218I1298J0D01*
G01Y873808D01*
G02X1500145Y873381I-1298J2D01*
G01X1500115Y873295D01*
X1500921Y871898D01*
X1501011Y871881D01*
G02X1502068Y870606I-240J-1275D01*
G02X1499474I-1297J0D01*
G01Y870607D01*
G02X1499545Y871032I1297J2D01*
G01X1499575Y871118D01*
X1498768Y872518D01*
X1498678Y872535D01*
G02X1497622Y873810I242J1275D01*
G37*
G36*
G01X1320941Y1128634D02*
X1322565D01*
G02X1323603Y1129154I1038J-776D01*
G02Y1126558I0J-1298D01*
G02X1322565Y1127078I0J1296D01*
G01X1320941D01*
G02X1319903Y1126558I-1038J776D01*
G02Y1129154I0J1298D01*
G02X1320941Y1128634I0J-1296D01*
G37*
G36*
G01X344799D02*
X346423D01*
G02X347461Y1129154I1038J-776D01*
G02Y1126558I0J-1298D01*
G02X346423Y1127078I0J1296D01*
G01X344799D01*
G02X343761Y1126558I-1038J776D01*
G02Y1129154I0J1298D01*
G02X344799Y1128634I0J-1296D01*
G37*
G36*
G01X515932Y883423D02*
G02X518526I1297J0D01*
G01Y883421D01*
G02X518454Y882994I-1298J-1D01*
G01X518424Y882908D01*
X519230Y881511D01*
X519320Y881494D01*
G02X520376Y880219I-242J-1275D01*
G02X517780I-1298J0D01*
G02X517853Y880647I1299J-1D01*
G01X517883Y880733D01*
X517077Y882131D01*
X516987Y882148D01*
G02X515932Y883423I243J1275D01*
G37*
G36*
G01X1328283Y251360D02*
X1326983D01*
G02X1326680Y251662I-1J302D01*
G01Y252662D01*
G02X1326983Y252964I303J-1D01*
G01X1328283D01*
G02X1328586Y252662I1J-302D01*
G01Y251662D01*
G02X1328283Y251360I-303J1D01*
G37*
G36*
G01X1357952Y242464D02*
X1356652D01*
G02X1356350Y242766I0J302D01*
G01Y243766D01*
G02X1356652Y244068I302J0D01*
G01X1357952D01*
G02X1358254Y243766I0J-302D01*
G01Y242766D01*
G02X1357952Y242464I-302J0D01*
G37*
G36*
G01X1358624Y283142D02*
X1355224D01*
G02Y286146I0J1502D01*
G01X1358624D01*
G02Y283142I0J-1502D01*
G37*
G36*
G01X1348084Y278756D02*
X1344684D01*
G02Y281762I0J1503D01*
G01X1348084D01*
G02Y278756I0J-1503D01*
G37*
G36*
G01X1368524Y281242D02*
X1365124D01*
G02Y284246I0J1502D01*
G01X1368524D01*
G02Y281242I0J-1502D01*
G37*
G36*
G01X1337040Y261764D02*
X1335740D01*
G02X1335438Y262066I0J302D01*
G01Y263066D01*
G02X1335740Y263368I302J0D01*
G01X1337040D01*
G02X1337342Y263066I0J-302D01*
G01Y262066D01*
G02X1337040Y261764I-302J0D01*
G37*
G36*
G01Y259664D02*
X1335740D01*
G02X1335438Y259966I0J302D01*
G01Y260966D01*
G02X1335740Y261268I302J0D01*
G01X1337040D01*
G02X1337342Y260966I0J-302D01*
G01Y259966D01*
G02X1337040Y259664I-302J0D01*
G37*
G36*
G01X1340640Y261764D02*
X1339340D01*
G02X1339038Y262066I0J302D01*
G01Y263066D01*
G02X1339340Y263368I302J0D01*
G01X1340640D01*
G02X1340942Y263066I0J-302D01*
G01Y262066D01*
G02X1340640Y261764I-302J0D01*
G37*
G36*
G01Y259664D02*
X1339340D01*
G02X1339038Y259966I0J302D01*
G01Y260966D01*
G02X1339340Y261268I302J0D01*
G01X1340640D01*
G02X1340942Y260966I0J-302D01*
G01Y259966D01*
G02X1340640Y259664I-302J0D01*
G37*
G36*
G01X1328283Y253460D02*
X1326983D01*
G02X1326680Y253762I-1J302D01*
G01Y254762D01*
G02X1326983Y255064I303J-1D01*
G01X1328283D01*
G02X1328586Y254762I1J-302D01*
G01Y253762D01*
G02X1328283Y253460I-303J1D01*
G37*
G36*
G01X1344432Y244564D02*
X1343132D01*
G02X1342830Y244866I0J302D01*
G01Y245866D01*
G02X1343132Y246168I302J0D01*
G01X1344432D01*
G02X1344734Y245866I0J-302D01*
G01Y244866D01*
G02X1344432Y244564I-302J0D01*
G37*
G36*
G01X1340832Y242464D02*
X1339532D01*
G02X1339230Y242766I0J302D01*
G01Y243766D01*
G02X1339532Y244068I302J0D01*
G01X1340832D01*
G02X1341134Y243766I0J-302D01*
G01Y242766D01*
G02X1340832Y242464I-302J0D01*
G37*
G36*
G01X1344432D02*
X1343132D01*
G02X1342830Y242766I0J302D01*
G01Y243766D01*
G02X1343132Y244068I302J0D01*
G01X1344432D01*
G02X1344734Y243766I0J-302D01*
G01Y242766D01*
G02X1344432Y242464I-302J0D01*
G37*
G36*
G01X1340832Y244564D02*
X1339532D01*
G02X1339230Y244866I0J302D01*
G01Y245866D01*
G02X1339532Y246168I302J0D01*
G01X1340832D01*
G02X1341134Y245866I0J-302D01*
G01Y244866D01*
G02X1340832Y244564I-302J0D01*
G37*
G36*
G01X1351698Y252564D02*
X1350398D01*
G02X1350096Y252866I0J302D01*
G01Y253866D01*
G02X1350398Y254168I302J0D01*
G01X1351698D01*
G02X1352000Y253866I0J-302D01*
G01Y252866D01*
G02X1351698Y252564I-302J0D01*
G37*
G36*
G01X1348098Y250464D02*
X1346798D01*
G02X1346496Y250766I0J302D01*
G01Y251766D01*
G02X1346798Y252068I302J0D01*
G01X1348098D01*
G02X1348400Y251766I0J-302D01*
G01Y250766D01*
G02X1348098Y250464I-302J0D01*
G37*
G36*
G01Y252564D02*
X1346798D01*
G02X1346496Y252866I0J302D01*
G01Y253866D01*
G02X1346798Y254168I302J0D01*
G01X1348098D01*
G02X1348400Y253866I0J-302D01*
G01Y252866D01*
G02X1348098Y252564I-302J0D01*
G37*
G36*
G01X1351698Y250464D02*
X1350398D01*
G02X1350096Y250766I0J302D01*
G01Y251766D01*
G02X1350398Y252068I302J0D01*
G01X1351698D01*
G02X1352000Y251766I0J-302D01*
G01Y250766D01*
G02X1351698Y250464I-302J0D01*
G37*
G36*
G01X1331883Y253460D02*
X1330583D01*
G02X1330280Y253762I-1J302D01*
G01Y254762D01*
G02X1330583Y255064I303J-1D01*
G01X1331883D01*
G02X1332186Y254762I1J-302D01*
G01Y253762D01*
G02X1331883Y253460I-303J1D01*
G37*
G36*
G01X1357952Y244564D02*
X1356652D01*
G02X1356350Y244866I0J302D01*
G01Y245866D01*
G02X1356652Y246168I302J0D01*
G01X1357952D01*
G02X1358254Y245866I0J-302D01*
G01Y244866D01*
G02X1357952Y244564I-302J0D01*
G37*
G36*
G01X1354352Y242464D02*
X1353052D01*
G02X1352750Y242766I0J302D01*
G01Y243766D01*
G02X1353052Y244068I302J0D01*
G01X1354352D01*
G02X1354654Y243766I0J-302D01*
G01Y242766D01*
G02X1354352Y242464I-302J0D01*
G37*
G36*
G01Y244564D02*
X1353052D01*
G02X1352750Y244866I0J302D01*
G01Y245866D01*
G02X1353052Y246168I302J0D01*
G01X1354352D01*
G02X1354654Y245866I0J-302D01*
G01Y244866D01*
G02X1354352Y244564I-302J0D01*
G37*
G36*
G01X1364700Y250464D02*
X1363400D01*
G02X1363098Y250766I0J302D01*
G01Y251766D01*
G02X1363400Y252068I302J0D01*
G01X1364700D01*
G02X1365002Y251766I0J-302D01*
G01Y250766D01*
G02X1364700Y250464I-302J0D01*
G37*
G36*
G01Y252564D02*
X1363400D01*
G02X1363098Y252866I0J302D01*
G01Y253866D01*
G02X1363400Y254168I302J0D01*
G01X1364700D01*
G02X1365002Y253866I0J-302D01*
G01Y252866D01*
G02X1364700Y252564I-302J0D01*
G37*
G36*
G01X1361100Y250464D02*
X1359800D01*
G02X1359498Y250766I0J302D01*
G01Y251766D01*
G02X1359800Y252068I302J0D01*
G01X1361100D01*
G02X1361402Y251766I0J-302D01*
G01Y250766D01*
G02X1361100Y250464I-302J0D01*
G37*
G36*
G01Y252564D02*
X1359800D01*
G02X1359498Y252866I0J302D01*
G01Y253866D01*
G02X1359800Y254168I302J0D01*
G01X1361100D01*
G02X1361402Y253866I0J-302D01*
G01Y252866D01*
G02X1361100Y252564I-302J0D01*
G37*
G36*
G01X1378528Y256930D02*
Y255630D01*
G02X1378226Y255328I-302J0D01*
G01X1377226D01*
G02X1376924Y255630I0J302D01*
G01Y256930D01*
G02X1377226Y257232I302J0D01*
G01X1378226D01*
G02X1378528Y256930I0J-302D01*
G37*
G36*
G01X1376428D02*
Y255630D01*
G02X1376126Y255328I-302J0D01*
G01X1375126D01*
G02X1374824Y255630I0J302D01*
G01Y256930D01*
G02X1375126Y257232I302J0D01*
G01X1376126D01*
G02X1376428Y256930I0J-302D01*
G37*
G36*
G01X1378528Y253330D02*
Y252030D01*
G02X1378226Y251728I-302J0D01*
G01X1377226D01*
G02X1376924Y252030I0J302D01*
G01Y253330D01*
G02X1377226Y253632I302J0D01*
G01X1378226D01*
G02X1378528Y253330I0J-302D01*
G37*
G36*
G01X1376428D02*
Y252030D01*
G02X1376126Y251728I-302J0D01*
G01X1375126D01*
G02X1374824Y252030I0J302D01*
G01Y253330D01*
G02X1375126Y253632I302J0D01*
G01X1376126D01*
G02X1376428Y253330I0J-302D01*
G37*
G36*
G01X1328480Y322400D02*
X1325080D01*
G02Y325404I0J1502D01*
G01X1328480D01*
G02Y322400I0J-1502D01*
G37*
G36*
G01X613970Y190254D02*
X617370D01*
G02Y187250I0J-1502D01*
G01X613970D01*
G02Y190254I0J1502D01*
G37*
G36*
G01X64571Y427304D02*
X61171D01*
G02Y430308I0J1502D01*
G01X64571D01*
G02Y427304I0J-1502D01*
G37*
G36*
G01X626640Y190254D02*
X630040D01*
G02Y187250I0J-1502D01*
G01X626640D01*
G02Y190254I0J1502D01*
G37*
G36*
G01X733378Y78807D02*
G02X733488Y78543I-284J-273D01*
G01Y77980D01*
X733486D01*
Y74332D01*
G02X733117Y73970I-388J27D01*
G01X731909D01*
Y73969D01*
G02X731624Y74089I-2J395D01*
G02X731514Y74353I284J273D01*
G01Y78563D01*
X731518Y78589D01*
G02X731885Y78926I386J-52D01*
G01X733093D01*
Y78927D01*
G02X733378Y78807I2J-395D01*
G37*
G36*
G01X737478D02*
G02X737588Y78543I-284J-273D01*
G01Y77980D01*
X737586D01*
Y74332D01*
G02X737217Y73970I-388J27D01*
G01X736009D01*
Y73969D01*
G02X735724Y74089I-2J395D01*
G02X735614Y74353I284J273D01*
G01Y78563D01*
X735618Y78589D01*
G02X735985Y78926I386J-52D01*
G01X737193D01*
Y78927D01*
G02X737478Y78807I2J-395D01*
G37*
G36*
G01X423180Y1601300D02*
X419780D01*
G02Y1604304I0J1502D01*
G01X423180D01*
G02Y1601300I0J-1502D01*
G37*
G36*
G01X49360Y427304D02*
X45960D01*
G02Y430308I0J1502D01*
G01X49360D01*
G02Y427304I0J-1502D01*
G37*
G36*
G01X1400985Y242432D02*
X1404385D01*
G02Y239426I0J-1503D01*
G01X1400985D01*
G02Y242432I0J1503D01*
G37*
G36*
G01X930731Y531982D02*
X933773D01*
G02Y528976I0J-1503D01*
G01X930731D01*
G02Y531982I0J1503D01*
G37*
G36*
G01X285377Y1591596D02*
X288777D01*
G02Y1588592I0J-1502D01*
G01X285377D01*
G02Y1591596I0J1502D01*
G37*
G36*
G01X229131Y49144D02*
X225731D01*
G02Y52148I0J1502D01*
G01X229131D01*
G02Y49144I0J-1502D01*
G37*
G36*
G01X284230D02*
X280830D01*
G02Y52148I0J1502D01*
G01X284230D01*
G02Y49144I0J-1502D01*
G37*
G36*
G01X1755272Y27934D02*
X1758672D01*
G02Y24928I0J-1503D01*
G01X1755272D01*
G02Y27934I0J1503D01*
G37*
G36*
G01X1530660Y101664D02*
X1534060D01*
G02Y98660I0J-1502D01*
G01X1530660D01*
G02Y101664I0J1502D01*
G37*
G36*
G01X1549308Y27934D02*
X1552708D01*
G02Y24928I0J-1503D01*
G01X1549308D01*
G02Y27934I0J1503D01*
G37*
G36*
G01X1556413Y20998D02*
X1559813D01*
G02Y17992I0J-1503D01*
G01X1556413D01*
G02Y20998I0J1503D01*
G37*
G36*
G01X1563481Y27934D02*
X1566881D01*
G02Y24928I0J-1503D01*
G01X1563481D01*
G02Y27934I0J1503D01*
G37*
G36*
G01X1570586Y20998D02*
X1573986D01*
G02Y17992I0J-1503D01*
G01X1570586D01*
G02Y20998I0J1503D01*
G37*
G36*
G01X1577654Y27934D02*
X1581054D01*
G02Y24928I0J-1503D01*
G01X1577654D01*
G02Y27934I0J1503D01*
G37*
G36*
G01X1584759Y20998D02*
X1588159D01*
G02Y17992I0J-1503D01*
G01X1584759D01*
G02Y20998I0J1503D01*
G37*
G36*
G01X1591828Y27934D02*
X1595228D01*
G02Y24928I0J-1503D01*
G01X1591828D01*
G02Y27934I0J1503D01*
G37*
G36*
G01X1598933Y20998D02*
X1602333D01*
G02Y17992I0J-1503D01*
G01X1598933D01*
G02Y20998I0J1503D01*
G37*
G36*
G01X1627694Y27934D02*
X1631094D01*
G02Y24928I0J-1503D01*
G01X1627694D01*
G02Y27934I0J1503D01*
G37*
G36*
G01X1634799Y20998D02*
X1638199D01*
G02Y17992I0J-1503D01*
G01X1634799D01*
G02Y20998I0J1503D01*
G37*
G36*
G01X218667Y21040D02*
X222067D01*
G02Y18036I0J-1502D01*
G01X218667D01*
G02Y21040I0J1502D01*
G37*
G36*
G01X211562Y27976D02*
X214962D01*
G02Y24972I0J-1502D01*
G01X211562D01*
G02Y27976I0J1502D01*
G37*
G36*
G01X204494Y21040D02*
X207894D01*
G02Y18036I0J-1502D01*
G01X204494D01*
G02Y21040I0J1502D01*
G37*
G36*
G01X197389Y27976D02*
X200789D01*
G02Y24972I0J-1502D01*
G01X197389D01*
G02Y27976I0J1502D01*
G37*
G36*
G01X167428D02*
X170828D01*
G02Y24972I0J-1502D01*
G01X167428D01*
G02Y27976I0J1502D01*
G37*
G36*
G01X174533Y21040D02*
X177933D01*
G02Y18036I0J-1502D01*
G01X174533D01*
G02Y21040I0J1502D01*
G37*
G36*
G01X153255Y27976D02*
X156655D01*
G02Y24972I0J-1502D01*
G01X153255D01*
G02Y27976I0J1502D01*
G37*
G36*
G01X160360Y21040D02*
X163760D01*
G02Y18036I0J-1502D01*
G01X160360D01*
G02Y21040I0J1502D01*
G37*
G36*
G01X124494D02*
X127894D01*
G02Y18036I0J-1502D01*
G01X124494D01*
G02Y21040I0J1502D01*
G37*
G36*
G01X117389Y27976D02*
X120789D01*
G02Y24972I0J-1502D01*
G01X117389D01*
G02Y27976I0J1502D01*
G37*
G36*
G01X103215D02*
X106615D01*
G02Y24972I0J-1502D01*
G01X103215D01*
G02Y27976I0J1502D01*
G37*
G36*
G01X110320Y21040D02*
X113720D01*
G02Y18036I0J-1502D01*
G01X110320D01*
G02Y21040I0J1502D01*
G37*
G36*
G01X89042Y27976D02*
X92442D01*
G02Y24972I0J-1502D01*
G01X89042D01*
G02Y27976I0J1502D01*
G37*
G36*
G01X96147Y21040D02*
X99547D01*
G02Y18036I0J-1502D01*
G01X96147D01*
G02Y21040I0J1502D01*
G37*
G36*
G01X74869Y27976D02*
X78269D01*
G02Y24972I0J-1502D01*
G01X74869D01*
G02Y27976I0J1502D01*
G37*
G36*
G01X81974Y21040D02*
X85374D01*
G02Y18036I0J-1502D01*
G01X81974D01*
G02Y21040I0J1502D01*
G37*
G36*
G01X1641867Y27934D02*
X1645267D01*
G02Y24928I0J-1503D01*
G01X1641867D01*
G02Y27934I0J1503D01*
G37*
G36*
G01X1648972Y20998D02*
X1652372D01*
G02Y17992I0J-1503D01*
G01X1648972D01*
G02Y20998I0J1503D01*
G37*
G36*
G01X1671828Y27934D02*
X1675228D01*
G02Y24928I0J-1503D01*
G01X1671828D01*
G02Y27934I0J1503D01*
G37*
G36*
G01X1678933Y20998D02*
X1682333D01*
G02Y17992I0J-1503D01*
G01X1678933D01*
G02Y20998I0J1503D01*
G37*
G36*
G01X1686001Y27934D02*
X1689401D01*
G02Y24928I0J-1503D01*
G01X1686001D01*
G02Y27934I0J1503D01*
G37*
G36*
G01X1693106Y20998D02*
X1696506D01*
G02Y17992I0J-1503D01*
G01X1693106D01*
G02Y20998I0J1503D01*
G37*
G36*
G01X1700217Y27962D02*
X1703617D01*
G02Y24956I0J-1503D01*
G01X1700217D01*
G02Y27962I0J1503D01*
G37*
G36*
G01X1700170Y52152D02*
X1703570D01*
G02Y49146I0J-1503D01*
G01X1700170D01*
G02Y52152I0J1503D01*
G37*
G36*
G01X670612Y48766D02*
X674012D01*
G02Y45762I0J-1502D01*
G01X670612D01*
G02Y48766I0J1502D01*
G37*
G36*
G01X284233Y24972D02*
X280833D01*
G02Y27976I0J1502D01*
G01X284233D01*
G02Y24972I0J-1502D01*
G37*
G36*
G01X1307442Y305496D02*
X1304042D01*
G02Y308500I0J1502D01*
G01X1307442D01*
G02Y305496I0J-1502D01*
G37*
G36*
G01X388794Y1591917D02*
Y1590917D01*
G02X388492Y1590614I-302J-1D01*
G01X387192D01*
G02X386890Y1590917I1J303D01*
G01Y1591917D01*
G02X387192Y1592220I302J1D01*
G01X388492D01*
G02X388794Y1591917I-1J-303D01*
G37*
G36*
G01Y1594017D02*
Y1593017D01*
G02X388492Y1592714I-302J-1D01*
G01X387192D01*
G02X386890Y1593017I1J303D01*
G01Y1594017D01*
G02X387192Y1594320I302J1D01*
G01X388492D01*
G02X388794Y1594017I-1J-303D01*
G37*
G36*
G01X1382972Y1603882D02*
X1386372D01*
G02Y1600878I0J-1502D01*
G01X1382972D01*
G02Y1603882I0J1502D01*
G37*
G36*
G01Y1615794D02*
X1386372D01*
G02Y1612790I0J-1502D01*
G01X1382972D01*
G02Y1615794I0J1502D01*
G37*
G36*
G01X229135Y24972D02*
X225735D01*
G02Y27976I0J1502D01*
G01X229135D01*
G02Y24972I0J-1502D01*
G37*
G36*
G01X350977Y1603882D02*
X354377D01*
G02Y1600878I0J-1502D01*
G01X350977D01*
G02Y1603882I0J1502D01*
G37*
G36*
G01X1307042Y291134D02*
X1303642D01*
G02Y294138I0J1502D01*
G01X1307042D01*
G02Y291134I0J-1502D01*
G37*
G36*
G01X405990Y1617450D02*
X402590D01*
G02Y1620454I0J1502D01*
G01X405990D01*
G02Y1617450I0J-1502D01*
G37*
G36*
G01X441740Y1650764D02*
X438340D01*
G02Y1653768I0J1502D01*
G01X441740D01*
G02Y1650764I0J-1502D01*
G37*
G36*
G01X49212Y450100D02*
X45812D01*
G02Y453104I0J1502D01*
G01X49212D01*
G02Y450100I0J-1502D01*
G37*
G36*
G01X1418630Y221520D02*
X1422030D01*
G02Y218516I0J-1502D01*
G01X1418630D01*
G02Y221520I0J1502D01*
G37*
G36*
G01X1407420D02*
X1410820D01*
G02Y218516I0J-1502D01*
G01X1407420D01*
G02Y221520I0J1502D01*
G37*
G36*
G01X1432660D02*
X1436060D01*
G02Y218516I0J-1502D01*
G01X1432660D01*
G02Y221520I0J1502D01*
G37*
G36*
G01X862930Y71574D02*
X866330D01*
G02Y68570I0J-1502D01*
G01X862930D01*
G02Y71574I0J1502D01*
G37*
G36*
G01X1348824Y327478D02*
X1345424D01*
G02Y330484I0J1503D01*
G01X1348824D01*
G02Y327478I0J-1503D01*
G37*
G36*
G01X1341431Y321190D02*
X1338031D01*
G02Y324196I0J1503D01*
G01X1341431D01*
G02Y321190I0J-1503D01*
G37*
G36*
G01X1335145Y331114D02*
X1331745D01*
G02Y334118I0J1502D01*
G01X1335145D01*
G02Y331114I0J-1502D01*
G37*
G36*
G01X1319618Y316570D02*
X1316218D01*
G02Y319576I0J1503D01*
G01X1319618D01*
G02Y316570I0J-1503D01*
G37*
G36*
G01X1311077Y321494D02*
X1307677D01*
G02Y324498I0J1502D01*
G01X1311077D01*
G02Y321494I0J-1502D01*
G37*
G36*
G01X1380602Y199170D02*
X1384002D01*
G02Y196166I0J-1502D01*
G01X1380602D01*
G02Y199170I0J1502D01*
G37*
G36*
G01X1398006D02*
X1401406D01*
G02Y196166I0J-1502D01*
G01X1398006D01*
G02Y199170I0J1502D01*
G37*
G36*
G01X1373591Y177932D02*
X1376991D01*
G02Y174928I0J-1502D01*
G01X1373591D01*
G02Y177932I0J1502D01*
G37*
G36*
G01X1169820Y637554D02*
X1173220D01*
G02Y634550I0J-1502D01*
G01X1169820D01*
G02Y637554I0J1502D01*
G37*
G36*
G01X519764Y41830D02*
X523164D01*
G02Y38826I0J-1502D01*
G01X519764D01*
G02Y41830I0J1502D01*
G37*
G36*
G01X732793Y72938D02*
X736193D01*
G02Y69934I0J-1502D01*
G01X732793D01*
G02Y72938I0J1502D01*
G37*
G36*
G01X1161860Y643614D02*
X1165260D01*
G02Y640610I0J-1502D01*
G01X1161860D01*
G02Y643614I0J1502D01*
G37*
G36*
G01X663543Y44830D02*
X666943D01*
G02Y41826I0J-1502D01*
G01X663543D01*
G02Y44830I0J1502D01*
G37*
G36*
G01X656439Y48766D02*
X659839D01*
G02Y45762I0J-1502D01*
G01X656439D01*
G02Y48766I0J1502D01*
G37*
G36*
G01X562771Y1603882D02*
X566171D01*
G02Y1600878I0J-1502D01*
G01X562771D01*
G02Y1603882I0J1502D01*
G37*
G36*
G01X538651D02*
X542051D01*
G02Y1600878I0J-1502D01*
G01X538651D01*
G02Y1603882I0J1502D01*
G37*
G36*
G01X1406970Y140244D02*
X1410370D01*
G02Y137240I0J-1502D01*
G01X1406970D01*
G02Y140244I0J1502D01*
G37*
G36*
G01X1323303Y297674D02*
X1319903D01*
G02Y300678I0J1502D01*
G01X1323303D01*
G02Y297674I0J-1502D01*
G37*
G36*
G01X1361771Y330772D02*
X1358371D01*
G02Y333778I0J1503D01*
G01X1361771D01*
G02Y330772I0J-1503D01*
G37*
G36*
G01X555175Y72938D02*
X558575D01*
G02Y69934I0J-1502D01*
G01X555175D01*
G02Y72938I0J1502D01*
G37*
G36*
G01X541002D02*
X544402D01*
G02Y69934I0J-1502D01*
G01X541002D01*
G02Y72938I0J1502D01*
G37*
G36*
G01X519742D02*
X523142D01*
G02Y69934I0J-1502D01*
G01X519742D01*
G02Y72938I0J1502D01*
G37*
G36*
G01X533915Y61324D02*
X537315D01*
G02Y58320I0J-1502D01*
G01X533915D01*
G02Y61324I0J1502D01*
G37*
G36*
G01X1294500Y298190D02*
X1291100D01*
G02Y301194I0J1502D01*
G01X1294500D01*
G02Y298190I0J-1502D01*
G37*
G36*
G01X1404829Y185766D02*
X1408229D01*
G02Y182760I0J-1503D01*
G01X1404829D01*
G02Y185766I0J1503D01*
G37*
G36*
G01X538651Y1615794D02*
X542051D01*
G02Y1612790I0J-1502D01*
G01X538651D01*
G02Y1615794I0J1502D01*
G37*
G36*
G01X526591Y1603882D02*
X529991D01*
G02Y1600878I0J-1502D01*
G01X526591D01*
G02Y1603882I0J1502D01*
G37*
G36*
G01X514531D02*
X517931D01*
G02Y1600878I0J-1502D01*
G01X514531D01*
G02Y1603882I0J1502D01*
G37*
G36*
G01X526591Y1615794D02*
X529991D01*
G02Y1612790I0J-1502D01*
G01X526591D01*
G02Y1615794I0J1502D01*
G37*
G36*
G01X514531D02*
X517931D01*
G02Y1612790I0J-1502D01*
G01X514531D01*
G02Y1615794I0J1502D01*
G37*
G36*
G01X490411Y1603882D02*
X493811D01*
G02Y1600878I0J-1502D01*
G01X490411D01*
G02Y1603882I0J1502D01*
G37*
G36*
G01X478351Y1615794D02*
X481751D01*
G02Y1612790I0J-1502D01*
G01X478351D01*
G02Y1615794I0J1502D01*
G37*
G36*
G01X502471D02*
X505871D01*
G02Y1612790I0J-1502D01*
G01X502471D01*
G02Y1615794I0J1502D01*
G37*
G36*
G01X478351Y1603882D02*
X481751D01*
G02Y1600878I0J-1502D01*
G01X478351D01*
G02Y1603882I0J1502D01*
G37*
G36*
G01X1412284Y173198D02*
X1415684D01*
G02Y170194I0J-1502D01*
G01X1412284D01*
G02Y173198I0J1502D01*
G37*
G36*
G01X598951Y1603882D02*
X602351D01*
G02Y1600878I0J-1502D01*
G01X598951D01*
G02Y1603882I0J1502D01*
G37*
G36*
G01Y1615794D02*
X602351D01*
G02Y1612790I0J-1502D01*
G01X598951D01*
G02Y1615794I0J1502D01*
G37*
G36*
G01X586891Y1603882D02*
X590291D01*
G02Y1600878I0J-1502D01*
G01X586891D01*
G02Y1603882I0J1502D01*
G37*
G36*
G01X647191D02*
X650591D01*
G02Y1600878I0J-1502D01*
G01X647191D01*
G02Y1603882I0J1502D01*
G37*
G36*
G01X635131Y1615794D02*
X638531D01*
G02Y1612790I0J-1502D01*
G01X635131D01*
G02Y1615794I0J1502D01*
G37*
G36*
G01X647191D02*
X650591D01*
G02Y1612790I0J-1502D01*
G01X647191D01*
G02Y1615794I0J1502D01*
G37*
G36*
G01X623071D02*
X626471D01*
G02Y1612790I0J-1502D01*
G01X623071D01*
G02Y1615794I0J1502D01*
G37*
G36*
G01X1355200Y336340D02*
X1351800D01*
G02Y339346I0J1503D01*
G01X1355200D01*
G02Y336340I0J-1503D01*
G37*
G36*
G01X1328814Y292054D02*
X1325414D01*
G02Y295058I0J1502D01*
G01X1328814D01*
G02Y292054I0J-1502D01*
G37*
G36*
G01X1340161Y291902D02*
X1336761D01*
G02Y294906I0J1502D01*
G01X1340161D01*
G02Y291902I0J-1502D01*
G37*
G36*
G01X1413950Y185766D02*
X1417350D01*
G02Y182760I0J-1503D01*
G01X1413950D01*
G02Y185766I0J1503D01*
G37*
G36*
G01X1423110D02*
X1426510D01*
G02Y182760I0J-1503D01*
G01X1423110D01*
G02Y185766I0J1503D01*
G37*
G36*
G01X1401341Y178662D02*
X1404741D01*
G02Y175656I0J-1503D01*
G01X1401341D01*
G02Y178662I0J1503D01*
G37*
G36*
G01X1403778Y173186D02*
X1407178D01*
G02Y170182I0J-1502D01*
G01X1403778D01*
G02Y173186I0J1502D01*
G37*
G36*
G01X1389256Y199170D02*
X1392656D01*
G02Y196166I0J-1502D01*
G01X1389256D01*
G02Y199170I0J1502D01*
G37*
G36*
G01X550711Y1603882D02*
X554111D01*
G02Y1600878I0J-1502D01*
G01X550711D01*
G02Y1603882I0J1502D01*
G37*
G36*
G01X502471D02*
X505871D01*
G02Y1600878I0J-1502D01*
G01X502471D01*
G02Y1603882I0J1502D01*
G37*
G36*
G01X490411Y1615794D02*
X493811D01*
G02Y1612790I0J-1502D01*
G01X490411D01*
G02Y1615794I0J1502D01*
G37*
G36*
G01X987440Y432696D02*
X990840D01*
G02Y429690I0J-1503D01*
G01X987440D01*
G02Y432696I0J1503D01*
G37*
G36*
G01X1471460Y631900D02*
X1468060D01*
G02Y634904I0J1502D01*
G01X1471460D01*
G02Y631900I0J-1502D01*
G37*
G36*
G01X934047Y459364D02*
X937447D01*
G02Y456360I0J-1502D01*
G01X934047D01*
G02Y459364I0J1502D01*
G37*
G36*
G01X942047Y464514D02*
X945447D01*
G02Y461510I0J-1502D01*
G01X942047D01*
G02Y464514I0J1502D01*
G37*
G36*
G01X550711Y1615794D02*
X554111D01*
G02Y1612790I0J-1502D01*
G01X550711D01*
G02Y1615794I0J1502D01*
G37*
G36*
G01X635131Y1603882D02*
X638531D01*
G02Y1600878I0J-1502D01*
G01X635131D01*
G02Y1603882I0J1502D01*
G37*
G36*
G01X909584Y459638D02*
X912984D01*
G02Y456632I0J-1503D01*
G01X909584D01*
G02Y459638I0J1503D01*
G37*
G36*
G01X913394Y523164D02*
X916794D01*
G02Y520160I0J-1502D01*
G01X913394D01*
G02Y523164I0J1502D01*
G37*
G36*
G01X574831Y1603882D02*
X578231D01*
G02Y1600878I0J-1502D01*
G01X574831D01*
G02Y1603882I0J1502D01*
G37*
G36*
G01X659251D02*
X662651D01*
G02Y1600878I0J-1502D01*
G01X659251D01*
G02Y1603882I0J1502D01*
G37*
G36*
G01X1153370Y639694D02*
X1156770D01*
G02Y636690I0J-1502D01*
G01X1153370D01*
G02Y639694I0J1502D01*
G37*
G36*
G01X1406786Y199170D02*
X1410186D01*
G02Y196166I0J-1502D01*
G01X1406786D01*
G02Y199170I0J1502D01*
G37*
G36*
G01X611011Y1615794D02*
X614411D01*
G02Y1612790I0J-1502D01*
G01X611011D01*
G02Y1615794I0J1502D01*
G37*
G36*
G01X1312136Y283446D02*
X1308736D01*
G02Y286450I0J1502D01*
G01X1312136D01*
G02Y283446I0J-1502D01*
G37*
G36*
G01X611011Y1603882D02*
X614411D01*
G02Y1600878I0J-1502D01*
G01X611011D01*
G02Y1603882I0J1502D01*
G37*
G36*
G01X586891Y1615794D02*
X590291D01*
G02Y1612790I0J-1502D01*
G01X586891D01*
G02Y1615794I0J1502D01*
G37*
G36*
G01X659251D02*
X662651D01*
G02Y1612790I0J-1502D01*
G01X659251D01*
G02Y1615794I0J1502D01*
G37*
G36*
G01X1331883Y251360D02*
X1330583D01*
G02X1330280Y251662I-1J302D01*
G01Y252662D01*
G02X1330583Y252964I303J-1D01*
G01X1331883D01*
G02X1332186Y252662I1J-302D01*
G01Y251662D01*
G02X1331883Y251360I-303J1D01*
G37*
G36*
G01X574831Y1615794D02*
X578231D01*
G02Y1612790I0J-1502D01*
G01X574831D01*
G02Y1615794I0J1502D01*
G37*
G36*
G01X1183360Y643564D02*
X1186760D01*
G02Y640560I0J-1502D01*
G01X1183360D01*
G02Y643564I0J1502D01*
G37*
G36*
G01X562771Y1615794D02*
X566171D01*
G02Y1612790I0J-1502D01*
G01X562771D01*
G02Y1615794I0J1502D01*
G37*
G36*
G01X901230Y533114D02*
X904630D01*
G02Y530110I0J-1502D01*
G01X901230D01*
G02Y533114I0J1502D01*
G37*
G36*
G01X954390Y529098D02*
X957790D01*
G02Y526094I0J-1502D01*
G01X954390D01*
G02Y529098I0J1502D01*
G37*
G36*
G01X963930Y534864D02*
X967330D01*
G02Y531860I0J-1502D01*
G01X963930D01*
G02Y534864I0J1502D01*
G37*
G36*
G01X548070Y80874D02*
X551470D01*
G02Y77870I0J-1502D01*
G01X548070D01*
G02Y80874I0J1502D01*
G37*
G36*
G01X623071Y1603882D02*
X626471D01*
G02Y1600878I0J-1502D01*
G01X623071D01*
G02Y1603882I0J1502D01*
G37*
G36*
G01X888130Y534114D02*
X891530D01*
G02Y531110I0J-1502D01*
G01X888130D01*
G02Y534114I0J1502D01*
G37*
G36*
G01X297437Y1591596D02*
X300837D01*
G02Y1588592I0J-1502D01*
G01X297437D01*
G02Y1591596I0J1502D01*
G37*
G36*
G01X237137D02*
X240537D01*
G02Y1588592I0J-1502D01*
G01X237137D01*
G02Y1591596I0J1502D01*
G37*
G36*
G01X937340Y309612D02*
X920138D01*
G02X937340I8601J12041D01*
G37*
G36*
G01X392370Y1591917D02*
Y1590917D01*
G02X392067Y1590614I-303J0D01*
G01X390767D01*
G02X390464Y1590917I0J303D01*
G01Y1591917D01*
G02X390767Y1592220I303J0D01*
G01X392067D01*
G02X392370Y1591917I0J-303D01*
G37*
G36*
G01Y1594017D02*
Y1593017D01*
G02X392067Y1592714I-303J0D01*
G01X390767D01*
G02X390464Y1593017I0J303D01*
G01Y1594017D01*
G02X390767Y1594320I303J0D01*
G01X392067D01*
G02X392370Y1594017I0J-303D01*
G37*
G36*
G01X921047Y464514D02*
X924447D01*
G02Y461510I0J-1502D01*
G01X921047D01*
G02Y464514I0J1502D01*
G37*
G36*
G01X371587Y173422D02*
X365287D01*
G02Y197050I0J11814D01*
G01X371587D01*
G02Y173422I0J-11814D01*
G37*
G36*
G01X253477D02*
X247176D01*
G02X247175Y197050I0J11814D01*
G01X253476D01*
G02X253477Y173422I0J-11814D01*
G37*
G36*
G01X1012861Y434390D02*
X1016261D01*
G02Y431386I0J-1502D01*
G01X1012861D01*
G02Y434390I0J1502D01*
G37*
G36*
G01X50772Y120610D02*
X55372Y124913D01*
G02X66448Y113076I5538J-5919D01*
G01X61848Y108773D01*
G02X50772Y120610I-5538J5918D01*
G37*
G36*
G01X62587Y23395D02*
G02X58024Y17311I-2280J-3043D01*
G02X62587Y23395I2279J3044D01*
G37*
G36*
G01X443227Y845968D02*
G02X444266Y845448I0J-1298D01*
G01X445888D01*
G02X446927Y845968I1039J-778D01*
G02Y843374I0J-1297D01*
G02X445888Y843894I0J1298D01*
G01X444266D01*
G02X443227Y843374I-1039J778D01*
G02Y845968I0J1297D01*
G37*
G36*
G01X356830Y844971D02*
G02X359424I1297J0D01*
G02X358362Y843695I-1298J0D01*
G01X358267Y843677D01*
X357426Y842082D01*
X357465Y841994D01*
G02X357576Y841467I-1186J-525D01*
G02X354982I-1297J0D01*
G02X356044Y842743I1298J0D01*
G01X356139Y842761D01*
X356980Y844356D01*
X356941Y844444D01*
G02X356830Y844971I1186J525D01*
G37*
G36*
G01X364230D02*
G02X366824I1297J0D01*
G02X365762Y843695I-1298J0D01*
G01X365667Y843677D01*
X364826Y842082D01*
X364865Y841994D01*
G02X364976Y841467I-1186J-525D01*
G02X362382I-1297J0D01*
G02X363444Y842743I1298J0D01*
G01X363539Y842761D01*
X364380Y844356D01*
X364341Y844444D01*
G02X364230Y844971I1186J525D01*
G37*
G36*
G01X371630D02*
G02X374224I1297J0D01*
G02X373162Y843695I-1298J0D01*
G01X373067Y843677D01*
X372226Y842082D01*
X372265Y841994D01*
G02X372376Y841467I-1186J-525D01*
G02X369782I-1297J0D01*
G02X370844Y842743I1298J0D01*
G01X370939Y842761D01*
X371780Y844356D01*
X371741Y844444D01*
G02X371630Y844971I1186J525D01*
G37*
G36*
G01X379030D02*
G02X381624I1297J0D01*
G02X380562Y843695I-1298J0D01*
G01X380467Y843677D01*
X379626Y842082D01*
X379665Y841994D01*
G02X379776Y841467I-1186J-525D01*
G02X377182I-1297J0D01*
G02X378244Y842743I1298J0D01*
G01X378339Y842761D01*
X379180Y844356D01*
X379141Y844444D01*
G02X379030Y844971I1186J525D01*
G37*
G36*
G01X386430D02*
G02X389024I1297J0D01*
G02X387962Y843695I-1298J0D01*
G01X387867Y843677D01*
X387026Y842082D01*
X387065Y841994D01*
G02X387176Y841467I-1186J-525D01*
G02X384582I-1297J0D01*
G02X385644Y842743I1298J0D01*
G01X385739Y842761D01*
X386580Y844356D01*
X386541Y844444D01*
G02X386430Y844971I1186J525D01*
G37*
G36*
G01X393830D02*
G02X396424I1297J0D01*
G02X395362Y843695I-1298J0D01*
G01X395267Y843677D01*
X394426Y842082D01*
X394465Y841994D01*
G02X394576Y841467I-1186J-525D01*
G02X391982I-1297J0D01*
G02X393044Y842743I1298J0D01*
G01X393139Y842761D01*
X393980Y844356D01*
X393941Y844444D01*
G02X393830Y844971I1186J525D01*
G37*
G36*
G01X401230D02*
G02X403824I1297J0D01*
G02X402762Y843695I-1298J0D01*
G01X402667Y843677D01*
X401826Y842082D01*
X401865Y841994D01*
G02X401976Y841467I-1186J-525D01*
G02X399382I-1297J0D01*
G02X400444Y842743I1298J0D01*
G01X400539Y842761D01*
X401380Y844356D01*
X401341Y844444D01*
G02X401230Y844971I1186J525D01*
G37*
G36*
G01X408630D02*
G02X411224I1297J0D01*
G02X410162Y843695I-1298J0D01*
G01X410067Y843677D01*
X409226Y842082D01*
X409265Y841994D01*
G02X409376Y841467I-1186J-525D01*
G02X406782I-1297J0D01*
G02X407844Y842743I1298J0D01*
G01X407939Y842761D01*
X408780Y844356D01*
X408741Y844444D01*
G02X408630Y844971I1186J525D01*
G37*
G36*
G01X416030D02*
G02X418624I1297J0D01*
G02X417562Y843695I-1298J0D01*
G01X417467Y843677D01*
X416626Y842082D01*
X416665Y841994D01*
G02X416776Y841467I-1186J-525D01*
G02X414182I-1297J0D01*
G02X415244Y842743I1298J0D01*
G01X415339Y842761D01*
X416180Y844356D01*
X416141Y844444D01*
G02X416030Y844971I1186J525D01*
G37*
G36*
G01X423430D02*
G02X426024I1297J0D01*
G02X424962Y843695I-1298J0D01*
G01X424867Y843677D01*
X424026Y842082D01*
X424065Y841994D01*
G02X424176Y841467I-1186J-525D01*
G02X421582I-1297J0D01*
G02X422644Y842743I1298J0D01*
G01X422739Y842761D01*
X423580Y844356D01*
X423541Y844444D01*
G02X423430Y844971I1186J525D01*
G37*
G36*
G01X453030D02*
G02X455624I1297J0D01*
G02X454562Y843695I-1298J0D01*
G01X454467Y843677D01*
X453626Y842082D01*
X453665Y841994D01*
G02X453776Y841467I-1186J-525D01*
G02X451182I-1297J0D01*
G02X452244Y842743I1298J0D01*
G01X452339Y842761D01*
X453180Y844356D01*
X453141Y844444D01*
G02X453030Y844971I1186J525D01*
G37*
G36*
G01X460430D02*
G02X463024I1297J0D01*
G02X461962Y843695I-1298J0D01*
G01X461867Y843677D01*
X461026Y842082D01*
X461065Y841994D01*
G02X461176Y841467I-1186J-525D01*
G02X458582I-1297J0D01*
G02X459644Y842743I1298J0D01*
G01X459739Y842761D01*
X460580Y844356D01*
X460541Y844444D01*
G02X460430Y844971I1186J525D01*
G37*
G36*
G01X467830D02*
G02X470424I1297J0D01*
G02X469362Y843695I-1298J0D01*
G01X469267Y843677D01*
X468426Y842082D01*
X468465Y841994D01*
G02X468576Y841467I-1186J-525D01*
G02X465982I-1297J0D01*
G02X467044Y842743I1298J0D01*
G01X467139Y842761D01*
X467980Y844356D01*
X467941Y844444D01*
G02X467830Y844971I1186J525D01*
G37*
G36*
G01X475230D02*
G02X477824I1297J0D01*
G02X476762Y843695I-1298J0D01*
G01X476667Y843677D01*
X475826Y842082D01*
X475865Y841994D01*
G02X475976Y841467I-1186J-525D01*
G02X473382I-1297J0D01*
G02X474444Y842743I1298J0D01*
G01X474539Y842761D01*
X475380Y844356D01*
X475341Y844444D01*
G02X475230Y844971I1186J525D01*
G37*
G36*
G01X482630D02*
G02X485224I1297J0D01*
G02X484162Y843695I-1298J0D01*
G01X484067Y843677D01*
X483226Y842082D01*
X483265Y841994D01*
G02X483376Y841467I-1186J-525D01*
G02X480782I-1297J0D01*
G02X481844Y842743I1298J0D01*
G01X481939Y842761D01*
X482780Y844356D01*
X482741Y844444D01*
G02X482630Y844971I1186J525D01*
G37*
G36*
G01X490030D02*
G02X492624I1297J0D01*
G02X491519Y843688I-1297J0D01*
G01X491418Y843673D01*
X490608Y842112D01*
X490651Y842023D01*
G02X490776Y841467I-1174J-556D01*
G02X488180I-1298J0D01*
G02X489315Y842754I1297J0D01*
G01X489420Y842767D01*
X490213Y844297D01*
X490168Y844389D01*
G02X490030Y844971I1158J582D01*
G37*
G36*
G01X497430D02*
G02X500024I1297J0D01*
G02X498962Y843695I-1298J0D01*
G01X498867Y843677D01*
X498025Y842081D01*
X498064Y841993D01*
G02X498176Y841467I-1186J-527D01*
G02X495580I-1298J0D01*
G02X496644Y842743I1297J0D01*
G01X496739Y842761D01*
X497580Y844356D01*
X497541Y844444D01*
G02X497430Y844971I1186J525D01*
G37*
G36*
G01X504830D02*
G02X507424I1297J0D01*
G02X506362Y843695I-1298J0D01*
G01X506267Y843677D01*
X505426Y842082D01*
X505465Y841994D01*
G02X505576Y841467I-1186J-525D01*
G02X502982I-1297J0D01*
G02X504044Y842743I1298J0D01*
G01X504139Y842761D01*
X504980Y844356D01*
X504941Y844444D01*
G02X504830Y844971I1186J525D01*
G37*
G36*
G01X512230D02*
G02X514824I1297J0D01*
G02X513762Y843695I-1298J0D01*
G01X513667Y843677D01*
X512826Y842082D01*
X512865Y841994D01*
G02X512976Y841467I-1186J-525D01*
G02X510382I-1297J0D01*
G02X511444Y842743I1298J0D01*
G01X511539Y842761D01*
X512380Y844356D01*
X512341Y844444D01*
G02X512230Y844971I1186J525D01*
G37*
G36*
G01X519630D02*
G02X522224I1297J0D01*
G02X521162Y843695I-1298J0D01*
G01X521067Y843677D01*
X520226Y842082D01*
X520265Y841994D01*
G02X520376Y841467I-1186J-525D01*
G02X517782I-1297J0D01*
G02X518844Y842743I1298J0D01*
G01X518939Y842761D01*
X519780Y844356D01*
X519741Y844444D01*
G02X519630Y844971I1186J525D01*
G37*
G36*
G01X1332972D02*
G02X1335566I1297J0D01*
G02X1334504Y843695I-1298J0D01*
G01X1334409Y843677D01*
X1333568Y842082D01*
X1333607Y841994D01*
G02X1333718Y841467I-1186J-525D01*
G02X1331124I-1297J0D01*
G02X1332186Y842743I1298J0D01*
G01X1332281Y842761D01*
X1333122Y844356D01*
X1333083Y844444D01*
G02X1332972Y844971I1186J525D01*
G37*
G36*
G01X1340372D02*
G02X1342966I1297J0D01*
G02X1341904Y843695I-1298J0D01*
G01X1341809Y843677D01*
X1340968Y842082D01*
X1341007Y841994D01*
G02X1341118Y841467I-1186J-525D01*
G02X1338524I-1297J0D01*
G02X1339586Y842743I1298J0D01*
G01X1339681Y842761D01*
X1340522Y844356D01*
X1340483Y844444D01*
G02X1340372Y844971I1186J525D01*
G37*
G36*
G01X1347772D02*
G02X1350366I1297J0D01*
G02X1349304Y843695I-1298J0D01*
G01X1349209Y843677D01*
X1348368Y842082D01*
X1348407Y841994D01*
G02X1348518Y841467I-1186J-525D01*
G02X1345924I-1297J0D01*
G02X1346986Y842743I1298J0D01*
G01X1347081Y842761D01*
X1347922Y844356D01*
X1347883Y844444D01*
G02X1347772Y844971I1186J525D01*
G37*
G36*
G01X1355172D02*
G02X1357766I1297J0D01*
G02X1356704Y843695I-1298J0D01*
G01X1356609Y843677D01*
X1355768Y842082D01*
X1355807Y841994D01*
G02X1355918Y841467I-1186J-525D01*
G02X1353324I-1297J0D01*
G02X1354386Y842743I1298J0D01*
G01X1354481Y842761D01*
X1355322Y844356D01*
X1355283Y844444D01*
G02X1355172Y844971I1186J525D01*
G37*
G36*
G01X1362572D02*
G02X1365166I1297J0D01*
G02X1364104Y843695I-1298J0D01*
G01X1364009Y843677D01*
X1363168Y842082D01*
X1363207Y841994D01*
G02X1363318Y841467I-1186J-525D01*
G02X1360724I-1297J0D01*
G02X1361786Y842743I1298J0D01*
G01X1361881Y842761D01*
X1362722Y844356D01*
X1362683Y844444D01*
G02X1362572Y844971I1186J525D01*
G37*
G36*
G01X1369972D02*
G02X1372566I1297J0D01*
G02X1371504Y843695I-1298J0D01*
G01X1371409Y843677D01*
X1370568Y842082D01*
X1370607Y841994D01*
G02X1370718Y841467I-1186J-525D01*
G02X1368124I-1297J0D01*
G02X1369186Y842743I1298J0D01*
G01X1369281Y842761D01*
X1370122Y844356D01*
X1370083Y844444D01*
G02X1369972Y844971I1186J525D01*
G37*
G36*
G01X1377372D02*
G02X1379966I1297J0D01*
G02X1378904Y843695I-1298J0D01*
G01X1378809Y843677D01*
X1377968Y842082D01*
X1378007Y841994D01*
G02X1378118Y841467I-1186J-525D01*
G02X1375524I-1297J0D01*
G02X1376586Y842743I1298J0D01*
G01X1376681Y842761D01*
X1377522Y844356D01*
X1377483Y844444D01*
G02X1377372Y844971I1186J525D01*
G37*
G36*
G01X1384772D02*
G02X1387366I1297J0D01*
G02X1386304Y843695I-1298J0D01*
G01X1386209Y843677D01*
X1385368Y842082D01*
X1385407Y841994D01*
G02X1385518Y841467I-1186J-525D01*
G02X1382924I-1297J0D01*
G02X1383986Y842743I1298J0D01*
G01X1384081Y842761D01*
X1384922Y844356D01*
X1384883Y844444D01*
G02X1384772Y844971I1186J525D01*
G37*
G36*
G01X1392172D02*
G02X1394766I1297J0D01*
G02X1393704Y843695I-1298J0D01*
G01X1393609Y843677D01*
X1392768Y842082D01*
X1392807Y841994D01*
G02X1392918Y841467I-1186J-525D01*
G02X1390324I-1297J0D01*
G02X1391386Y842743I1298J0D01*
G01X1391481Y842761D01*
X1392322Y844356D01*
X1392283Y844444D01*
G02X1392172Y844971I1186J525D01*
G37*
G36*
G01X1399572D02*
G02X1402166I1297J0D01*
G02X1401104Y843695I-1298J0D01*
G01X1401009Y843677D01*
X1400168Y842082D01*
X1400207Y841994D01*
G02X1400318Y841467I-1186J-525D01*
G02X1397724I-1297J0D01*
G02X1398786Y842743I1298J0D01*
G01X1398881Y842761D01*
X1399722Y844356D01*
X1399683Y844444D01*
G02X1399572Y844971I1186J525D01*
G37*
G36*
G01X351280Y848176D02*
G02X353876I1298J0D01*
G02X353803Y847747I-1297J0D01*
G01X353772Y847661D01*
X354579Y846263D01*
X354669Y846246D01*
G02X355724Y844971I-243J-1275D01*
G02X353130I-1297J0D01*
G02X353202Y845400I1297J3D01*
G01X353233Y845486D01*
X352426Y846884D01*
X352336Y846901D01*
G02X351280Y848176I242J1275D01*
G37*
G36*
G01X358680D02*
G02X361276I1298J0D01*
G02X361203Y847747I-1297J0D01*
G01X361172Y847661D01*
X361979Y846263D01*
X362069Y846246D01*
G02X363124Y844971I-243J-1275D01*
G02X360530I-1297J0D01*
G02X360602Y845400I1297J3D01*
G01X360633Y845486D01*
X359826Y846884D01*
X359736Y846901D01*
G02X358680Y848176I242J1275D01*
G37*
G36*
G01X366080D02*
G02X368676I1298J0D01*
G02X368603Y847747I-1297J0D01*
G01X368572Y847661D01*
X369379Y846263D01*
X369469Y846246D01*
G02X370524Y844971I-243J-1275D01*
G02X367930I-1297J0D01*
G02X368002Y845400I1297J3D01*
G01X368033Y845486D01*
X367226Y846884D01*
X367136Y846901D01*
G02X366080Y848176I242J1275D01*
G37*
G36*
G01X373480D02*
G02X376076I1298J0D01*
G02X376003Y847747I-1297J0D01*
G01X375972Y847661D01*
X376779Y846263D01*
X376869Y846246D01*
G02X377924Y844971I-243J-1275D01*
G02X375330I-1297J0D01*
G02X375402Y845400I1297J3D01*
G01X375433Y845486D01*
X374626Y846884D01*
X374536Y846901D01*
G02X373480Y848176I242J1275D01*
G37*
G36*
G01X380880D02*
G02X383476I1298J0D01*
G02X383403Y847747I-1297J0D01*
G01X383372Y847661D01*
X384179Y846263D01*
X384269Y846246D01*
G02X385324Y844971I-243J-1275D01*
G02X382730I-1297J0D01*
G02X382802Y845400I1297J3D01*
G01X382833Y845486D01*
X382026Y846884D01*
X381936Y846901D01*
G02X380880Y848176I242J1275D01*
G37*
G36*
G01X388280D02*
G02X390876I1298J0D01*
G02X390803Y847747I-1297J0D01*
G01X390772Y847661D01*
X391579Y846263D01*
X391669Y846246D01*
G02X392724Y844971I-243J-1275D01*
G02X390130I-1297J0D01*
G02X390202Y845400I1297J3D01*
G01X390233Y845486D01*
X389426Y846884D01*
X389336Y846901D01*
G02X388280Y848176I242J1275D01*
G37*
G36*
G01X395680D02*
G02X398276I1298J0D01*
G02X398203Y847747I-1297J0D01*
G01X398172Y847661D01*
X398979Y846263D01*
X399069Y846246D01*
G02X400124Y844971I-243J-1275D01*
G02X397530I-1297J0D01*
G02X397602Y845400I1297J3D01*
G01X397633Y845486D01*
X396826Y846884D01*
X396736Y846901D01*
G02X395680Y848176I242J1275D01*
G37*
G36*
G01X403080D02*
G02X405676I1298J0D01*
G02X405603Y847747I-1297J0D01*
G01X405572Y847661D01*
X406379Y846263D01*
X406469Y846246D01*
G02X407524Y844971I-243J-1275D01*
G02X404930I-1297J0D01*
G02X405002Y845400I1297J3D01*
G01X405033Y845486D01*
X404226Y846884D01*
X404136Y846901D01*
G02X403080Y848176I242J1275D01*
G37*
G36*
G01X410480D02*
G02X413076I1298J0D01*
G02X413003Y847747I-1297J0D01*
G01X412972Y847661D01*
X413779Y846263D01*
X413869Y846246D01*
G02X414924Y844971I-243J-1275D01*
G02X412330I-1297J0D01*
G02X412402Y845400I1297J3D01*
G01X412433Y845486D01*
X411626Y846884D01*
X411536Y846901D01*
G02X410480Y848176I242J1275D01*
G37*
G36*
G01X417880D02*
G02X420476I1298J0D01*
G02X420403Y847747I-1297J0D01*
G01X420372Y847661D01*
X421179Y846263D01*
X421269Y846246D01*
G02X422324Y844971I-243J-1275D01*
G02X419730I-1297J0D01*
G02X419802Y845400I1297J3D01*
G01X419833Y845486D01*
X419026Y846884D01*
X418936Y846901D01*
G02X417880Y848176I242J1275D01*
G37*
G36*
G01X425280D02*
G02X427876I1298J0D01*
G02X427803Y847747I-1297J0D01*
G01X427772Y847661D01*
X428579Y846263D01*
X428669Y846246D01*
G02X429724Y844971I-243J-1275D01*
G02X427130I-1297J0D01*
G02X427202Y845400I1297J3D01*
G01X427233Y845486D01*
X426426Y846884D01*
X426336Y846901D01*
G02X425280Y848176I242J1275D01*
G37*
G36*
G01X430278Y849474D02*
G02X431317Y848954I0J-1298D01*
G01X432939D01*
G02X433978Y849474I1039J-778D01*
G02Y846878I0J-1298D01*
G02X432939Y847398I0J1298D01*
G01X431317D01*
G02X430278Y846878I-1039J778D01*
G02Y849474I0J1298D01*
G37*
G36*
G01X436380Y848176D02*
G02X438976I1298J0D01*
G02X437913Y846900I-1297J0D01*
G01X437818Y846882D01*
X436976Y845286D01*
X437015Y845197D01*
G02X437126Y844673I-1186J-525D01*
G01Y844671D01*
G02X434532I-1297J0D01*
G02X435594Y845947I1298J0D01*
G01X435689Y845965D01*
X436531Y847561D01*
X436492Y847650D01*
G02X436380Y848176I1186J527D01*
G37*
G36*
G01X447480D02*
G02X450076I1298J0D01*
G02X450003Y847748I-1298J1D01*
G01X449972Y847661D01*
X450780Y846263D01*
X450870Y846246D01*
G02X451926Y844971I-242J-1275D01*
G02X449330I-1298J0D01*
G02X449403Y845399I1298J-1D01*
G01X449434Y845486D01*
X448626Y846884D01*
X448536Y846901D01*
G02X447480Y848176I242J1275D01*
G37*
G36*
G01X454880D02*
G02X457476I1298J0D01*
G02X457403Y847747I-1297J0D01*
G01X457372Y847661D01*
X458179Y846263D01*
X458269Y846246D01*
G02X459324Y844971I-243J-1275D01*
G02X456730I-1297J0D01*
G02X456802Y845400I1297J3D01*
G01X456833Y845486D01*
X456026Y846884D01*
X455936Y846901D01*
G02X454880Y848176I242J1275D01*
G37*
G36*
G01X462280D02*
G02X464876I1298J0D01*
G02X464803Y847747I-1297J0D01*
G01X464772Y847661D01*
X465579Y846263D01*
X465669Y846246D01*
G02X466724Y844971I-243J-1275D01*
G02X464130I-1297J0D01*
G02X464202Y845400I1297J3D01*
G01X464233Y845486D01*
X463426Y846884D01*
X463336Y846901D01*
G02X462280Y848176I242J1275D01*
G37*
G36*
G01X469680D02*
G02X472276I1298J0D01*
G02X472203Y847747I-1297J0D01*
G01X472172Y847661D01*
X472979Y846263D01*
X473069Y846246D01*
G02X474124Y844971I-243J-1275D01*
G02X471530I-1297J0D01*
G02X471602Y845400I1297J3D01*
G01X471633Y845486D01*
X470826Y846884D01*
X470736Y846901D01*
G02X469680Y848176I242J1275D01*
G37*
G36*
G01X477080D02*
G02X479676I1298J0D01*
G02X479603Y847747I-1297J0D01*
G01X479572Y847661D01*
X480379Y846263D01*
X480469Y846246D01*
G02X481524Y844971I-243J-1275D01*
G02X478930I-1297J0D01*
G02X479002Y845400I1297J3D01*
G01X479033Y845486D01*
X478226Y846884D01*
X478136Y846901D01*
G02X477080Y848176I242J1275D01*
G37*
G36*
G01X484480D02*
G02X487076I1298J0D01*
G02X487003Y847747I-1297J0D01*
G01X486972Y847661D01*
X487779Y846263D01*
X487869Y846246D01*
G02X488924Y844971I-243J-1275D01*
G02X486330I-1297J0D01*
G02X486402Y845400I1297J3D01*
G01X486433Y845486D01*
X485626Y846884D01*
X485536Y846901D01*
G02X484480Y848176I242J1275D01*
G37*
G36*
G01X491880D02*
G02X494476I1298J0D01*
G02X494403Y847747I-1297J0D01*
G01X494372Y847661D01*
X495179Y846263D01*
X495269Y846246D01*
G02X496324Y844971I-243J-1275D01*
G02X493730I-1297J0D01*
G02X493802Y845400I1297J3D01*
G01X493833Y845486D01*
X493026Y846884D01*
X492936Y846901D01*
G02X491880Y848176I242J1275D01*
G37*
G36*
G01X499280D02*
G02X501876I1298J0D01*
G02X501803Y847747I-1297J0D01*
G01X501772Y847661D01*
X502579Y846263D01*
X502669Y846246D01*
G02X503724Y844971I-243J-1275D01*
G02X501130I-1297J0D01*
G02X501202Y845400I1297J3D01*
G01X501233Y845486D01*
X500426Y846884D01*
X500336Y846901D01*
G02X499280Y848176I242J1275D01*
G37*
G36*
G01X506680D02*
G02X509276I1298J0D01*
G02X509203Y847747I-1297J0D01*
G01X509172Y847661D01*
X509979Y846263D01*
X510069Y846246D01*
G02X511124Y844971I-243J-1275D01*
G02X508530I-1297J0D01*
G02X508602Y845400I1297J3D01*
G01X508633Y845486D01*
X507826Y846884D01*
X507736Y846901D01*
G02X506680Y848176I242J1275D01*
G37*
G36*
G01X514080D02*
G02X516676I1298J0D01*
G02X516603Y847747I-1297J0D01*
G01X516572Y847661D01*
X517379Y846263D01*
X517469Y846246D01*
G02X518524Y844971I-243J-1275D01*
G02X515930I-1297J0D01*
G02X516002Y845400I1297J3D01*
G01X516033Y845486D01*
X515226Y846884D01*
X515136Y846901D01*
G02X514080Y848176I242J1275D01*
G37*
G36*
G01X521480D02*
G02X524076I1298J0D01*
G02X524003Y847747I-1297J0D01*
G01X523972Y847661D01*
X524779Y846263D01*
X524869Y846246D01*
G02X525924Y844971I-243J-1275D01*
G02X523330I-1297J0D01*
G02X523402Y845400I1297J3D01*
G01X523433Y845486D01*
X522626Y846884D01*
X522536Y846901D01*
G02X521480Y848176I242J1275D01*
G37*
G36*
G01X526478Y849474D02*
G02X527517Y848954I0J-1298D01*
G01X529139D01*
G02X530178Y849474I1039J-778D01*
G02Y846878I0J-1298D01*
G02X529139Y847398I0J1298D01*
G01X527517D01*
G02X526478Y846878I-1039J778D01*
G02Y849474I0J1298D01*
G37*
G36*
G01X532580Y848176D02*
G02X535176I1298J0D01*
G02X534168Y846911I-1298J0D01*
G01X534079Y846891D01*
X533202Y845231D01*
X533236Y845145D01*
G02X533326Y844671I-1208J-475D01*
G02X530730I-1298J0D01*
G02X531738Y845936I1298J0D01*
G01X531827Y845956D01*
X532704Y847616D01*
X532670Y847702D01*
G02X532580Y848176I1208J475D01*
G37*
G36*
G01X1327422D02*
G02X1330018I1298J0D01*
G02X1329945Y847747I-1297J0D01*
G01X1329914Y847661D01*
X1330721Y846263D01*
X1330811Y846246D01*
G02X1331866Y844971I-243J-1275D01*
G02X1329272I-1297J0D01*
G02X1329344Y845400I1297J3D01*
G01X1329375Y845486D01*
X1328568Y846884D01*
X1328478Y846901D01*
G02X1327422Y848176I242J1275D01*
G37*
G36*
G01X1334822D02*
G02X1337418I1298J0D01*
G02X1337345Y847747I-1297J0D01*
G01X1337314Y847661D01*
X1338121Y846263D01*
X1338211Y846246D01*
G02X1339266Y844971I-243J-1275D01*
G02X1336672I-1297J0D01*
G02X1336744Y845400I1297J3D01*
G01X1336775Y845486D01*
X1335968Y846884D01*
X1335878Y846901D01*
G02X1334822Y848176I242J1275D01*
G37*
G36*
G01X1342222D02*
G02X1344818I1298J0D01*
G02X1344745Y847747I-1297J0D01*
G01X1344714Y847661D01*
X1345521Y846263D01*
X1345611Y846246D01*
G02X1346666Y844971I-243J-1275D01*
G02X1344072I-1297J0D01*
G02X1344144Y845400I1297J3D01*
G01X1344175Y845486D01*
X1343368Y846884D01*
X1343278Y846901D01*
G02X1342222Y848176I242J1275D01*
G37*
G36*
G01X1349622D02*
G02X1352218I1298J0D01*
G02X1352145Y847747I-1297J0D01*
G01X1352114Y847661D01*
X1352921Y846263D01*
X1353011Y846246D01*
G02X1354066Y844971I-243J-1275D01*
G02X1351472I-1297J0D01*
G02X1351544Y845400I1297J3D01*
G01X1351575Y845486D01*
X1350768Y846884D01*
X1350678Y846901D01*
G02X1349622Y848176I242J1275D01*
G37*
G36*
G01X1357022D02*
G02X1359618I1298J0D01*
G02X1359545Y847747I-1297J0D01*
G01X1359514Y847661D01*
X1360321Y846263D01*
X1360411Y846246D01*
G02X1361466Y844971I-243J-1275D01*
G02X1358872I-1297J0D01*
G02X1358944Y845400I1297J3D01*
G01X1358975Y845486D01*
X1358168Y846884D01*
X1358078Y846901D01*
G02X1357022Y848176I242J1275D01*
G37*
G36*
G01X1364422D02*
G02X1367018I1298J0D01*
G02X1366945Y847747I-1297J0D01*
G01X1366914Y847661D01*
X1367721Y846263D01*
X1367811Y846246D01*
G02X1368866Y844971I-243J-1275D01*
G02X1366272I-1297J0D01*
G02X1366344Y845400I1297J3D01*
G01X1366375Y845486D01*
X1365568Y846884D01*
X1365478Y846901D01*
G02X1364422Y848176I242J1275D01*
G37*
G36*
G01X1371822D02*
G02X1374418I1298J0D01*
G02X1374345Y847747I-1297J0D01*
G01X1374314Y847661D01*
X1375121Y846263D01*
X1375211Y846246D01*
G02X1376266Y844971I-243J-1275D01*
G02X1373672I-1297J0D01*
G02X1373744Y845400I1297J3D01*
G01X1373775Y845486D01*
X1372968Y846884D01*
X1372878Y846901D01*
G02X1371822Y848176I242J1275D01*
G37*
G36*
G01X1379222D02*
G02X1381818I1298J0D01*
G02X1381745Y847747I-1297J0D01*
G01X1381714Y847661D01*
X1382521Y846263D01*
X1382611Y846246D01*
G02X1383666Y844971I-243J-1275D01*
G02X1381072I-1297J0D01*
G02X1381144Y845400I1297J3D01*
G01X1381175Y845486D01*
X1380368Y846884D01*
X1380278Y846901D01*
G02X1379222Y848176I242J1275D01*
G37*
G36*
G01X1386622D02*
G02X1389218I1298J0D01*
G02X1389145Y847747I-1297J0D01*
G01X1389114Y847661D01*
X1389921Y846263D01*
X1390011Y846246D01*
G02X1391066Y844971I-243J-1275D01*
G02X1388472I-1297J0D01*
G02X1388544Y845400I1297J3D01*
G01X1388575Y845486D01*
X1387768Y846884D01*
X1387678Y846901D01*
G02X1386622Y848176I242J1275D01*
G37*
G36*
G01X1394022D02*
G02X1396618I1298J0D01*
G02X1396545Y847747I-1297J0D01*
G01X1396514Y847661D01*
X1397321Y846263D01*
X1397411Y846246D01*
G02X1398466Y844971I-243J-1275D01*
G02X1395872I-1297J0D01*
G02X1395944Y845400I1297J3D01*
G01X1395975Y845486D01*
X1395168Y846884D01*
X1395078Y846901D01*
G02X1394022Y848176I242J1275D01*
G37*
G36*
G01X1401422D02*
G02X1404018I1298J0D01*
G02X1403945Y847747I-1297J0D01*
G01X1403914Y847661D01*
X1404721Y846263D01*
X1404811Y846246D01*
G02X1405866Y844971I-243J-1275D01*
G02X1403272I-1297J0D01*
G02X1403344Y845400I1297J3D01*
G01X1403375Y845486D01*
X1402568Y846884D01*
X1402478Y846901D01*
G02X1401422Y848176I242J1275D01*
G37*
G36*
G01X1406420Y849474D02*
G02X1407459Y848954I0J-1298D01*
G01X1409081D01*
G02X1410120Y849474I1039J-778D01*
G02Y846878I0J-1298D01*
G02X1409081Y847398I0J1298D01*
G01X1407459D01*
G02X1406420Y846878I-1039J778D01*
G02Y849474I0J1298D01*
G37*
G36*
G01X1412522Y848176D02*
G02X1415118I1298J0D01*
G02X1414062Y846901I-1298J0D01*
G01X1413972Y846884D01*
X1413164Y845485D01*
X1413194Y845398D01*
G02X1413266Y844973I-1225J-426D01*
G01Y844971D01*
G02X1410672I-1297J0D01*
G02X1411728Y846246I1298J0D01*
G01X1411818Y846263D01*
X1412625Y847662D01*
X1412595Y847748D01*
G02X1412522Y848176I1225J429D01*
G37*
G36*
G01X349430Y851380D02*
G02X352024I1297J0D01*
G02X350969Y850105I-1298J0D01*
G01X350879Y850088D01*
X350072Y848691D01*
X350103Y848604D01*
G02X350176Y848176I-1225J-429D01*
G02X347580I-1298J0D01*
G02X348636Y849451I1298J0D01*
G01X348726Y849468D01*
X349533Y850865D01*
X349502Y850952D01*
G02X349430Y851380I1225J426D01*
G37*
G36*
G01X1325572D02*
G02X1328166I1297J0D01*
G02X1327111Y850105I-1298J0D01*
G01X1327021Y850088D01*
X1326214Y848691D01*
X1326245Y848604D01*
G02X1326318Y848176I-1225J-429D01*
G02X1323722I-1298J0D01*
G02X1324778Y849451I1298J0D01*
G01X1324868Y849468D01*
X1325675Y850865D01*
X1325644Y850952D01*
G02X1325572Y851380I1225J426D01*
G37*
G36*
G01X353132Y857789D02*
G02X355726I1297J0D01*
G02X355654Y857360I-1297J-3D01*
G01X355623Y857274D01*
X356430Y855876D01*
X356520Y855859D01*
G02X357576Y854584I-242J-1275D01*
G02X354980I-1298J0D01*
G02X355053Y855013I1297J0D01*
G01X355084Y855099D01*
X354277Y856497D01*
X354187Y856514D01*
G02X353132Y857789I243J1275D01*
G37*
G36*
G01X360532D02*
G02X363126I1297J0D01*
G02X363054Y857360I-1297J-3D01*
G01X363023Y857274D01*
X363830Y855876D01*
X363920Y855859D01*
G02X364976Y854584I-242J-1275D01*
G02X362380I-1298J0D01*
G02X362453Y855013I1297J0D01*
G01X362484Y855099D01*
X361677Y856497D01*
X361587Y856514D01*
G02X360532Y857789I243J1275D01*
G37*
G36*
G01X367932D02*
G02X370526I1297J0D01*
G02X370454Y857360I-1297J-3D01*
G01X370423Y857274D01*
X371230Y855876D01*
X371320Y855859D01*
G02X372376Y854584I-242J-1275D01*
G02X369780I-1298J0D01*
G02X369853Y855013I1297J0D01*
G01X369884Y855099D01*
X369077Y856497D01*
X368987Y856514D01*
G02X367932Y857789I243J1275D01*
G37*
G36*
G01X375332D02*
G02X377926I1297J0D01*
G02X377854Y857360I-1297J-3D01*
G01X377823Y857274D01*
X378630Y855876D01*
X378720Y855859D01*
G02X379776Y854584I-242J-1275D01*
G02X377180I-1298J0D01*
G02X377253Y855013I1297J0D01*
G01X377284Y855099D01*
X376477Y856497D01*
X376387Y856514D01*
G02X375332Y857789I243J1275D01*
G37*
G36*
G01X382732D02*
G02X385326I1297J0D01*
G02X385254Y857360I-1297J-3D01*
G01X385223Y857274D01*
X386030Y855876D01*
X386120Y855859D01*
G02X387176Y854584I-242J-1275D01*
G02X384580I-1298J0D01*
G02X384653Y855013I1297J0D01*
G01X384684Y855099D01*
X383877Y856497D01*
X383787Y856514D01*
G02X382732Y857789I243J1275D01*
G37*
G36*
G01X390132D02*
G02X392726I1297J0D01*
G02X392654Y857360I-1297J-3D01*
G01X392623Y857274D01*
X393430Y855876D01*
X393520Y855859D01*
G02X394576Y854584I-242J-1275D01*
G02X391980I-1298J0D01*
G02X392053Y855013I1297J0D01*
G01X392084Y855099D01*
X391277Y856497D01*
X391187Y856514D01*
G02X390132Y857789I243J1275D01*
G37*
G36*
G01X397532D02*
G02X400126I1297J0D01*
G02X400054Y857360I-1297J-3D01*
G01X400023Y857274D01*
X400830Y855876D01*
X400920Y855859D01*
G02X401976Y854584I-242J-1275D01*
G02X399380I-1298J0D01*
G02X399453Y855013I1297J0D01*
G01X399484Y855099D01*
X398677Y856497D01*
X398587Y856514D01*
G02X397532Y857789I243J1275D01*
G37*
G36*
G01X404932D02*
G02X407526I1297J0D01*
G02X407454Y857360I-1297J-3D01*
G01X407423Y857274D01*
X408230Y855876D01*
X408320Y855859D01*
G02X409376Y854584I-242J-1275D01*
G02X406780I-1298J0D01*
G02X406853Y855013I1297J0D01*
G01X406884Y855099D01*
X406077Y856497D01*
X405987Y856514D01*
G02X404932Y857789I243J1275D01*
G37*
G36*
G01X412332D02*
G02X414926I1297J0D01*
G02X414854Y857360I-1297J-3D01*
G01X414823Y857274D01*
X415630Y855876D01*
X415720Y855859D01*
G02X416776Y854584I-242J-1275D01*
G02X414180I-1298J0D01*
G02X414253Y855013I1297J0D01*
G01X414284Y855099D01*
X413477Y856497D01*
X413387Y856514D01*
G02X412332Y857789I243J1275D01*
G37*
G36*
G01X419732D02*
G02X422326I1297J0D01*
G02X422254Y857360I-1297J-3D01*
G01X422223Y857274D01*
X423030Y855876D01*
X423120Y855859D01*
G02X424176Y854584I-242J-1275D01*
G02X421580I-1298J0D01*
G02X421653Y855013I1297J0D01*
G01X421684Y855099D01*
X420877Y856497D01*
X420787Y856514D01*
G02X419732Y857789I243J1275D01*
G37*
G36*
G01X427132D02*
G02X429726I1297J0D01*
G02X429654Y857360I-1297J-3D01*
G01X429623Y857274D01*
X430430Y855876D01*
X430520Y855859D01*
G02X431576Y854584I-242J-1275D01*
G02X428980I-1298J0D01*
G02X429053Y855013I1297J0D01*
G01X429084Y855099D01*
X428277Y856497D01*
X428187Y856514D01*
G02X427132Y857789I243J1275D01*
G37*
G36*
G01X434532D02*
G02X437126I1297J0D01*
G02X437054Y857360I-1297J-3D01*
G01X437023Y857274D01*
X437830Y855876D01*
X437920Y855859D01*
G02X438976Y854584I-242J-1275D01*
G02X436382I-1297J0D01*
G02X436454Y855012I1297J2D01*
G01X436484Y855098D01*
X435677Y856497D01*
X435587Y856514D01*
G02X434532Y857789I243J1275D01*
G37*
G36*
G01X445632D02*
G02X448226I1297J0D01*
G02X447171Y856514I-1298J0D01*
G01X447081Y856497D01*
X446273Y855098D01*
X446303Y855011D01*
G02X446376Y854584I-1225J-429D01*
G02X443780I-1298J0D01*
G02X444838Y855859I1297J0D01*
G01X444928Y855876D01*
X445735Y857274D01*
X445704Y857361D01*
G02X445632Y857789I1225J426D01*
G37*
G36*
G01X453032D02*
G02X455626I1297J0D01*
G02X454571Y856514I-1298J0D01*
G01X454481Y856497D01*
X453673Y855098D01*
X453703Y855011D01*
G02X453776Y854584I-1225J-429D01*
G02X451180I-1298J0D01*
G02X452238Y855859I1297J0D01*
G01X452328Y855876D01*
X453135Y857274D01*
X453104Y857361D01*
G02X453032Y857789I1225J426D01*
G37*
G36*
G01X460432D02*
G02X463026I1297J0D01*
G02X461971Y856514I-1298J0D01*
G01X461881Y856497D01*
X461073Y855098D01*
X461103Y855011D01*
G02X461176Y854584I-1225J-429D01*
G02X458580I-1298J0D01*
G02X459638Y855859I1297J0D01*
G01X459728Y855876D01*
X460535Y857274D01*
X460504Y857361D01*
G02X460432Y857789I1225J426D01*
G37*
G36*
G01X467832D02*
G02X470426I1297J0D01*
G02X469371Y856514I-1298J0D01*
G01X469281Y856497D01*
X468473Y855098D01*
X468503Y855011D01*
G02X468576Y854584I-1225J-429D01*
G02X465980I-1298J0D01*
G02X467038Y855859I1297J0D01*
G01X467128Y855876D01*
X467935Y857274D01*
X467904Y857361D01*
G02X467832Y857789I1225J426D01*
G37*
G36*
G01X475232D02*
G02X477826I1297J0D01*
G02X476771Y856514I-1298J0D01*
G01X476681Y856497D01*
X475873Y855098D01*
X475903Y855011D01*
G02X475976Y854584I-1225J-429D01*
G02X473380I-1298J0D01*
G02X474438Y855859I1297J0D01*
G01X474528Y855876D01*
X475335Y857274D01*
X475304Y857361D01*
G02X475232Y857789I1225J426D01*
G37*
G36*
G01X482632D02*
G02X485226I1297J0D01*
G02X484171Y856514I-1298J0D01*
G01X484081Y856497D01*
X483273Y855098D01*
X483303Y855011D01*
G02X483376Y854584I-1225J-429D01*
G02X480780I-1298J0D01*
G02X481838Y855859I1297J0D01*
G01X481928Y855876D01*
X482735Y857274D01*
X482704Y857361D01*
G02X482632Y857789I1225J426D01*
G37*
G36*
G01X490032D02*
G02X492626I1297J0D01*
G02X491571Y856514I-1298J0D01*
G01X491481Y856497D01*
X490673Y855098D01*
X490703Y855011D01*
G02X490776Y854584I-1225J-429D01*
G02X488180I-1298J0D01*
G02X489238Y855859I1297J0D01*
G01X489328Y855876D01*
X490135Y857274D01*
X490104Y857361D01*
G02X490032Y857789I1225J426D01*
G37*
G36*
G01X497432D02*
G02X500026I1297J0D01*
G02X498971Y856514I-1298J0D01*
G01X498881Y856497D01*
X498073Y855098D01*
X498103Y855011D01*
G02X498176Y854584I-1225J-429D01*
G02X495580I-1298J0D01*
G02X496638Y855859I1297J0D01*
G01X496728Y855876D01*
X497535Y857274D01*
X497504Y857361D01*
G02X497432Y857789I1225J426D01*
G37*
G36*
G01X504832D02*
G02X507426I1297J0D01*
G02X506371Y856514I-1298J0D01*
G01X506281Y856497D01*
X505473Y855098D01*
X505503Y855011D01*
G02X505576Y854584I-1225J-429D01*
G02X502980I-1298J0D01*
G02X504038Y855859I1297J0D01*
G01X504128Y855876D01*
X504935Y857274D01*
X504904Y857361D01*
G02X504832Y857789I1225J426D01*
G37*
G36*
G01X512232D02*
G02X514826I1297J0D01*
G02X513771Y856514I-1298J0D01*
G01X513681Y856497D01*
X512873Y855098D01*
X512903Y855011D01*
G02X512976Y854584I-1225J-429D01*
G02X510380I-1298J0D01*
G02X511438Y855859I1297J0D01*
G01X511528Y855876D01*
X512335Y857274D01*
X512304Y857361D01*
G02X512232Y857789I1225J426D01*
G37*
G36*
G01X519632D02*
G02X522226I1297J0D01*
G02X521171Y856514I-1298J0D01*
G01X521081Y856497D01*
X520273Y855098D01*
X520303Y855011D01*
G02X520376Y854584I-1225J-429D01*
G02X517780I-1298J0D01*
G02X518838Y855859I1297J0D01*
G01X518928Y855876D01*
X519735Y857274D01*
X519704Y857361D01*
G02X519632Y857789I1225J426D01*
G37*
G36*
G01X527032D02*
G02X529626I1297J0D01*
G02X528571Y856514I-1298J0D01*
G01X528481Y856497D01*
X527673Y855098D01*
X527703Y855011D01*
G02X527776Y854584I-1225J-429D01*
G02X525180I-1298J0D01*
G02X526238Y855859I1297J0D01*
G01X526328Y855876D01*
X527135Y857274D01*
X527104Y857361D01*
G02X527032Y857789I1225J426D01*
G37*
G36*
G01X1329274D02*
G02X1331868I1297J0D01*
G02X1331796Y857360I-1297J-3D01*
G01X1331765Y857274D01*
X1332572Y855876D01*
X1332662Y855859D01*
G02X1333718Y854584I-242J-1275D01*
G02X1331122I-1298J0D01*
G02X1331195Y855013I1297J0D01*
G01X1331226Y855099D01*
X1330419Y856497D01*
X1330329Y856514D01*
G02X1329274Y857789I243J1275D01*
G37*
G36*
G01X1336674D02*
G02X1339268I1297J0D01*
G02X1339196Y857360I-1297J-3D01*
G01X1339165Y857274D01*
X1339972Y855876D01*
X1340062Y855859D01*
G02X1341118Y854584I-242J-1275D01*
G02X1338522I-1298J0D01*
G02X1338595Y855013I1297J0D01*
G01X1338626Y855099D01*
X1337819Y856497D01*
X1337729Y856514D01*
G02X1336674Y857789I243J1275D01*
G37*
G36*
G01X1344074D02*
G02X1346668I1297J0D01*
G02X1346596Y857360I-1297J-3D01*
G01X1346565Y857274D01*
X1347372Y855876D01*
X1347462Y855859D01*
G02X1348518Y854584I-242J-1275D01*
G02X1345922I-1298J0D01*
G02X1345995Y855013I1297J0D01*
G01X1346026Y855099D01*
X1345219Y856497D01*
X1345129Y856514D01*
G02X1344074Y857789I243J1275D01*
G37*
G36*
G01X1351474D02*
G02X1354068I1297J0D01*
G02X1353996Y857360I-1297J-3D01*
G01X1353965Y857274D01*
X1354772Y855876D01*
X1354862Y855859D01*
G02X1355918Y854584I-242J-1275D01*
G02X1353322I-1298J0D01*
G02X1353395Y855013I1297J0D01*
G01X1353426Y855099D01*
X1352619Y856497D01*
X1352529Y856514D01*
G02X1351474Y857789I243J1275D01*
G37*
G36*
G01X1358874D02*
G02X1361468I1297J0D01*
G02X1361396Y857360I-1297J-3D01*
G01X1361365Y857274D01*
X1362172Y855876D01*
X1362262Y855859D01*
G02X1363318Y854584I-242J-1275D01*
G02X1360722I-1298J0D01*
G02X1360795Y855013I1297J0D01*
G01X1360826Y855099D01*
X1360019Y856497D01*
X1359929Y856514D01*
G02X1358874Y857789I243J1275D01*
G37*
G36*
G01X1366274D02*
G02X1368868I1297J0D01*
G02X1368796Y857360I-1297J-3D01*
G01X1368765Y857274D01*
X1369572Y855876D01*
X1369662Y855859D01*
G02X1370718Y854584I-242J-1275D01*
G02X1368122I-1298J0D01*
G02X1368195Y855013I1297J0D01*
G01X1368226Y855099D01*
X1367419Y856497D01*
X1367329Y856514D01*
G02X1366274Y857789I243J1275D01*
G37*
G36*
G01X1373674D02*
G02X1376268I1297J0D01*
G02X1376196Y857360I-1297J-3D01*
G01X1376165Y857274D01*
X1376972Y855876D01*
X1377062Y855859D01*
G02X1378118Y854584I-242J-1275D01*
G02X1375522I-1298J0D01*
G02X1375595Y855013I1297J0D01*
G01X1375626Y855099D01*
X1374819Y856497D01*
X1374729Y856514D01*
G02X1373674Y857789I243J1275D01*
G37*
G36*
G01X1381074D02*
G02X1383668I1297J0D01*
G02X1383596Y857360I-1297J-3D01*
G01X1383565Y857274D01*
X1384372Y855876D01*
X1384462Y855859D01*
G02X1385518Y854584I-242J-1275D01*
G02X1382922I-1298J0D01*
G02X1382995Y855013I1297J0D01*
G01X1383026Y855099D01*
X1382219Y856497D01*
X1382129Y856514D01*
G02X1381074Y857789I243J1275D01*
G37*
G36*
G01X1388474D02*
G02X1391068I1297J0D01*
G02X1390996Y857360I-1297J-3D01*
G01X1390965Y857274D01*
X1391772Y855876D01*
X1391862Y855859D01*
G02X1392918Y854584I-242J-1275D01*
G02X1390322I-1298J0D01*
G02X1390395Y855013I1297J0D01*
G01X1390426Y855099D01*
X1389619Y856497D01*
X1389529Y856514D01*
G02X1388474Y857789I243J1275D01*
G37*
G36*
G01X1395874D02*
G02X1398468I1297J0D01*
G02X1398396Y857360I-1297J-3D01*
G01X1398365Y857274D01*
X1399172Y855876D01*
X1399262Y855859D01*
G02X1400318Y854584I-242J-1275D01*
G02X1397722I-1298J0D01*
G02X1397795Y855013I1297J0D01*
G01X1397826Y855099D01*
X1397019Y856497D01*
X1396929Y856514D01*
G02X1395874Y857789I243J1275D01*
G37*
G36*
G01X1403274D02*
G02X1405868I1297J0D01*
G02X1405796Y857360I-1297J-3D01*
G01X1405765Y857274D01*
X1406572Y855876D01*
X1406662Y855859D01*
G02X1407718Y854584I-242J-1275D01*
G02X1405122I-1298J0D01*
G02X1405195Y855013I1297J0D01*
G01X1405226Y855099D01*
X1404419Y856497D01*
X1404329Y856514D01*
G02X1403274Y857789I243J1275D01*
G37*
G36*
G01X1410674D02*
G02X1413268I1297J0D01*
G02X1413196Y857360I-1297J-3D01*
G01X1413165Y857274D01*
X1413972Y855876D01*
X1414062Y855859D01*
G02X1415118Y854584I-242J-1275D01*
G02X1412524I-1297J0D01*
G02X1412596Y855012I1297J2D01*
G01X1412626Y855098D01*
X1411819Y856497D01*
X1411729Y856514D01*
G02X1410674Y857789I243J1275D01*
G37*
G36*
G01X1421774D02*
G02X1424368I1297J0D01*
G02X1423313Y856514I-1298J0D01*
G01X1423223Y856497D01*
X1422415Y855098D01*
X1422445Y855011D01*
G02X1422518Y854584I-1225J-429D01*
G02X1419922I-1298J0D01*
G02X1420980Y855859I1297J0D01*
G01X1421070Y855876D01*
X1421877Y857274D01*
X1421846Y857361D01*
G02X1421774Y857789I1225J426D01*
G37*
G36*
G01X1429174D02*
G02X1431768I1297J0D01*
G02X1430713Y856514I-1298J0D01*
G01X1430623Y856497D01*
X1429815Y855098D01*
X1429845Y855011D01*
G02X1429918Y854584I-1225J-429D01*
G02X1427322I-1298J0D01*
G02X1428380Y855859I1297J0D01*
G01X1428470Y855876D01*
X1429277Y857274D01*
X1429246Y857361D01*
G02X1429174Y857789I1225J426D01*
G37*
G36*
G01X1436574D02*
G02X1439168I1297J0D01*
G02X1438113Y856514I-1298J0D01*
G01X1438023Y856497D01*
X1437215Y855098D01*
X1437245Y855011D01*
G02X1437318Y854584I-1225J-429D01*
G02X1434722I-1298J0D01*
G02X1435780Y855859I1297J0D01*
G01X1435870Y855876D01*
X1436677Y857274D01*
X1436646Y857361D01*
G02X1436574Y857789I1225J426D01*
G37*
G36*
G01X1443974D02*
G02X1446568I1297J0D01*
G02X1445513Y856514I-1298J0D01*
G01X1445423Y856497D01*
X1444615Y855098D01*
X1444645Y855011D01*
G02X1444718Y854584I-1225J-429D01*
G02X1442122I-1298J0D01*
G02X1443180Y855859I1297J0D01*
G01X1443270Y855876D01*
X1444077Y857274D01*
X1444046Y857361D01*
G02X1443974Y857789I1225J426D01*
G37*
G36*
G01X1451374D02*
G02X1453968I1297J0D01*
G02X1452913Y856514I-1298J0D01*
G01X1452823Y856497D01*
X1452015Y855098D01*
X1452045Y855011D01*
G02X1452118Y854584I-1225J-429D01*
G02X1449522I-1298J0D01*
G02X1450580Y855859I1297J0D01*
G01X1450670Y855876D01*
X1451477Y857274D01*
X1451446Y857361D01*
G02X1451374Y857789I1225J426D01*
G37*
G36*
G01X1458774D02*
G02X1461368I1297J0D01*
G02X1460313Y856514I-1298J0D01*
G01X1460223Y856497D01*
X1459415Y855098D01*
X1459445Y855011D01*
G02X1459518Y854584I-1225J-429D01*
G02X1456922I-1298J0D01*
G02X1457980Y855859I1297J0D01*
G01X1458070Y855876D01*
X1458877Y857274D01*
X1458846Y857361D01*
G02X1458774Y857789I1225J426D01*
G37*
G36*
G01X1466174D02*
G02X1468768I1297J0D01*
G02X1467713Y856514I-1298J0D01*
G01X1467623Y856497D01*
X1466815Y855098D01*
X1466845Y855011D01*
G02X1466918Y854584I-1225J-429D01*
G02X1464322I-1298J0D01*
G02X1465380Y855859I1297J0D01*
G01X1465470Y855876D01*
X1466277Y857274D01*
X1466246Y857361D01*
G02X1466174Y857789I1225J426D01*
G37*
G36*
G01X1473574D02*
G02X1476168I1297J0D01*
G02X1475113Y856514I-1298J0D01*
G01X1475023Y856497D01*
X1474215Y855098D01*
X1474245Y855011D01*
G02X1474318Y854584I-1225J-429D01*
G02X1471722I-1298J0D01*
G02X1472780Y855859I1297J0D01*
G01X1472870Y855876D01*
X1473677Y857274D01*
X1473646Y857361D01*
G02X1473574Y857789I1225J426D01*
G37*
G36*
G01X1480974D02*
G02X1483568I1297J0D01*
G02X1482513Y856514I-1298J0D01*
G01X1482423Y856497D01*
X1481615Y855098D01*
X1481645Y855011D01*
G02X1481718Y854584I-1225J-429D01*
G02X1479122I-1298J0D01*
G02X1480180Y855859I1297J0D01*
G01X1480270Y855876D01*
X1481077Y857274D01*
X1481046Y857361D01*
G02X1480974Y857789I1225J426D01*
G37*
G36*
G01X1488374D02*
G02X1490968I1297J0D01*
G02X1489913Y856514I-1298J0D01*
G01X1489823Y856497D01*
X1489015Y855098D01*
X1489045Y855011D01*
G02X1489118Y854584I-1225J-429D01*
G02X1486522I-1298J0D01*
G02X1487580Y855859I1297J0D01*
G01X1487670Y855876D01*
X1488477Y857274D01*
X1488446Y857361D01*
G02X1488374Y857789I1225J426D01*
G37*
G36*
G01X1495774D02*
G02X1498368I1297J0D01*
G02X1497313Y856514I-1298J0D01*
G01X1497223Y856497D01*
X1496415Y855098D01*
X1496445Y855011D01*
G02X1496518Y854584I-1225J-429D01*
G02X1493922I-1298J0D01*
G02X1494980Y855859I1297J0D01*
G01X1495070Y855876D01*
X1495877Y857274D01*
X1495846Y857361D01*
G02X1495774Y857789I1225J426D01*
G37*
G36*
G01X1503174D02*
G02X1505768I1297J0D01*
G02X1504713Y856514I-1298J0D01*
G01X1504623Y856497D01*
X1503815Y855098D01*
X1503845Y855011D01*
G02X1503918Y854584I-1225J-429D01*
G02X1501322I-1298J0D01*
G02X1502380Y855859I1297J0D01*
G01X1502470Y855876D01*
X1503277Y857274D01*
X1503246Y857361D01*
G02X1503174Y857789I1225J426D01*
G37*
G36*
G01X351280Y860993D02*
G02X353876I1298J0D01*
G02X352820Y859718I-1298J0D01*
G01X352730Y859701D01*
X351923Y858304D01*
X351954Y858217D01*
G02X352026Y857789I-1225J-426D01*
G02X349432I-1297J0D01*
G02X350487Y859064I1298J0D01*
G01X350577Y859081D01*
X351384Y860478D01*
X351353Y860565D01*
G02X351280Y860993I1225J429D01*
G37*
G36*
G01X358680D02*
G02X361276I1298J0D01*
G02X360220Y859718I-1298J0D01*
G01X360130Y859701D01*
X359323Y858304D01*
X359354Y858217D01*
G02X359426Y857789I-1225J-426D01*
G02X356832I-1297J0D01*
G02X357887Y859064I1298J0D01*
G01X357977Y859081D01*
X358784Y860478D01*
X358753Y860565D01*
G02X358680Y860993I1225J429D01*
G37*
G36*
G01X366080D02*
G02X368676I1298J0D01*
G02X367620Y859718I-1298J0D01*
G01X367530Y859701D01*
X366723Y858304D01*
X366754Y858217D01*
G02X366826Y857789I-1225J-426D01*
G02X364232I-1297J0D01*
G02X365287Y859064I1298J0D01*
G01X365377Y859081D01*
X366184Y860478D01*
X366153Y860565D01*
G02X366080Y860993I1225J429D01*
G37*
G36*
G01X373480D02*
G02X376076I1298J0D01*
G02X375020Y859718I-1298J0D01*
G01X374930Y859701D01*
X374123Y858304D01*
X374154Y858217D01*
G02X374226Y857789I-1225J-426D01*
G02X371632I-1297J0D01*
G02X372687Y859064I1298J0D01*
G01X372777Y859081D01*
X373584Y860478D01*
X373553Y860565D01*
G02X373480Y860993I1225J429D01*
G37*
G36*
G01X380880D02*
G02X383476I1298J0D01*
G02X382420Y859718I-1298J0D01*
G01X382330Y859701D01*
X381523Y858304D01*
X381554Y858217D01*
G02X381626Y857789I-1225J-426D01*
G02X379032I-1297J0D01*
G02X380087Y859064I1298J0D01*
G01X380177Y859081D01*
X380984Y860478D01*
X380953Y860565D01*
G02X380880Y860993I1225J429D01*
G37*
G36*
G01X388280D02*
G02X390876I1298J0D01*
G02X389820Y859718I-1298J0D01*
G01X389730Y859701D01*
X388923Y858304D01*
X388954Y858217D01*
G02X389026Y857789I-1225J-426D01*
G02X386432I-1297J0D01*
G02X387487Y859064I1298J0D01*
G01X387577Y859081D01*
X388384Y860478D01*
X388353Y860565D01*
G02X388280Y860993I1225J429D01*
G37*
G36*
G01X395680D02*
G02X398276I1298J0D01*
G02X397220Y859718I-1298J0D01*
G01X397130Y859701D01*
X396323Y858304D01*
X396354Y858217D01*
G02X396426Y857789I-1225J-426D01*
G02X393832I-1297J0D01*
G02X394887Y859064I1298J0D01*
G01X394977Y859081D01*
X395784Y860478D01*
X395753Y860565D01*
G02X395680Y860993I1225J429D01*
G37*
G36*
G01X403080D02*
G02X405676I1298J0D01*
G02X404620Y859718I-1298J0D01*
G01X404530Y859701D01*
X403723Y858304D01*
X403754Y858217D01*
G02X403826Y857789I-1225J-426D01*
G02X401232I-1297J0D01*
G02X402287Y859064I1298J0D01*
G01X402377Y859081D01*
X403184Y860478D01*
X403153Y860565D01*
G02X403080Y860993I1225J429D01*
G37*
G36*
G01X410480D02*
G02X413076I1298J0D01*
G02X412020Y859718I-1298J0D01*
G01X411930Y859701D01*
X411123Y858304D01*
X411154Y858217D01*
G02X411226Y857789I-1225J-426D01*
G02X408632I-1297J0D01*
G02X409687Y859064I1298J0D01*
G01X409777Y859081D01*
X410584Y860478D01*
X410553Y860565D01*
G02X410480Y860993I1225J429D01*
G37*
G36*
G01X417880D02*
G02X420476I1298J0D01*
G02X419420Y859718I-1298J0D01*
G01X419330Y859701D01*
X418523Y858304D01*
X418554Y858217D01*
G02X418626Y857789I-1225J-426D01*
G02X416032I-1297J0D01*
G02X417087Y859064I1298J0D01*
G01X417177Y859081D01*
X417984Y860478D01*
X417953Y860565D01*
G02X417880Y860993I1225J429D01*
G37*
G36*
G01X425280D02*
G02X427876I1298J0D01*
G02X426820Y859718I-1298J0D01*
G01X426730Y859701D01*
X425923Y858304D01*
X425954Y858217D01*
G02X426026Y857789I-1225J-426D01*
G02X423432I-1297J0D01*
G02X424487Y859064I1298J0D01*
G01X424577Y859081D01*
X425384Y860478D01*
X425353Y860565D01*
G02X425280Y860993I1225J429D01*
G37*
G36*
G01X432682D02*
G02X435276I1297J0D01*
G02X434221Y859718I-1298J0D01*
G01X434131Y859701D01*
X433324Y858303D01*
X433354Y858217D01*
G02X433426Y857789I-1225J-426D01*
G02X430832I-1297J0D01*
G02X431888Y859064I1298J0D01*
G01X431978Y859081D01*
X432785Y860478D01*
X432754Y860565D01*
G02X432682Y860993I1225J426D01*
G37*
G36*
G01X440080D02*
G02X442676I1298J0D01*
G02X442603Y860564I-1297J0D01*
G01X442572Y860478D01*
X443378Y859081D01*
X443468Y859064D01*
G02X444526Y857789I-239J-1275D01*
G02X441932I-1297J0D01*
G02X442003Y858215I1297J3D01*
G01X442034Y858302D01*
X441226Y859701D01*
X441136Y859718D01*
G02X440080Y860993I242J1275D01*
G37*
G36*
G01X447482D02*
G02X450076I1297J0D01*
G02X450004Y860564I-1297J-3D01*
G01X449973Y860478D01*
X450779Y859081D01*
X450869Y859064D01*
G02X451926Y857789I-240J-1275D01*
G02X449332I-1297J0D01*
G01Y857791D01*
G02X449404Y858216I1297J-1D01*
G01X449434Y858303D01*
X448627Y859701D01*
X448537Y859718D01*
G02X447482Y860993I243J1275D01*
G37*
G36*
G01X454880D02*
G02X457476I1298J0D01*
G02X457403Y860564I-1297J0D01*
G01X457372Y860478D01*
X458178Y859081D01*
X458268Y859064D01*
G02X459326Y857789I-239J-1275D01*
G02X456732I-1297J0D01*
G02X456803Y858215I1297J3D01*
G01X456834Y858302D01*
X456026Y859701D01*
X455936Y859718D01*
G02X454880Y860993I242J1275D01*
G37*
G36*
G01X462280D02*
G02X464876I1298J0D01*
G02X464803Y860564I-1297J0D01*
G01X464772Y860478D01*
X465578Y859081D01*
X465668Y859064D01*
G02X466726Y857789I-239J-1275D01*
G02X464132I-1297J0D01*
G02X464203Y858215I1297J3D01*
G01X464234Y858302D01*
X463426Y859701D01*
X463336Y859718D01*
G02X462280Y860993I242J1275D01*
G37*
G36*
G01X469680D02*
G02X472276I1298J0D01*
G02X472203Y860564I-1297J0D01*
G01X472172Y860478D01*
X472978Y859081D01*
X473068Y859064D01*
G02X474126Y857789I-239J-1275D01*
G02X471532I-1297J0D01*
G02X471603Y858215I1297J3D01*
G01X471634Y858302D01*
X470826Y859701D01*
X470736Y859718D01*
G02X469680Y860993I242J1275D01*
G37*
G36*
G01X477080D02*
G02X479676I1298J0D01*
G02X479603Y860564I-1297J0D01*
G01X479572Y860478D01*
X480378Y859081D01*
X480468Y859064D01*
G02X481526Y857789I-239J-1275D01*
G02X478932I-1297J0D01*
G02X479003Y858215I1297J3D01*
G01X479034Y858302D01*
X478226Y859701D01*
X478136Y859718D01*
G02X477080Y860993I242J1275D01*
G37*
G36*
G01X484480D02*
G02X487076I1298J0D01*
G02X487003Y860564I-1297J0D01*
G01X486972Y860478D01*
X487778Y859081D01*
X487868Y859064D01*
G02X488926Y857789I-239J-1275D01*
G02X486332I-1297J0D01*
G02X486403Y858215I1297J3D01*
G01X486434Y858302D01*
X485626Y859701D01*
X485536Y859718D01*
G02X484480Y860993I242J1275D01*
G37*
G36*
G01X491880D02*
G02X494476I1298J0D01*
G02X494403Y860564I-1297J0D01*
G01X494372Y860478D01*
X495178Y859081D01*
X495268Y859064D01*
G02X496326Y857789I-239J-1275D01*
G02X493732I-1297J0D01*
G02X493803Y858215I1297J3D01*
G01X493834Y858302D01*
X493026Y859701D01*
X492936Y859718D01*
G02X491880Y860993I242J1275D01*
G37*
G36*
G01X499280D02*
G02X501876I1298J0D01*
G02X501803Y860564I-1297J0D01*
G01X501772Y860478D01*
X502578Y859081D01*
X502668Y859064D01*
G02X503726Y857789I-239J-1275D01*
G02X501132I-1297J0D01*
G02X501203Y858215I1297J3D01*
G01X501234Y858302D01*
X500426Y859701D01*
X500336Y859718D01*
G02X499280Y860993I242J1275D01*
G37*
G36*
G01X506680D02*
G02X509276I1298J0D01*
G02X509203Y860564I-1297J0D01*
G01X509172Y860478D01*
X509978Y859081D01*
X510068Y859064D01*
G02X511126Y857789I-239J-1275D01*
G02X508532I-1297J0D01*
G02X508603Y858215I1297J3D01*
G01X508634Y858302D01*
X507826Y859701D01*
X507736Y859718D01*
G02X506680Y860993I242J1275D01*
G37*
G36*
G01X514080D02*
G02X516676I1298J0D01*
G02X516603Y860564I-1297J0D01*
G01X516572Y860478D01*
X517378Y859081D01*
X517468Y859064D01*
G02X518526Y857789I-239J-1275D01*
G02X515932I-1297J0D01*
G02X516003Y858215I1297J3D01*
G01X516034Y858302D01*
X515226Y859701D01*
X515136Y859718D01*
G02X514080Y860993I242J1275D01*
G37*
G36*
G01X521480D02*
G02X524076I1298J0D01*
G02X524003Y860564I-1297J0D01*
G01X523972Y860478D01*
X524778Y859081D01*
X524868Y859064D01*
G02X525926Y857789I-239J-1275D01*
G02X523332I-1297J0D01*
G02X523403Y858215I1297J3D01*
G01X523434Y858302D01*
X522626Y859701D01*
X522536Y859718D01*
G02X521480Y860993I242J1275D01*
G37*
G36*
G01X1327422D02*
G02X1330018I1298J0D01*
G02X1328962Y859718I-1298J0D01*
G01X1328872Y859701D01*
X1328065Y858304D01*
X1328096Y858217D01*
G02X1328168Y857789I-1225J-426D01*
G02X1325574I-1297J0D01*
G02X1326629Y859064I1298J0D01*
G01X1326719Y859081D01*
X1327526Y860478D01*
X1327495Y860565D01*
G02X1327422Y860993I1225J429D01*
G37*
G36*
G01X1334822D02*
G02X1337418I1298J0D01*
G02X1336362Y859718I-1298J0D01*
G01X1336272Y859701D01*
X1335465Y858304D01*
X1335496Y858217D01*
G02X1335568Y857789I-1225J-426D01*
G02X1332974I-1297J0D01*
G02X1334029Y859064I1298J0D01*
G01X1334119Y859081D01*
X1334926Y860478D01*
X1334895Y860565D01*
G02X1334822Y860993I1225J429D01*
G37*
G36*
G01X1342222D02*
G02X1344818I1298J0D01*
G02X1343762Y859718I-1298J0D01*
G01X1343672Y859701D01*
X1342865Y858304D01*
X1342896Y858217D01*
G02X1342968Y857789I-1225J-426D01*
G02X1340374I-1297J0D01*
G02X1341429Y859064I1298J0D01*
G01X1341519Y859081D01*
X1342326Y860478D01*
X1342295Y860565D01*
G02X1342222Y860993I1225J429D01*
G37*
G36*
G01X1349622D02*
G02X1352218I1298J0D01*
G02X1351162Y859718I-1298J0D01*
G01X1351072Y859701D01*
X1350265Y858304D01*
X1350296Y858217D01*
G02X1350368Y857789I-1225J-426D01*
G02X1347774I-1297J0D01*
G02X1348829Y859064I1298J0D01*
G01X1348919Y859081D01*
X1349726Y860478D01*
X1349695Y860565D01*
G02X1349622Y860993I1225J429D01*
G37*
G36*
G01X1357022D02*
G02X1359618I1298J0D01*
G02X1358562Y859718I-1298J0D01*
G01X1358472Y859701D01*
X1357665Y858304D01*
X1357696Y858217D01*
G02X1357768Y857789I-1225J-426D01*
G02X1355174I-1297J0D01*
G02X1356229Y859064I1298J0D01*
G01X1356319Y859081D01*
X1357126Y860478D01*
X1357095Y860565D01*
G02X1357022Y860993I1225J429D01*
G37*
G36*
G01X1364422D02*
G02X1367018I1298J0D01*
G02X1365962Y859718I-1298J0D01*
G01X1365872Y859701D01*
X1365065Y858304D01*
X1365096Y858217D01*
G02X1365168Y857789I-1225J-426D01*
G02X1362574I-1297J0D01*
G02X1363629Y859064I1298J0D01*
G01X1363719Y859081D01*
X1364526Y860478D01*
X1364495Y860565D01*
G02X1364422Y860993I1225J429D01*
G37*
G36*
G01X1371822D02*
G02X1374418I1298J0D01*
G02X1373362Y859718I-1298J0D01*
G01X1373272Y859701D01*
X1372465Y858304D01*
X1372496Y858217D01*
G02X1372568Y857789I-1225J-426D01*
G02X1369974I-1297J0D01*
G02X1371029Y859064I1298J0D01*
G01X1371119Y859081D01*
X1371926Y860478D01*
X1371895Y860565D01*
G02X1371822Y860993I1225J429D01*
G37*
G36*
G01X1379222D02*
G02X1381818I1298J0D01*
G02X1380762Y859718I-1298J0D01*
G01X1380672Y859701D01*
X1379865Y858304D01*
X1379896Y858217D01*
G02X1379968Y857789I-1225J-426D01*
G02X1377374I-1297J0D01*
G02X1378429Y859064I1298J0D01*
G01X1378519Y859081D01*
X1379326Y860478D01*
X1379295Y860565D01*
G02X1379222Y860993I1225J429D01*
G37*
G36*
G01X1386622D02*
G02X1389218I1298J0D01*
G02X1388162Y859718I-1298J0D01*
G01X1388072Y859701D01*
X1387265Y858304D01*
X1387296Y858217D01*
G02X1387368Y857789I-1225J-426D01*
G02X1384774I-1297J0D01*
G02X1385829Y859064I1298J0D01*
G01X1385919Y859081D01*
X1386726Y860478D01*
X1386695Y860565D01*
G02X1386622Y860993I1225J429D01*
G37*
G36*
G01X1394022D02*
G02X1396618I1298J0D01*
G02X1395562Y859718I-1298J0D01*
G01X1395472Y859701D01*
X1394665Y858304D01*
X1394696Y858217D01*
G02X1394768Y857789I-1225J-426D01*
G02X1392174I-1297J0D01*
G02X1393229Y859064I1298J0D01*
G01X1393319Y859081D01*
X1394126Y860478D01*
X1394095Y860565D01*
G02X1394022Y860993I1225J429D01*
G37*
G36*
G01X1401422D02*
G02X1404018I1298J0D01*
G02X1402962Y859718I-1298J0D01*
G01X1402872Y859701D01*
X1402065Y858304D01*
X1402096Y858217D01*
G02X1402168Y857789I-1225J-426D01*
G02X1399574I-1297J0D01*
G02X1400629Y859064I1298J0D01*
G01X1400719Y859081D01*
X1401526Y860478D01*
X1401495Y860565D01*
G02X1401422Y860993I1225J429D01*
G37*
G36*
G01X1408824D02*
G02X1411418I1297J0D01*
G02X1410363Y859718I-1298J0D01*
G01X1410273Y859701D01*
X1409466Y858303D01*
X1409496Y858217D01*
G02X1409568Y857789I-1225J-426D01*
G02X1406974I-1297J0D01*
G02X1408030Y859064I1298J0D01*
G01X1408120Y859081D01*
X1408927Y860478D01*
X1408896Y860565D01*
G02X1408824Y860993I1225J426D01*
G37*
G36*
G01X1416222D02*
G02X1418818I1298J0D01*
G02X1418745Y860564I-1297J0D01*
G01X1418714Y860478D01*
X1419520Y859081D01*
X1419610Y859064D01*
G02X1420668Y857789I-239J-1275D01*
G02X1418074I-1297J0D01*
G02X1418145Y858215I1297J3D01*
G01X1418176Y858302D01*
X1417368Y859701D01*
X1417278Y859718D01*
G02X1416222Y860993I242J1275D01*
G37*
G36*
G01X1423624D02*
G02X1426218I1297J0D01*
G02X1426146Y860564I-1297J-3D01*
G01X1426115Y860478D01*
X1426921Y859081D01*
X1427011Y859064D01*
G02X1428068Y857789I-240J-1275D01*
G02X1425474I-1297J0D01*
G01Y857791D01*
G02X1425546Y858216I1297J-1D01*
G01X1425576Y858303D01*
X1424769Y859701D01*
X1424679Y859718D01*
G02X1423624Y860993I243J1275D01*
G37*
G36*
G01X1431022D02*
G02X1433618I1298J0D01*
G02X1433545Y860564I-1297J0D01*
G01X1433514Y860478D01*
X1434320Y859081D01*
X1434410Y859064D01*
G02X1435468Y857789I-239J-1275D01*
G02X1432874I-1297J0D01*
G02X1432945Y858215I1297J3D01*
G01X1432976Y858302D01*
X1432168Y859701D01*
X1432078Y859718D01*
G02X1431022Y860993I242J1275D01*
G37*
G36*
G01X1438422D02*
G02X1441018I1298J0D01*
G02X1440945Y860564I-1297J0D01*
G01X1440914Y860478D01*
X1441720Y859081D01*
X1441810Y859064D01*
G02X1442868Y857789I-239J-1275D01*
G02X1440274I-1297J0D01*
G02X1440345Y858215I1297J3D01*
G01X1440376Y858302D01*
X1439568Y859701D01*
X1439478Y859718D01*
G02X1438422Y860993I242J1275D01*
G37*
G36*
G01X1445822D02*
G02X1448418I1298J0D01*
G02X1448345Y860564I-1297J0D01*
G01X1448314Y860478D01*
X1449120Y859081D01*
X1449210Y859064D01*
G02X1450268Y857789I-239J-1275D01*
G02X1447674I-1297J0D01*
G02X1447745Y858215I1297J3D01*
G01X1447776Y858302D01*
X1446968Y859701D01*
X1446878Y859718D01*
G02X1445822Y860993I242J1275D01*
G37*
G36*
G01X1453222D02*
G02X1455818I1298J0D01*
G02X1455745Y860564I-1297J0D01*
G01X1455714Y860478D01*
X1456520Y859081D01*
X1456610Y859064D01*
G02X1457668Y857789I-239J-1275D01*
G02X1455074I-1297J0D01*
G02X1455145Y858215I1297J3D01*
G01X1455176Y858302D01*
X1454368Y859701D01*
X1454278Y859718D01*
G02X1453222Y860993I242J1275D01*
G37*
G36*
G01X1460622D02*
G02X1463218I1298J0D01*
G02X1463145Y860564I-1297J0D01*
G01X1463114Y860478D01*
X1463920Y859081D01*
X1464010Y859064D01*
G02X1465068Y857789I-239J-1275D01*
G02X1462474I-1297J0D01*
G02X1462545Y858215I1297J3D01*
G01X1462576Y858302D01*
X1461768Y859701D01*
X1461678Y859718D01*
G02X1460622Y860993I242J1275D01*
G37*
G36*
G01X1468022D02*
G02X1470618I1298J0D01*
G02X1470545Y860564I-1297J0D01*
G01X1470514Y860478D01*
X1471320Y859081D01*
X1471410Y859064D01*
G02X1472468Y857789I-239J-1275D01*
G02X1469874I-1297J0D01*
G02X1469945Y858215I1297J3D01*
G01X1469976Y858302D01*
X1469168Y859701D01*
X1469078Y859718D01*
G02X1468022Y860993I242J1275D01*
G37*
G36*
G01X1475422D02*
G02X1478018I1298J0D01*
G02X1477945Y860564I-1297J0D01*
G01X1477914Y860478D01*
X1478720Y859081D01*
X1478810Y859064D01*
G02X1479868Y857789I-239J-1275D01*
G02X1477274I-1297J0D01*
G02X1477345Y858215I1297J3D01*
G01X1477376Y858302D01*
X1476568Y859701D01*
X1476478Y859718D01*
G02X1475422Y860993I242J1275D01*
G37*
G36*
G01X1482822D02*
G02X1485418I1298J0D01*
G02X1485345Y860564I-1297J0D01*
G01X1485314Y860478D01*
X1486120Y859081D01*
X1486210Y859064D01*
G02X1487268Y857789I-239J-1275D01*
G02X1484674I-1297J0D01*
G02X1484745Y858215I1297J3D01*
G01X1484776Y858302D01*
X1483968Y859701D01*
X1483878Y859718D01*
G02X1482822Y860993I242J1275D01*
G37*
G36*
G01X1490222D02*
G02X1492818I1298J0D01*
G02X1492745Y860564I-1297J0D01*
G01X1492714Y860478D01*
X1493520Y859081D01*
X1493610Y859064D01*
G02X1494668Y857789I-239J-1275D01*
G02X1492074I-1297J0D01*
G02X1492145Y858215I1297J3D01*
G01X1492176Y858302D01*
X1491368Y859701D01*
X1491278Y859718D01*
G02X1490222Y860993I242J1275D01*
G37*
G36*
G01X1497622D02*
G02X1500218I1298J0D01*
G02X1500145Y860564I-1297J0D01*
G01X1500114Y860478D01*
X1500920Y859081D01*
X1501010Y859064D01*
G02X1502068Y857789I-239J-1275D01*
G02X1499474I-1297J0D01*
G02X1499545Y858215I1297J3D01*
G01X1499576Y858302D01*
X1498768Y859701D01*
X1498678Y859718D01*
G02X1497622Y860993I242J1275D01*
G37*
G36*
G01X353132Y870606D02*
G02X355726I1297J0D01*
G02X355654Y870177I-1297J-3D01*
G01X355623Y870091D01*
X356430Y868693D01*
X356520Y868676D01*
G02X357576Y867401I-242J-1275D01*
G02X354980I-1298J0D01*
G02X355053Y867830I1297J0D01*
G01X355084Y867916D01*
X354277Y869314D01*
X354187Y869331D01*
G02X353132Y870606I243J1275D01*
G37*
G36*
G01X360532D02*
G02X363126I1297J0D01*
G02X363054Y870177I-1297J-3D01*
G01X363023Y870091D01*
X363830Y868693D01*
X363920Y868676D01*
G02X364976Y867401I-242J-1275D01*
G02X362380I-1298J0D01*
G02X362453Y867830I1297J0D01*
G01X362484Y867916D01*
X361677Y869314D01*
X361587Y869331D01*
G02X360532Y870606I243J1275D01*
G37*
G36*
G01X367932D02*
G02X370526I1297J0D01*
G02X370454Y870177I-1297J-3D01*
G01X370423Y870091D01*
X371230Y868693D01*
X371320Y868676D01*
G02X372376Y867401I-242J-1275D01*
G02X369780I-1298J0D01*
G02X369853Y867830I1297J0D01*
G01X369884Y867916D01*
X369077Y869314D01*
X368987Y869331D01*
G02X367932Y870606I243J1275D01*
G37*
G36*
G01X375332D02*
G02X377926I1297J0D01*
G02X377854Y870177I-1297J-3D01*
G01X377823Y870091D01*
X378630Y868693D01*
X378720Y868676D01*
G02X379776Y867401I-242J-1275D01*
G02X377180I-1298J0D01*
G02X377253Y867830I1297J0D01*
G01X377284Y867916D01*
X376477Y869314D01*
X376387Y869331D01*
G02X375332Y870606I243J1275D01*
G37*
G36*
G01X382732D02*
G02X385326I1297J0D01*
G02X385254Y870177I-1297J-3D01*
G01X385223Y870091D01*
X386030Y868693D01*
X386120Y868676D01*
G02X387176Y867401I-242J-1275D01*
G02X384580I-1298J0D01*
G02X384653Y867830I1297J0D01*
G01X384684Y867916D01*
X383877Y869314D01*
X383787Y869331D01*
G02X382732Y870606I243J1275D01*
G37*
G36*
G01X390132D02*
G02X392726I1297J0D01*
G02X392654Y870177I-1297J-3D01*
G01X392623Y870091D01*
X393430Y868693D01*
X393520Y868676D01*
G02X394576Y867401I-242J-1275D01*
G02X391980I-1298J0D01*
G02X392053Y867830I1297J0D01*
G01X392084Y867916D01*
X391277Y869314D01*
X391187Y869331D01*
G02X390132Y870606I243J1275D01*
G37*
G36*
G01X397532D02*
G02X400126I1297J0D01*
G02X400054Y870177I-1297J-3D01*
G01X400023Y870091D01*
X400830Y868693D01*
X400920Y868676D01*
G02X401976Y867401I-242J-1275D01*
G02X399380I-1298J0D01*
G02X399453Y867830I1297J0D01*
G01X399484Y867916D01*
X398677Y869314D01*
X398587Y869331D01*
G02X397532Y870606I243J1275D01*
G37*
G36*
G01X404932D02*
G02X407526I1297J0D01*
G02X407454Y870177I-1297J-3D01*
G01X407423Y870091D01*
X408230Y868693D01*
X408320Y868676D01*
G02X409376Y867401I-242J-1275D01*
G02X406780I-1298J0D01*
G02X406853Y867830I1297J0D01*
G01X406884Y867916D01*
X406077Y869314D01*
X405987Y869331D01*
G02X404932Y870606I243J1275D01*
G37*
G36*
G01X416032D02*
G02X418626I1297J0D01*
G02X417571Y869331I-1298J0D01*
G01X417481Y869314D01*
X416673Y867915D01*
X416703Y867828D01*
G02X416776Y867401I-1225J-429D01*
G02X414180I-1298J0D01*
G02X415238Y868676I1297J0D01*
G01X415328Y868693D01*
X416135Y870091D01*
X416104Y870178D01*
G02X416032Y870606I1225J426D01*
G37*
G36*
G01X423432D02*
G02X426026I1297J0D01*
G02X424971Y869331I-1298J0D01*
G01X424881Y869314D01*
X424073Y867915D01*
X424103Y867828D01*
G02X424176Y867401I-1225J-429D01*
G02X421580I-1298J0D01*
G02X422638Y868676I1297J0D01*
G01X422728Y868693D01*
X423535Y870091D01*
X423504Y870178D01*
G02X423432Y870606I1225J426D01*
G37*
G36*
G01X430832D02*
G02X433426I1297J0D01*
G02X432371Y869331I-1298J0D01*
G01X432281Y869314D01*
X431473Y867915D01*
X431503Y867828D01*
G02X431576Y867401I-1225J-429D01*
G02X428980I-1298J0D01*
G02X430038Y868676I1297J0D01*
G01X430128Y868693D01*
X430935Y870091D01*
X430904Y870178D01*
G02X430832Y870606I1225J426D01*
G37*
G36*
G01X438232D02*
G02X440826I1297J0D01*
G02X439771Y869331I-1298J0D01*
G01X439681Y869314D01*
X438873Y867915D01*
X438903Y867828D01*
G02X438976Y867401I-1225J-429D01*
G02X436380I-1298J0D01*
G02X437438Y868676I1297J0D01*
G01X437528Y868693D01*
X438335Y870091D01*
X438304Y870178D01*
G02X438232Y870606I1225J426D01*
G37*
G36*
G01X445632D02*
G02X448226I1297J0D01*
G02X447171Y869331I-1298J0D01*
G01X447081Y869314D01*
X446273Y867915D01*
X446303Y867828D01*
G02X446376Y867401I-1225J-429D01*
G02X443780I-1298J0D01*
G02X444838Y868676I1297J0D01*
G01X444928Y868693D01*
X445735Y870091D01*
X445704Y870178D01*
G02X445632Y870606I1225J426D01*
G37*
G36*
G01X453032D02*
G02X455626I1297J0D01*
G02X454571Y869331I-1298J0D01*
G01X454481Y869314D01*
X453673Y867915D01*
X453703Y867828D01*
G02X453776Y867401I-1225J-429D01*
G02X451180I-1298J0D01*
G02X452238Y868676I1297J0D01*
G01X452328Y868693D01*
X453135Y870091D01*
X453104Y870178D01*
G02X453032Y870606I1225J426D01*
G37*
G36*
G01X460432D02*
G02X463026I1297J0D01*
G02X461971Y869331I-1298J0D01*
G01X461881Y869314D01*
X461073Y867915D01*
X461103Y867828D01*
G02X461176Y867401I-1225J-429D01*
G02X458580I-1298J0D01*
G02X459638Y868676I1297J0D01*
G01X459728Y868693D01*
X460535Y870091D01*
X460504Y870178D01*
G02X460432Y870606I1225J426D01*
G37*
G36*
G01X467832D02*
G02X470426I1297J0D01*
G02X469371Y869331I-1298J0D01*
G01X469281Y869314D01*
X468473Y867915D01*
X468503Y867828D01*
G02X468576Y867401I-1225J-429D01*
G02X465980I-1298J0D01*
G02X467038Y868676I1297J0D01*
G01X467128Y868693D01*
X467935Y870091D01*
X467904Y870178D01*
G02X467832Y870606I1225J426D01*
G37*
G36*
G01X475232D02*
G02X477826I1297J0D01*
G02X476771Y869331I-1298J0D01*
G01X476681Y869314D01*
X475873Y867915D01*
X475903Y867828D01*
G02X475976Y867401I-1225J-429D01*
G02X473380I-1298J0D01*
G02X474438Y868676I1297J0D01*
G01X474528Y868693D01*
X475335Y870091D01*
X475304Y870178D01*
G02X475232Y870606I1225J426D01*
G37*
G36*
G01X482632D02*
G02X485226I1297J0D01*
G02X484171Y869331I-1298J0D01*
G01X484081Y869314D01*
X483273Y867915D01*
X483303Y867828D01*
G02X483376Y867401I-1225J-429D01*
G02X480780I-1298J0D01*
G02X481838Y868676I1297J0D01*
G01X481928Y868693D01*
X482735Y870091D01*
X482704Y870178D01*
G02X482632Y870606I1225J426D01*
G37*
G36*
G01X490032D02*
G02X492626I1297J0D01*
G02X491571Y869331I-1298J0D01*
G01X491481Y869314D01*
X490673Y867915D01*
X490703Y867828D01*
G02X490776Y867401I-1225J-429D01*
G02X488180I-1298J0D01*
G02X489238Y868676I1297J0D01*
G01X489328Y868693D01*
X490135Y870091D01*
X490104Y870178D01*
G02X490032Y870606I1225J426D01*
G37*
G36*
G01X497432D02*
G02X500026I1297J0D01*
G02X498971Y869331I-1298J0D01*
G01X498881Y869314D01*
X498073Y867915D01*
X498103Y867828D01*
G02X498176Y867401I-1225J-429D01*
G02X495580I-1298J0D01*
G02X496638Y868676I1297J0D01*
G01X496728Y868693D01*
X497535Y870091D01*
X497504Y870178D01*
G02X497432Y870606I1225J426D01*
G37*
G36*
G01X504832D02*
G02X507426I1297J0D01*
G02X506371Y869331I-1298J0D01*
G01X506281Y869314D01*
X505473Y867915D01*
X505503Y867828D01*
G02X505576Y867401I-1225J-429D01*
G02X502980I-1298J0D01*
G02X504038Y868676I1297J0D01*
G01X504128Y868693D01*
X504935Y870091D01*
X504904Y870178D01*
G02X504832Y870606I1225J426D01*
G37*
G36*
G01X512232D02*
G02X514826I1297J0D01*
G02X513771Y869331I-1298J0D01*
G01X513681Y869314D01*
X512873Y867915D01*
X512903Y867828D01*
G02X512976Y867401I-1225J-429D01*
G02X510380I-1298J0D01*
G02X511438Y868676I1297J0D01*
G01X511528Y868693D01*
X512335Y870091D01*
X512304Y870178D01*
G02X512232Y870606I1225J426D01*
G37*
G36*
G01X519632D02*
G02X522226I1297J0D01*
G02X521171Y869331I-1298J0D01*
G01X521081Y869314D01*
X520273Y867915D01*
X520303Y867828D01*
G02X520376Y867401I-1225J-429D01*
G02X517780I-1298J0D01*
G02X518838Y868676I1297J0D01*
G01X518928Y868693D01*
X519735Y870091D01*
X519704Y870178D01*
G02X519632Y870606I1225J426D01*
G37*
G36*
G01X527032D02*
G02X529626I1297J0D01*
G02X528571Y869331I-1298J0D01*
G01X528481Y869314D01*
X527674Y867916D01*
X527704Y867829D01*
G02X527776Y867401I-1225J-426D01*
G02X525182I-1297J0D01*
G02X526238Y868676I1298J0D01*
G01X526328Y868693D01*
X527135Y870091D01*
X527104Y870178D01*
G02X527032Y870606I1225J426D01*
G37*
G36*
G01X1329274D02*
G02X1331868I1297J0D01*
G02X1331796Y870177I-1297J-3D01*
G01X1331765Y870091D01*
X1332572Y868693D01*
X1332662Y868676D01*
G02X1333718Y867401I-242J-1275D01*
G02X1331122I-1298J0D01*
G02X1331195Y867830I1297J0D01*
G01X1331226Y867916D01*
X1330419Y869314D01*
X1330329Y869331D01*
G02X1329274Y870606I243J1275D01*
G37*
G36*
G01X1336674D02*
G02X1339268I1297J0D01*
G02X1339196Y870177I-1297J-3D01*
G01X1339165Y870091D01*
X1339972Y868693D01*
X1340062Y868676D01*
G02X1341118Y867401I-242J-1275D01*
G02X1338522I-1298J0D01*
G02X1338595Y867830I1297J0D01*
G01X1338626Y867916D01*
X1337819Y869314D01*
X1337729Y869331D01*
G02X1336674Y870606I243J1275D01*
G37*
G36*
G01X1344074D02*
G02X1346668I1297J0D01*
G02X1346596Y870177I-1297J-3D01*
G01X1346565Y870091D01*
X1347372Y868693D01*
X1347462Y868676D01*
G02X1348518Y867401I-242J-1275D01*
G02X1345922I-1298J0D01*
G02X1345995Y867830I1297J0D01*
G01X1346026Y867916D01*
X1345219Y869314D01*
X1345129Y869331D01*
G02X1344074Y870606I243J1275D01*
G37*
G36*
G01X1351474D02*
G02X1354068I1297J0D01*
G02X1353996Y870177I-1297J-3D01*
G01X1353965Y870091D01*
X1354772Y868693D01*
X1354862Y868676D01*
G02X1355918Y867401I-242J-1275D01*
G02X1353322I-1298J0D01*
G02X1353395Y867830I1297J0D01*
G01X1353426Y867916D01*
X1352619Y869314D01*
X1352529Y869331D01*
G02X1351474Y870606I243J1275D01*
G37*
G36*
G01X1358874D02*
G02X1361468I1297J0D01*
G02X1361396Y870177I-1297J-3D01*
G01X1361365Y870091D01*
X1362172Y868693D01*
X1362262Y868676D01*
G02X1363318Y867401I-242J-1275D01*
G02X1360722I-1298J0D01*
G02X1360795Y867830I1297J0D01*
G01X1360826Y867916D01*
X1360019Y869314D01*
X1359929Y869331D01*
G02X1358874Y870606I243J1275D01*
G37*
G36*
G01X1366274D02*
G02X1368868I1297J0D01*
G02X1368796Y870177I-1297J-3D01*
G01X1368765Y870091D01*
X1369572Y868693D01*
X1369662Y868676D01*
G02X1370718Y867401I-242J-1275D01*
G02X1368122I-1298J0D01*
G02X1368195Y867830I1297J0D01*
G01X1368226Y867916D01*
X1367419Y869314D01*
X1367329Y869331D01*
G02X1366274Y870606I243J1275D01*
G37*
G36*
G01X1373674D02*
G02X1376268I1297J0D01*
G02X1376196Y870177I-1297J-3D01*
G01X1376165Y870091D01*
X1376972Y868693D01*
X1377062Y868676D01*
G02X1378118Y867401I-242J-1275D01*
G02X1375522I-1298J0D01*
G02X1375595Y867830I1297J0D01*
G01X1375626Y867916D01*
X1374819Y869314D01*
X1374729Y869331D01*
G02X1373674Y870606I243J1275D01*
G37*
G36*
G01X1381074D02*
G02X1383668I1297J0D01*
G02X1383596Y870177I-1297J-3D01*
G01X1383565Y870091D01*
X1384372Y868693D01*
X1384462Y868676D01*
G02X1385518Y867401I-242J-1275D01*
G02X1382922I-1298J0D01*
G02X1382995Y867830I1297J0D01*
G01X1383026Y867916D01*
X1382219Y869314D01*
X1382129Y869331D01*
G02X1381074Y870606I243J1275D01*
G37*
G36*
G01X1392174D02*
G02X1394768I1297J0D01*
G02X1393713Y869331I-1298J0D01*
G01X1393623Y869314D01*
X1392815Y867915D01*
X1392845Y867828D01*
G02X1392918Y867401I-1225J-429D01*
G02X1390322I-1298J0D01*
G02X1391380Y868676I1297J0D01*
G01X1391470Y868693D01*
X1392277Y870091D01*
X1392246Y870178D01*
G02X1392174Y870606I1225J426D01*
G37*
G36*
G01X1399574D02*
G02X1402168I1297J0D01*
G02X1401113Y869331I-1298J0D01*
G01X1401023Y869314D01*
X1400215Y867915D01*
X1400245Y867828D01*
G02X1400318Y867401I-1225J-429D01*
G02X1397722I-1298J0D01*
G02X1398780Y868676I1297J0D01*
G01X1398870Y868693D01*
X1399677Y870091D01*
X1399646Y870178D01*
G02X1399574Y870606I1225J426D01*
G37*
G36*
G01X1406974D02*
G02X1409568I1297J0D01*
G02X1408513Y869331I-1298J0D01*
G01X1408423Y869314D01*
X1407615Y867915D01*
X1407645Y867828D01*
G02X1407718Y867401I-1225J-429D01*
G02X1405122I-1298J0D01*
G02X1406180Y868676I1297J0D01*
G01X1406270Y868693D01*
X1407077Y870091D01*
X1407046Y870178D01*
G02X1406974Y870606I1225J426D01*
G37*
G36*
G01X1414374D02*
G02X1416968I1297J0D01*
G02X1415913Y869331I-1298J0D01*
G01X1415823Y869314D01*
X1415015Y867915D01*
X1415045Y867828D01*
G02X1415118Y867401I-1225J-429D01*
G02X1412522I-1298J0D01*
G02X1413580Y868676I1297J0D01*
G01X1413670Y868693D01*
X1414477Y870091D01*
X1414446Y870178D01*
G02X1414374Y870606I1225J426D01*
G37*
G36*
G01X1421774D02*
G02X1424368I1297J0D01*
G02X1423313Y869331I-1298J0D01*
G01X1423223Y869314D01*
X1422415Y867915D01*
X1422445Y867828D01*
G02X1422518Y867401I-1225J-429D01*
G02X1419922I-1298J0D01*
G02X1420980Y868676I1297J0D01*
G01X1421070Y868693D01*
X1421877Y870091D01*
X1421846Y870178D01*
G02X1421774Y870606I1225J426D01*
G37*
G36*
G01X1429174D02*
G02X1431768I1297J0D01*
G02X1430713Y869331I-1298J0D01*
G01X1430623Y869314D01*
X1429815Y867915D01*
X1429845Y867828D01*
G02X1429918Y867401I-1225J-429D01*
G02X1427322I-1298J0D01*
G02X1428380Y868676I1297J0D01*
G01X1428470Y868693D01*
X1429277Y870091D01*
X1429246Y870178D01*
G02X1429174Y870606I1225J426D01*
G37*
G36*
G01X1436574D02*
G02X1439168I1297J0D01*
G02X1438113Y869331I-1298J0D01*
G01X1438023Y869314D01*
X1437215Y867915D01*
X1437245Y867828D01*
G02X1437318Y867401I-1225J-429D01*
G02X1434722I-1298J0D01*
G02X1435780Y868676I1297J0D01*
G01X1435870Y868693D01*
X1436677Y870091D01*
X1436646Y870178D01*
G02X1436574Y870606I1225J426D01*
G37*
G36*
G01X1443974D02*
G02X1446568I1297J0D01*
G02X1445513Y869331I-1298J0D01*
G01X1445423Y869314D01*
X1444615Y867915D01*
X1444645Y867828D01*
G02X1444718Y867401I-1225J-429D01*
G02X1442122I-1298J0D01*
G02X1443180Y868676I1297J0D01*
G01X1443270Y868693D01*
X1444077Y870091D01*
X1444046Y870178D01*
G02X1443974Y870606I1225J426D01*
G37*
G36*
G01X1451374D02*
G02X1453968I1297J0D01*
G02X1452913Y869331I-1298J0D01*
G01X1452823Y869314D01*
X1452015Y867915D01*
X1452045Y867828D01*
G02X1452118Y867401I-1225J-429D01*
G02X1449522I-1298J0D01*
G02X1450580Y868676I1297J0D01*
G01X1450670Y868693D01*
X1451477Y870091D01*
X1451446Y870178D01*
G02X1451374Y870606I1225J426D01*
G37*
G36*
G01X1458774D02*
G02X1461368I1297J0D01*
G02X1460313Y869331I-1298J0D01*
G01X1460223Y869314D01*
X1459415Y867915D01*
X1459445Y867828D01*
G02X1459518Y867401I-1225J-429D01*
G02X1456922I-1298J0D01*
G02X1457980Y868676I1297J0D01*
G01X1458070Y868693D01*
X1458877Y870091D01*
X1458846Y870178D01*
G02X1458774Y870606I1225J426D01*
G37*
G36*
G01X1466174D02*
G02X1468768I1297J0D01*
G02X1467713Y869331I-1298J0D01*
G01X1467623Y869314D01*
X1466815Y867915D01*
X1466845Y867828D01*
G02X1466918Y867401I-1225J-429D01*
G02X1464322I-1298J0D01*
G02X1465380Y868676I1297J0D01*
G01X1465470Y868693D01*
X1466277Y870091D01*
X1466246Y870178D01*
G02X1466174Y870606I1225J426D01*
G37*
G36*
G01X1473574D02*
G02X1476168I1297J0D01*
G02X1475113Y869331I-1298J0D01*
G01X1475023Y869314D01*
X1474215Y867915D01*
X1474245Y867828D01*
G02X1474318Y867401I-1225J-429D01*
G02X1471722I-1298J0D01*
G02X1472780Y868676I1297J0D01*
G01X1472870Y868693D01*
X1473677Y870091D01*
X1473646Y870178D01*
G02X1473574Y870606I1225J426D01*
G37*
G36*
G01X1480974D02*
G02X1483568I1297J0D01*
G02X1482513Y869331I-1298J0D01*
G01X1482423Y869314D01*
X1481615Y867915D01*
X1481645Y867828D01*
G02X1481718Y867401I-1225J-429D01*
G02X1479122I-1298J0D01*
G02X1480180Y868676I1297J0D01*
G01X1480270Y868693D01*
X1481077Y870091D01*
X1481046Y870178D01*
G02X1480974Y870606I1225J426D01*
G37*
G36*
G01X1488374D02*
G02X1490968I1297J0D01*
G02X1489913Y869331I-1298J0D01*
G01X1489823Y869314D01*
X1489015Y867915D01*
X1489045Y867828D01*
G02X1489118Y867401I-1225J-429D01*
G02X1486522I-1298J0D01*
G02X1487580Y868676I1297J0D01*
G01X1487670Y868693D01*
X1488477Y870091D01*
X1488446Y870178D01*
G02X1488374Y870606I1225J426D01*
G37*
G36*
G01X1495774D02*
G02X1498368I1297J0D01*
G02X1497313Y869331I-1298J0D01*
G01X1497223Y869314D01*
X1496415Y867915D01*
X1496445Y867828D01*
G02X1496518Y867401I-1225J-429D01*
G02X1493922I-1298J0D01*
G02X1494980Y868676I1297J0D01*
G01X1495070Y868693D01*
X1495877Y870091D01*
X1495846Y870178D01*
G02X1495774Y870606I1225J426D01*
G37*
G36*
G01X1503174D02*
G02X1505768I1297J0D01*
G02X1504713Y869331I-1298J0D01*
G01X1504623Y869314D01*
X1503816Y867916D01*
X1503846Y867829D01*
G02X1503918Y867401I-1225J-426D01*
G02X1501324I-1297J0D01*
G02X1502380Y868676I1298J0D01*
G01X1502470Y868693D01*
X1503277Y870091D01*
X1503246Y870178D01*
G02X1503174Y870606I1225J426D01*
G37*
G36*
G01X351280Y873810D02*
G02X353876I1298J0D01*
G02X352820Y872535I-1298J0D01*
G01X352730Y872518D01*
X351923Y871121D01*
X351954Y871034D01*
G02X352026Y870606I-1225J-426D01*
G02X349432I-1297J0D01*
G02X350487Y871881I1298J0D01*
G01X350577Y871898D01*
X351384Y873295D01*
X351353Y873382D01*
G02X351280Y873810I1225J429D01*
G37*
G36*
G01X358680D02*
G02X361276I1298J0D01*
G02X360220Y872535I-1298J0D01*
G01X360130Y872518D01*
X359323Y871121D01*
X359354Y871034D01*
G02X359426Y870606I-1225J-426D01*
G02X356832I-1297J0D01*
G02X357887Y871881I1298J0D01*
G01X357977Y871898D01*
X358784Y873295D01*
X358753Y873382D01*
G02X358680Y873810I1225J429D01*
G37*
G36*
G01X366080D02*
G02X368676I1298J0D01*
G02X367620Y872535I-1298J0D01*
G01X367530Y872518D01*
X366723Y871121D01*
X366754Y871034D01*
G02X366826Y870606I-1225J-426D01*
G02X364232I-1297J0D01*
G02X365287Y871881I1298J0D01*
G01X365377Y871898D01*
X366184Y873295D01*
X366153Y873382D01*
G02X366080Y873810I1225J429D01*
G37*
G36*
G01X373480D02*
G02X376076I1298J0D01*
G02X375020Y872535I-1298J0D01*
G01X374930Y872518D01*
X374123Y871121D01*
X374154Y871034D01*
G02X374226Y870606I-1225J-426D01*
G02X371632I-1297J0D01*
G02X372687Y871881I1298J0D01*
G01X372777Y871898D01*
X373584Y873295D01*
X373553Y873382D01*
G02X373480Y873810I1225J429D01*
G37*
G36*
G01X380880D02*
G02X383476I1298J0D01*
G02X382420Y872535I-1298J0D01*
G01X382330Y872518D01*
X381523Y871121D01*
X381554Y871034D01*
G02X381626Y870606I-1225J-426D01*
G02X379032I-1297J0D01*
G02X380087Y871881I1298J0D01*
G01X380177Y871898D01*
X380984Y873295D01*
X380953Y873382D01*
G02X380880Y873810I1225J429D01*
G37*
G36*
G01X388280D02*
G02X390876I1298J0D01*
G02X389820Y872535I-1298J0D01*
G01X389730Y872518D01*
X388923Y871121D01*
X388954Y871034D01*
G02X389026Y870606I-1225J-426D01*
G02X386432I-1297J0D01*
G02X387487Y871881I1298J0D01*
G01X387577Y871898D01*
X388384Y873295D01*
X388353Y873382D01*
G02X388280Y873810I1225J429D01*
G37*
G36*
G01X395680D02*
G02X398276I1298J0D01*
G02X397220Y872535I-1298J0D01*
G01X397130Y872518D01*
X396323Y871121D01*
X396354Y871034D01*
G02X396426Y870606I-1225J-426D01*
G02X393832I-1297J0D01*
G02X394887Y871881I1298J0D01*
G01X394977Y871898D01*
X395784Y873295D01*
X395753Y873382D01*
G02X395680Y873810I1225J429D01*
G37*
G36*
G01X403080D02*
G02X405676I1298J0D01*
G02X404620Y872535I-1298J0D01*
G01X404530Y872518D01*
X403723Y871121D01*
X403754Y871034D01*
G02X403826Y870606I-1225J-426D01*
G02X401232I-1297J0D01*
G02X402287Y871881I1298J0D01*
G01X402377Y871898D01*
X403184Y873295D01*
X403153Y873382D01*
G02X403080Y873810I1225J429D01*
G37*
G36*
G01X410480D02*
G02X413076I1298J0D01*
G02X413003Y873381I-1297J0D01*
G01X412972Y873295D01*
X413778Y871898D01*
X413868Y871881D01*
G02X414926Y870606I-239J-1275D01*
G02X412332I-1297J0D01*
G02X412403Y871032I1297J3D01*
G01X412434Y871119D01*
X411626Y872518D01*
X411536Y872535D01*
G02X410480Y873810I242J1275D01*
G37*
G36*
G01X417880D02*
G02X420476I1298J0D01*
G02X420403Y873381I-1297J0D01*
G01X420372Y873295D01*
X421178Y871898D01*
X421268Y871881D01*
G02X422326Y870606I-239J-1275D01*
G02X419732I-1297J0D01*
G02X419803Y871032I1297J3D01*
G01X419834Y871119D01*
X419026Y872518D01*
X418936Y872535D01*
G02X417880Y873810I242J1275D01*
G37*
G36*
G01X425280D02*
G02X427876I1298J0D01*
G02X427803Y873381I-1297J0D01*
G01X427772Y873295D01*
X428578Y871898D01*
X428668Y871881D01*
G02X429726Y870606I-239J-1275D01*
G02X427132I-1297J0D01*
G02X427203Y871032I1297J3D01*
G01X427234Y871119D01*
X426426Y872518D01*
X426336Y872535D01*
G02X425280Y873810I242J1275D01*
G37*
G36*
G01X432682D02*
G02X435276I1297J0D01*
G02X435204Y873381I-1297J-3D01*
G01X435173Y873295D01*
X435979Y871898D01*
X436069Y871881D01*
G02X437126Y870606I-240J-1275D01*
G02X434532I-1297J0D01*
G01Y870608D01*
G02X434604Y871033I1297J-1D01*
G01X434634Y871120D01*
X433827Y872518D01*
X433737Y872535D01*
G02X432682Y873810I243J1275D01*
G37*
G36*
G01X440080D02*
G02X442676I1298J0D01*
G02X442603Y873381I-1297J0D01*
G01X442572Y873295D01*
X443378Y871898D01*
X443468Y871881D01*
G02X444526Y870606I-239J-1275D01*
G02X441932I-1297J0D01*
G02X442003Y871032I1297J3D01*
G01X442034Y871119D01*
X441226Y872518D01*
X441136Y872535D01*
G02X440080Y873810I242J1275D01*
G37*
G36*
G01X447482D02*
G02X450076I1297J0D01*
G02X450004Y873381I-1297J-3D01*
G01X449973Y873295D01*
X450779Y871898D01*
X450869Y871881D01*
G02X451926Y870606I-240J-1275D01*
G02X449332I-1297J0D01*
G01Y870608D01*
G02X449404Y871033I1297J-1D01*
G01X449434Y871120D01*
X448627Y872518D01*
X448537Y872535D01*
G02X447482Y873810I243J1275D01*
G37*
G36*
G01X454880D02*
G02X457476I1298J0D01*
G02X457403Y873381I-1297J0D01*
G01X457372Y873295D01*
X458178Y871898D01*
X458268Y871881D01*
G02X459326Y870606I-239J-1275D01*
G02X456732I-1297J0D01*
G02X456803Y871032I1297J3D01*
G01X456834Y871119D01*
X456026Y872518D01*
X455936Y872535D01*
G02X454880Y873810I242J1275D01*
G37*
G36*
G01X462280D02*
G02X464876I1298J0D01*
G02X464803Y873381I-1297J0D01*
G01X464772Y873295D01*
X465578Y871898D01*
X465668Y871881D01*
G02X466726Y870606I-239J-1275D01*
G02X464132I-1297J0D01*
G02X464203Y871032I1297J3D01*
G01X464234Y871119D01*
X463426Y872518D01*
X463336Y872535D01*
G02X462280Y873810I242J1275D01*
G37*
G36*
G01X477080D02*
G02X479676I1298J0D01*
G02X479603Y873381I-1297J0D01*
G01X479572Y873295D01*
X480378Y871898D01*
X480468Y871881D01*
G02X481526Y870606I-239J-1275D01*
G02X478932I-1297J0D01*
G02X479003Y871032I1297J3D01*
G01X479034Y871119D01*
X478226Y872518D01*
X478136Y872535D01*
G02X477080Y873810I242J1275D01*
G37*
G36*
G01X484480D02*
G02X487076I1298J0D01*
G02X487003Y873381I-1297J0D01*
G01X486972Y873295D01*
X487778Y871898D01*
X487868Y871881D01*
G02X488926Y870606I-239J-1275D01*
G02X486332I-1297J0D01*
G02X486403Y871032I1297J3D01*
G01X486434Y871119D01*
X485626Y872518D01*
X485536Y872535D01*
G02X484480Y873810I242J1275D01*
G37*
G36*
G01X491880D02*
G02X494476I1298J0D01*
G02X494403Y873381I-1297J0D01*
G01X494372Y873295D01*
X495178Y871898D01*
X495268Y871881D01*
G02X496326Y870606I-239J-1275D01*
G02X493732I-1297J0D01*
G02X493803Y871032I1297J3D01*
G01X493834Y871119D01*
X493026Y872518D01*
X492936Y872535D01*
G02X491880Y873810I242J1275D01*
G37*
G36*
G01X499280D02*
G02X501876I1298J0D01*
G02X501803Y873381I-1297J0D01*
G01X501772Y873295D01*
X502578Y871898D01*
X502668Y871881D01*
G02X503726Y870606I-239J-1275D01*
G02X501132I-1297J0D01*
G02X501203Y871032I1297J3D01*
G01X501234Y871119D01*
X500426Y872518D01*
X500336Y872535D01*
G02X499280Y873810I242J1275D01*
G37*
G36*
G01X506680D02*
G02X509276I1298J0D01*
G02X509203Y873381I-1297J0D01*
G01X509172Y873295D01*
X509978Y871898D01*
X510068Y871881D01*
G02X511126Y870606I-239J-1275D01*
G02X508532I-1297J0D01*
G02X508603Y871032I1297J3D01*
G01X508634Y871119D01*
X507826Y872518D01*
X507736Y872535D01*
G02X506680Y873810I242J1275D01*
G37*
G36*
G01X514080D02*
G02X516676I1298J0D01*
G02X516603Y873381I-1297J0D01*
G01X516572Y873295D01*
X517378Y871898D01*
X517468Y871881D01*
G02X518526Y870606I-239J-1275D01*
G02X515932I-1297J0D01*
G02X516003Y871032I1297J3D01*
G01X516034Y871119D01*
X515226Y872518D01*
X515136Y872535D01*
G02X514080Y873810I242J1275D01*
G37*
G36*
G01X1327422D02*
G02X1330018I1298J0D01*
G02X1328962Y872535I-1298J0D01*
G01X1328872Y872518D01*
X1328065Y871121D01*
X1328096Y871034D01*
G02X1328168Y870606I-1225J-426D01*
G02X1325574I-1297J0D01*
G02X1326629Y871881I1298J0D01*
G01X1326719Y871898D01*
X1327526Y873295D01*
X1327495Y873382D01*
G02X1327422Y873810I1225J429D01*
G37*
G36*
G01X1334822D02*
G02X1337418I1298J0D01*
G02X1336362Y872535I-1298J0D01*
G01X1336272Y872518D01*
X1335465Y871121D01*
X1335496Y871034D01*
G02X1335568Y870606I-1225J-426D01*
G02X1332974I-1297J0D01*
G02X1334029Y871881I1298J0D01*
G01X1334119Y871898D01*
X1334926Y873295D01*
X1334895Y873382D01*
G02X1334822Y873810I1225J429D01*
G37*
G36*
G01X1342222D02*
G02X1344818I1298J0D01*
G02X1343762Y872535I-1298J0D01*
G01X1343672Y872518D01*
X1342865Y871121D01*
X1342896Y871034D01*
G02X1342968Y870606I-1225J-426D01*
G02X1340374I-1297J0D01*
G02X1341429Y871881I1298J0D01*
G01X1341519Y871898D01*
X1342326Y873295D01*
X1342295Y873382D01*
G02X1342222Y873810I1225J429D01*
G37*
G36*
G01X1349622D02*
G02X1352218I1298J0D01*
G02X1351162Y872535I-1298J0D01*
G01X1351072Y872518D01*
X1350265Y871121D01*
X1350296Y871034D01*
G02X1350368Y870606I-1225J-426D01*
G02X1347774I-1297J0D01*
G02X1348829Y871881I1298J0D01*
G01X1348919Y871898D01*
X1349726Y873295D01*
X1349695Y873382D01*
G02X1349622Y873810I1225J429D01*
G37*
G36*
G01X1357022D02*
G02X1359618I1298J0D01*
G02X1358562Y872535I-1298J0D01*
G01X1358472Y872518D01*
X1357665Y871121D01*
X1357696Y871034D01*
G02X1357768Y870606I-1225J-426D01*
G02X1355174I-1297J0D01*
G02X1356229Y871881I1298J0D01*
G01X1356319Y871898D01*
X1357126Y873295D01*
X1357095Y873382D01*
G02X1357022Y873810I1225J429D01*
G37*
G36*
G01X1364422D02*
G02X1367018I1298J0D01*
G02X1365962Y872535I-1298J0D01*
G01X1365872Y872518D01*
X1365065Y871121D01*
X1365096Y871034D01*
G02X1365168Y870606I-1225J-426D01*
G02X1362574I-1297J0D01*
G02X1363629Y871881I1298J0D01*
G01X1363719Y871898D01*
X1364526Y873295D01*
X1364495Y873382D01*
G02X1364422Y873810I1225J429D01*
G37*
G36*
G01X1371822D02*
G02X1374418I1298J0D01*
G02X1373362Y872535I-1298J0D01*
G01X1373272Y872518D01*
X1372465Y871121D01*
X1372496Y871034D01*
G02X1372568Y870606I-1225J-426D01*
G02X1369974I-1297J0D01*
G02X1371029Y871881I1298J0D01*
G01X1371119Y871898D01*
X1371926Y873295D01*
X1371895Y873382D01*
G02X1371822Y873810I1225J429D01*
G37*
G36*
G01X1379222D02*
G02X1381818I1298J0D01*
G02X1380762Y872535I-1298J0D01*
G01X1380672Y872518D01*
X1379865Y871121D01*
X1379896Y871034D01*
G02X1379968Y870606I-1225J-426D01*
G02X1377374I-1297J0D01*
G02X1378429Y871881I1298J0D01*
G01X1378519Y871898D01*
X1379326Y873295D01*
X1379295Y873382D01*
G02X1379222Y873810I1225J429D01*
G37*
G36*
G01X1386622D02*
G02X1389218I1298J0D01*
G02X1389145Y873381I-1297J0D01*
G01X1389114Y873295D01*
X1389920Y871898D01*
X1390010Y871881D01*
G02X1391068Y870606I-239J-1275D01*
G02X1388474I-1297J0D01*
G02X1388545Y871032I1297J3D01*
G01X1388576Y871119D01*
X1387768Y872518D01*
X1387678Y872535D01*
G02X1386622Y873810I242J1275D01*
G37*
G36*
G01X1394022D02*
G02X1396618I1298J0D01*
G02X1396545Y873381I-1297J0D01*
G01X1396514Y873295D01*
X1397320Y871898D01*
X1397410Y871881D01*
G02X1398468Y870606I-239J-1275D01*
G02X1395874I-1297J0D01*
G02X1395945Y871032I1297J3D01*
G01X1395976Y871119D01*
X1395168Y872518D01*
X1395078Y872535D01*
G02X1394022Y873810I242J1275D01*
G37*
G36*
G01X1401422D02*
G02X1404018I1298J0D01*
G02X1403945Y873381I-1297J0D01*
G01X1403914Y873295D01*
X1404720Y871898D01*
X1404810Y871881D01*
G02X1405868Y870606I-239J-1275D01*
G02X1403274I-1297J0D01*
G02X1403345Y871032I1297J3D01*
G01X1403376Y871119D01*
X1402568Y872518D01*
X1402478Y872535D01*
G02X1401422Y873810I242J1275D01*
G37*
G36*
G01X1408824D02*
G02X1411418I1297J0D01*
G02X1411346Y873381I-1297J-3D01*
G01X1411315Y873295D01*
X1412121Y871898D01*
X1412211Y871881D01*
G02X1413268Y870606I-240J-1275D01*
G02X1410674I-1297J0D01*
G01Y870608D01*
G02X1410746Y871033I1297J-1D01*
G01X1410776Y871120D01*
X1409969Y872518D01*
X1409879Y872535D01*
G02X1408824Y873810I243J1275D01*
G37*
G36*
G01X1416222D02*
G02X1418818I1298J0D01*
G02X1418745Y873381I-1297J0D01*
G01X1418714Y873295D01*
X1419520Y871898D01*
X1419610Y871881D01*
G02X1420668Y870606I-239J-1275D01*
G02X1418074I-1297J0D01*
G02X1418145Y871032I1297J3D01*
G01X1418176Y871119D01*
X1417368Y872518D01*
X1417278Y872535D01*
G02X1416222Y873810I242J1275D01*
G37*
G36*
G01X1423624D02*
G02X1426218I1297J0D01*
G02X1426146Y873381I-1297J-3D01*
G01X1426115Y873295D01*
X1426921Y871898D01*
X1427011Y871881D01*
G02X1428068Y870606I-240J-1275D01*
G02X1425474I-1297J0D01*
G01Y870608D01*
G02X1425546Y871033I1297J-1D01*
G01X1425576Y871120D01*
X1424769Y872518D01*
X1424679Y872535D01*
G02X1423624Y873810I243J1275D01*
G37*
G36*
G01X1431022D02*
G02X1433618I1298J0D01*
G02X1433545Y873381I-1297J0D01*
G01X1433514Y873295D01*
X1434320Y871898D01*
X1434410Y871881D01*
G02X1435468Y870606I-239J-1275D01*
G02X1432874I-1297J0D01*
G02X1432945Y871032I1297J3D01*
G01X1432976Y871119D01*
X1432168Y872518D01*
X1432078Y872535D01*
G02X1431022Y873810I242J1275D01*
G37*
G36*
G01X1438422D02*
G02X1441018I1298J0D01*
G02X1440945Y873381I-1297J0D01*
G01X1440914Y873295D01*
X1441720Y871898D01*
X1441810Y871881D01*
G02X1442868Y870606I-239J-1275D01*
G02X1440274I-1297J0D01*
G02X1440345Y871032I1297J3D01*
G01X1440376Y871119D01*
X1439568Y872518D01*
X1439478Y872535D01*
G02X1438422Y873810I242J1275D01*
G37*
G36*
G01X1453222D02*
G02X1455818I1298J0D01*
G02X1455745Y873381I-1297J0D01*
G01X1455714Y873295D01*
X1456520Y871898D01*
X1456610Y871881D01*
G02X1457668Y870606I-239J-1275D01*
G02X1455074I-1297J0D01*
G02X1455145Y871032I1297J3D01*
G01X1455176Y871119D01*
X1454368Y872518D01*
X1454278Y872535D01*
G02X1453222Y873810I242J1275D01*
G37*
G36*
G01X1460622D02*
G02X1463218I1298J0D01*
G02X1463145Y873381I-1297J0D01*
G01X1463114Y873295D01*
X1463920Y871898D01*
X1464010Y871881D01*
G02X1465068Y870606I-239J-1275D01*
G02X1462474I-1297J0D01*
G02X1462545Y871032I1297J3D01*
G01X1462576Y871119D01*
X1461768Y872518D01*
X1461678Y872535D01*
G02X1460622Y873810I242J1275D01*
G37*
G36*
G01X1468022D02*
G02X1470618I1298J0D01*
G02X1470545Y873381I-1297J0D01*
G01X1470514Y873295D01*
X1471320Y871898D01*
X1471410Y871881D01*
G02X1472468Y870606I-239J-1275D01*
G02X1469874I-1297J0D01*
G02X1469945Y871032I1297J3D01*
G01X1469976Y871119D01*
X1469168Y872518D01*
X1469078Y872535D01*
G02X1468022Y873810I242J1275D01*
G37*
G36*
G01X1475422D02*
G02X1478018I1298J0D01*
G02X1477945Y873381I-1297J0D01*
G01X1477914Y873295D01*
X1478720Y871898D01*
X1478810Y871881D01*
G02X1479868Y870606I-239J-1275D01*
G02X1477274I-1297J0D01*
G02X1477345Y871032I1297J3D01*
G01X1477376Y871119D01*
X1476568Y872518D01*
X1476478Y872535D01*
G02X1475422Y873810I242J1275D01*
G37*
G36*
G01X1482822D02*
G02X1485418I1298J0D01*
G02X1485345Y873381I-1297J0D01*
G01X1485314Y873295D01*
X1486120Y871898D01*
X1486210Y871881D01*
G02X1487268Y870606I-239J-1275D01*
G02X1484674I-1297J0D01*
G02X1484745Y871032I1297J3D01*
G01X1484776Y871119D01*
X1483968Y872518D01*
X1483878Y872535D01*
G02X1482822Y873810I242J1275D01*
G37*
G36*
G01X1490222D02*
G02X1492818I1298J0D01*
G02X1492745Y873381I-1297J0D01*
G01X1492714Y873295D01*
X1493520Y871898D01*
X1493610Y871881D01*
G02X1494668Y870606I-239J-1275D01*
G02X1492074I-1297J0D01*
G02X1492145Y871032I1297J3D01*
G01X1492176Y871119D01*
X1491368Y872518D01*
X1491278Y872535D01*
G02X1490222Y873810I242J1275D01*
G37*
G36*
G01X367932Y883423D02*
G02X370526I1297J0D01*
G02X370454Y882994I-1297J-3D01*
G01X370423Y882908D01*
X371229Y881511D01*
X371319Y881494D01*
G02X372376Y880219I-240J-1275D01*
G02X369780I-1298J0D01*
G02X369853Y880647I1298J-1D01*
G01X369883Y880734D01*
X369077Y882131D01*
X368987Y882148D01*
G02X367932Y883423I243J1275D01*
G37*
G36*
G01X375332D02*
G02X377926I1297J0D01*
G02X377854Y882994I-1297J-3D01*
G01X377823Y882908D01*
X378629Y881511D01*
X378719Y881494D01*
G02X379776Y880219I-240J-1275D01*
G02X377180I-1298J0D01*
G02X377253Y880647I1298J-1D01*
G01X377283Y880734D01*
X376477Y882131D01*
X376387Y882148D01*
G02X375332Y883423I243J1275D01*
G37*
G36*
G01X382732D02*
G02X385326I1297J0D01*
G02X385254Y882994I-1297J-3D01*
G01X385223Y882908D01*
X386029Y881511D01*
X386119Y881494D01*
G02X387176Y880219I-240J-1275D01*
G02X384580I-1298J0D01*
G02X384653Y880647I1298J-1D01*
G01X384683Y880734D01*
X383877Y882131D01*
X383787Y882148D01*
G02X382732Y883423I243J1275D01*
G37*
G36*
G01X390132D02*
G02X392726I1297J0D01*
G02X392654Y882994I-1297J-3D01*
G01X392623Y882908D01*
X393429Y881511D01*
X393519Y881494D01*
G02X394576Y880219I-240J-1275D01*
G02X391980I-1298J0D01*
G02X392053Y880647I1298J-1D01*
G01X392083Y880734D01*
X391277Y882131D01*
X391187Y882148D01*
G02X390132Y883423I243J1275D01*
G37*
G36*
G01X397532D02*
G02X400126I1297J0D01*
G02X400054Y882994I-1297J-3D01*
G01X400023Y882908D01*
X400829Y881511D01*
X400919Y881494D01*
G02X401976Y880219I-240J-1275D01*
G02X399380I-1298J0D01*
G02X399453Y880647I1298J-1D01*
G01X399483Y880734D01*
X398677Y882131D01*
X398587Y882148D01*
G02X397532Y883423I243J1275D01*
G37*
G36*
G01X404932D02*
G02X407526I1297J0D01*
G02X407454Y882994I-1297J-3D01*
G01X407423Y882908D01*
X408229Y881511D01*
X408319Y881494D01*
G02X409376Y880219I-240J-1275D01*
G02X406780I-1298J0D01*
G02X406853Y880647I1298J-1D01*
G01X406883Y880734D01*
X406077Y882131D01*
X405987Y882148D01*
G02X404932Y883423I243J1275D01*
G37*
G36*
G01X412332D02*
G02X414926I1297J0D01*
G02X414854Y882994I-1297J-3D01*
G01X414823Y882908D01*
X415629Y881511D01*
X415719Y881494D01*
G02X416776Y880219I-240J-1275D01*
G02X414180I-1298J0D01*
G02X414253Y880647I1298J-1D01*
G01X414283Y880734D01*
X413477Y882131D01*
X413387Y882148D01*
G02X412332Y883423I243J1275D01*
G37*
G36*
G01X419732D02*
G02X422326I1297J0D01*
G02X422254Y882994I-1297J-3D01*
G01X422223Y882908D01*
X423029Y881511D01*
X423119Y881494D01*
G02X424176Y880219I-240J-1275D01*
G02X421580I-1298J0D01*
G02X421653Y880647I1298J-1D01*
G01X421683Y880734D01*
X420877Y882131D01*
X420787Y882148D01*
G02X419732Y883423I243J1275D01*
G37*
G36*
G01X427132D02*
G02X429726I1297J0D01*
G02X429654Y882994I-1297J-3D01*
G01X429623Y882908D01*
X430429Y881511D01*
X430519Y881494D01*
G02X431576Y880219I-240J-1275D01*
G02X428980I-1298J0D01*
G02X429053Y880647I1298J-1D01*
G01X429083Y880734D01*
X428277Y882131D01*
X428187Y882148D01*
G02X427132Y883423I243J1275D01*
G37*
G36*
G01X434532D02*
G02X437126I1297J0D01*
G02X437054Y882994I-1297J-3D01*
G01X437023Y882908D01*
X437829Y881511D01*
X437919Y881494D01*
G02X438976Y880219I-240J-1275D01*
G02X436380I-1298J0D01*
G02X436453Y880647I1298J-1D01*
G01X436483Y880734D01*
X435677Y882131D01*
X435587Y882148D01*
G02X434532Y883423I243J1275D01*
G37*
G36*
G01X441932D02*
G02X444526I1297J0D01*
G02X444454Y882994I-1297J-3D01*
G01X444423Y882908D01*
X445229Y881511D01*
X445319Y881494D01*
G02X446376Y880219I-240J-1275D01*
G02X443780I-1298J0D01*
G02X443853Y880647I1298J-1D01*
G01X443883Y880734D01*
X443077Y882131D01*
X442987Y882148D01*
G02X441932Y883423I243J1275D01*
G37*
G36*
G01X449332D02*
G02X451926I1297J0D01*
G02X451854Y882994I-1297J-3D01*
G01X451823Y882908D01*
X452629Y881511D01*
X452719Y881494D01*
G02X453776Y880219I-240J-1275D01*
G02X451182I-1297J0D01*
G01Y880221D01*
G02X451254Y880646I1297J-1D01*
G01X451284Y880733D01*
X450477Y882131D01*
X450387Y882148D01*
G02X449332Y883423I243J1275D01*
G37*
G36*
G01X456732D02*
G02X459326I1297J0D01*
G02X459254Y882994I-1297J-3D01*
G01X459223Y882908D01*
X460029Y881511D01*
X460119Y881494D01*
G02X461176Y880219I-240J-1275D01*
G02X458580I-1298J0D01*
G02X458653Y880647I1298J-1D01*
G01X458683Y880734D01*
X457877Y882131D01*
X457787Y882148D01*
G02X456732Y883423I243J1275D01*
G37*
G36*
G01X464132D02*
G02X466726I1297J0D01*
G02X466654Y882994I-1297J-3D01*
G01X466623Y882908D01*
X467429Y881511D01*
X467519Y881494D01*
G02X468576Y880219I-240J-1275D01*
G02X465980I-1298J0D01*
G02X466053Y880647I1298J-1D01*
G01X466083Y880734D01*
X465277Y882131D01*
X465187Y882148D01*
G02X464132Y883423I243J1275D01*
G37*
G36*
G01X471532D02*
G02X474126I1297J0D01*
G02X474054Y882994I-1297J-3D01*
G01X474023Y882908D01*
X474829Y881511D01*
X474919Y881494D01*
G02X475976Y880219I-240J-1275D01*
G02X473380I-1298J0D01*
G02X473453Y880647I1298J-1D01*
G01X473483Y880734D01*
X472677Y882131D01*
X472587Y882148D01*
G02X471532Y883423I243J1275D01*
G37*
G36*
G01X478932D02*
G02X481526I1297J0D01*
G02X481454Y882994I-1297J-3D01*
G01X481423Y882908D01*
X482229Y881511D01*
X482319Y881494D01*
G02X483376Y880219I-240J-1275D01*
G02X480780I-1298J0D01*
G02X480853Y880647I1298J-1D01*
G01X480883Y880734D01*
X480077Y882131D01*
X479987Y882148D01*
G02X478932Y883423I243J1275D01*
G37*
G36*
G01X486332D02*
G02X488926I1297J0D01*
G02X488854Y882994I-1297J-3D01*
G01X488823Y882908D01*
X489629Y881511D01*
X489719Y881494D01*
G02X490776Y880219I-240J-1275D01*
G02X488180I-1298J0D01*
G02X488253Y880647I1298J-1D01*
G01X488283Y880734D01*
X487477Y882131D01*
X487387Y882148D01*
G02X486332Y883423I243J1275D01*
G37*
G36*
G01X493732D02*
G02X496326I1297J0D01*
G02X496254Y882994I-1297J-3D01*
G01X496223Y882908D01*
X497029Y881511D01*
X497119Y881494D01*
G02X498176Y880219I-240J-1275D01*
G02X495580I-1298J0D01*
G02X495653Y880647I1298J-1D01*
G01X495683Y880734D01*
X494877Y882131D01*
X494787Y882148D01*
G02X493732Y883423I243J1275D01*
G37*
G36*
G01X501132D02*
G02X503726I1297J0D01*
G02X503654Y882994I-1297J-3D01*
G01X503623Y882908D01*
X504429Y881511D01*
X504519Y881494D01*
G02X505576Y880219I-240J-1275D01*
G02X502980I-1298J0D01*
G02X503053Y880647I1298J-1D01*
G01X503083Y880734D01*
X502277Y882131D01*
X502187Y882148D01*
G02X501132Y883423I243J1275D01*
G37*
G36*
G01X508532D02*
G02X511126I1297J0D01*
G02X511054Y882994I-1297J-3D01*
G01X511023Y882908D01*
X511829Y881511D01*
X511919Y881494D01*
G02X512976Y880219I-240J-1275D01*
G02X510380I-1298J0D01*
G02X510453Y880647I1298J-1D01*
G01X510483Y880734D01*
X509677Y882131D01*
X509587Y882148D01*
G02X508532Y883423I243J1275D01*
G37*
G36*
G01X1344074D02*
G02X1346668I1297J0D01*
G02X1346596Y882994I-1297J-3D01*
G01X1346565Y882908D01*
X1347371Y881511D01*
X1347461Y881494D01*
G02X1348518Y880219I-240J-1275D01*
G02X1345922I-1298J0D01*
G02X1345995Y880647I1298J-1D01*
G01X1346025Y880734D01*
X1345219Y882131D01*
X1345129Y882148D01*
G02X1344074Y883423I243J1275D01*
G37*
G36*
G01X1351474D02*
G02X1354068I1297J0D01*
G02X1353996Y882994I-1297J-3D01*
G01X1353965Y882908D01*
X1354771Y881511D01*
X1354861Y881494D01*
G02X1355918Y880219I-240J-1275D01*
G02X1353322I-1298J0D01*
G02X1353395Y880647I1298J-1D01*
G01X1353425Y880734D01*
X1352619Y882131D01*
X1352529Y882148D01*
G02X1351474Y883423I243J1275D01*
G37*
G36*
G01X1358874D02*
G02X1361468I1297J0D01*
G02X1361396Y882994I-1297J-3D01*
G01X1361365Y882908D01*
X1362171Y881511D01*
X1362261Y881494D01*
G02X1363318Y880219I-240J-1275D01*
G02X1360722I-1298J0D01*
G02X1360795Y880647I1298J-1D01*
G01X1360825Y880734D01*
X1360019Y882131D01*
X1359929Y882148D01*
G02X1358874Y883423I243J1275D01*
G37*
G36*
G01X1366274D02*
G02X1368868I1297J0D01*
G02X1368796Y882994I-1297J-3D01*
G01X1368765Y882908D01*
X1369571Y881511D01*
X1369661Y881494D01*
G02X1370718Y880219I-240J-1275D01*
G02X1368122I-1298J0D01*
G02X1368195Y880647I1298J-1D01*
G01X1368225Y880734D01*
X1367419Y882131D01*
X1367329Y882148D01*
G02X1366274Y883423I243J1275D01*
G37*
G36*
G01X1373674D02*
G02X1376268I1297J0D01*
G02X1376196Y882994I-1297J-3D01*
G01X1376165Y882908D01*
X1376971Y881511D01*
X1377061Y881494D01*
G02X1378118Y880219I-240J-1275D01*
G02X1375522I-1298J0D01*
G02X1375595Y880647I1298J-1D01*
G01X1375625Y880734D01*
X1374819Y882131D01*
X1374729Y882148D01*
G02X1373674Y883423I243J1275D01*
G37*
G36*
G01X1381074D02*
G02X1383668I1297J0D01*
G02X1383596Y882994I-1297J-3D01*
G01X1383565Y882908D01*
X1384371Y881511D01*
X1384461Y881494D01*
G02X1385518Y880219I-240J-1275D01*
G02X1382922I-1298J0D01*
G02X1382995Y880647I1298J-1D01*
G01X1383025Y880734D01*
X1382219Y882131D01*
X1382129Y882148D01*
G02X1381074Y883423I243J1275D01*
G37*
G36*
G01X1388474D02*
G02X1391068I1297J0D01*
G02X1390996Y882994I-1297J-3D01*
G01X1390965Y882908D01*
X1391771Y881511D01*
X1391861Y881494D01*
G02X1392918Y880219I-240J-1275D01*
G02X1390322I-1298J0D01*
G02X1390395Y880647I1298J-1D01*
G01X1390425Y880734D01*
X1389619Y882131D01*
X1389529Y882148D01*
G02X1388474Y883423I243J1275D01*
G37*
G36*
G01X1395874D02*
G02X1398468I1297J0D01*
G02X1398396Y882994I-1297J-3D01*
G01X1398365Y882908D01*
X1399171Y881511D01*
X1399261Y881494D01*
G02X1400318Y880219I-240J-1275D01*
G02X1397722I-1298J0D01*
G02X1397795Y880647I1298J-1D01*
G01X1397825Y880734D01*
X1397019Y882131D01*
X1396929Y882148D01*
G02X1395874Y883423I243J1275D01*
G37*
G36*
G01X1403274D02*
G02X1405868I1297J0D01*
G02X1405796Y882994I-1297J-3D01*
G01X1405765Y882908D01*
X1406571Y881511D01*
X1406661Y881494D01*
G02X1407718Y880219I-240J-1275D01*
G02X1405122I-1298J0D01*
G02X1405195Y880647I1298J-1D01*
G01X1405225Y880734D01*
X1404419Y882131D01*
X1404329Y882148D01*
G02X1403274Y883423I243J1275D01*
G37*
G36*
G01X1410674D02*
G02X1413268I1297J0D01*
G02X1413196Y882994I-1297J-3D01*
G01X1413165Y882908D01*
X1413971Y881511D01*
X1414061Y881494D01*
G02X1415118Y880219I-240J-1275D01*
G02X1412522I-1298J0D01*
G02X1412595Y880647I1298J-1D01*
G01X1412625Y880734D01*
X1411819Y882131D01*
X1411729Y882148D01*
G02X1410674Y883423I243J1275D01*
G37*
G36*
G01X1418074D02*
G02X1420668I1297J0D01*
G02X1420596Y882994I-1297J-3D01*
G01X1420565Y882908D01*
X1421371Y881511D01*
X1421461Y881494D01*
G02X1422518Y880219I-240J-1275D01*
G02X1419922I-1298J0D01*
G02X1419995Y880647I1298J-1D01*
G01X1420025Y880734D01*
X1419219Y882131D01*
X1419129Y882148D01*
G02X1418074Y883423I243J1275D01*
G37*
G36*
G01X1425474D02*
G02X1428068I1297J0D01*
G02X1427996Y882994I-1297J-3D01*
G01X1427965Y882908D01*
X1428771Y881511D01*
X1428861Y881494D01*
G02X1429918Y880219I-240J-1275D01*
G02X1427324I-1297J0D01*
G01Y880221D01*
G02X1427396Y880646I1297J-1D01*
G01X1427426Y880733D01*
X1426619Y882131D01*
X1426529Y882148D01*
G02X1425474Y883423I243J1275D01*
G37*
G36*
G01X1432874D02*
G02X1435468I1297J0D01*
G02X1435396Y882994I-1297J-3D01*
G01X1435365Y882908D01*
X1436171Y881511D01*
X1436261Y881494D01*
G02X1437318Y880219I-240J-1275D01*
G02X1434722I-1298J0D01*
G02X1434795Y880647I1298J-1D01*
G01X1434825Y880734D01*
X1434019Y882131D01*
X1433929Y882148D01*
G02X1432874Y883423I243J1275D01*
G37*
G36*
G01X1440274D02*
G02X1442868I1297J0D01*
G02X1442796Y882994I-1297J-3D01*
G01X1442765Y882908D01*
X1443571Y881511D01*
X1443661Y881494D01*
G02X1444718Y880219I-240J-1275D01*
G02X1442122I-1298J0D01*
G02X1442195Y880647I1298J-1D01*
G01X1442225Y880734D01*
X1441419Y882131D01*
X1441329Y882148D01*
G02X1440274Y883423I243J1275D01*
G37*
G36*
G01X1447674D02*
G02X1450268I1297J0D01*
G02X1450196Y882994I-1297J-3D01*
G01X1450165Y882908D01*
X1450971Y881511D01*
X1451061Y881494D01*
G02X1452118Y880219I-240J-1275D01*
G02X1449522I-1298J0D01*
G02X1449595Y880647I1298J-1D01*
G01X1449625Y880734D01*
X1448819Y882131D01*
X1448729Y882148D01*
G02X1447674Y883423I243J1275D01*
G37*
G36*
G01X1455074D02*
G02X1457668I1297J0D01*
G02X1457596Y882994I-1297J-3D01*
G01X1457565Y882908D01*
X1458371Y881511D01*
X1458461Y881494D01*
G02X1459518Y880219I-240J-1275D01*
G02X1456922I-1298J0D01*
G02X1456995Y880647I1298J-1D01*
G01X1457025Y880734D01*
X1456219Y882131D01*
X1456129Y882148D01*
G02X1455074Y883423I243J1275D01*
G37*
G36*
G01X1462474D02*
G02X1465068I1297J0D01*
G02X1464996Y882994I-1297J-3D01*
G01X1464965Y882908D01*
X1465771Y881511D01*
X1465861Y881494D01*
G02X1466918Y880219I-240J-1275D01*
G02X1464322I-1298J0D01*
G02X1464395Y880647I1298J-1D01*
G01X1464425Y880734D01*
X1463619Y882131D01*
X1463529Y882148D01*
G02X1462474Y883423I243J1275D01*
G37*
G36*
G01X1469874D02*
G02X1472468I1297J0D01*
G02X1472396Y882994I-1297J-3D01*
G01X1472365Y882908D01*
X1473171Y881511D01*
X1473261Y881494D01*
G02X1474318Y880219I-240J-1275D01*
G02X1471722I-1298J0D01*
G02X1471795Y880647I1298J-1D01*
G01X1471825Y880734D01*
X1471019Y882131D01*
X1470929Y882148D01*
G02X1469874Y883423I243J1275D01*
G37*
G36*
G01X1477274D02*
G02X1479868I1297J0D01*
G02X1479796Y882994I-1297J-3D01*
G01X1479765Y882908D01*
X1480571Y881511D01*
X1480661Y881494D01*
G02X1481718Y880219I-240J-1275D01*
G02X1479122I-1298J0D01*
G02X1479195Y880647I1298J-1D01*
G01X1479225Y880734D01*
X1478419Y882131D01*
X1478329Y882148D01*
G02X1477274Y883423I243J1275D01*
G37*
G36*
G01X1484674D02*
G02X1487268I1297J0D01*
G02X1487196Y882994I-1297J-3D01*
G01X1487165Y882908D01*
X1487971Y881511D01*
X1488061Y881494D01*
G02X1489118Y880219I-240J-1275D01*
G02X1486522I-1298J0D01*
G02X1486595Y880647I1298J-1D01*
G01X1486625Y880734D01*
X1485819Y882131D01*
X1485729Y882148D01*
G02X1484674Y883423I243J1275D01*
G37*
G36*
G01X373480Y886627D02*
G02X376076I1298J0D01*
G02X375020Y885352I-1298J0D01*
G01X374930Y885335D01*
X374123Y883938D01*
X374154Y883851D01*
G02X374226Y883423I-1225J-426D01*
G02X371632I-1297J0D01*
G02X372687Y884698I1298J0D01*
G01X372777Y884715D01*
X373584Y886112D01*
X373553Y886199D01*
G02X373480Y886627I1225J429D01*
G37*
G36*
G01X380880D02*
G02X383476I1298J0D01*
G02X382420Y885352I-1298J0D01*
G01X382330Y885335D01*
X381523Y883938D01*
X381554Y883851D01*
G02X381626Y883423I-1225J-426D01*
G02X379032I-1297J0D01*
G02X380087Y884698I1298J0D01*
G01X380177Y884715D01*
X380984Y886112D01*
X380953Y886199D01*
G02X380880Y886627I1225J429D01*
G37*
G36*
G01X388280D02*
G02X390876I1298J0D01*
G02X389820Y885352I-1298J0D01*
G01X389730Y885335D01*
X388923Y883938D01*
X388954Y883851D01*
G02X389026Y883423I-1225J-426D01*
G02X386432I-1297J0D01*
G02X387487Y884698I1298J0D01*
G01X387577Y884715D01*
X388384Y886112D01*
X388353Y886199D01*
G02X388280Y886627I1225J429D01*
G37*
G36*
G01X395680D02*
G02X398276I1298J0D01*
G02X397220Y885352I-1298J0D01*
G01X397130Y885335D01*
X396323Y883938D01*
X396354Y883851D01*
G02X396426Y883423I-1225J-426D01*
G02X393832I-1297J0D01*
G02X394887Y884698I1298J0D01*
G01X394977Y884715D01*
X395784Y886112D01*
X395753Y886199D01*
G02X395680Y886627I1225J429D01*
G37*
G36*
G01X403080D02*
G02X405676I1298J0D01*
G02X404620Y885352I-1298J0D01*
G01X404530Y885335D01*
X403723Y883938D01*
X403754Y883851D01*
G02X403826Y883423I-1225J-426D01*
G02X401232I-1297J0D01*
G02X402287Y884698I1298J0D01*
G01X402377Y884715D01*
X403184Y886112D01*
X403153Y886199D01*
G02X403080Y886627I1225J429D01*
G37*
G36*
G01X410480D02*
G02X413076I1298J0D01*
G02X412020Y885352I-1298J0D01*
G01X411930Y885335D01*
X411123Y883938D01*
X411154Y883851D01*
G02X411226Y883423I-1225J-426D01*
G02X408632I-1297J0D01*
G02X409687Y884698I1298J0D01*
G01X409777Y884715D01*
X410584Y886112D01*
X410553Y886199D01*
G02X410480Y886627I1225J429D01*
G37*
G36*
G01X417880D02*
G02X420476I1298J0D01*
G02X419420Y885352I-1298J0D01*
G01X419330Y885335D01*
X418523Y883938D01*
X418554Y883851D01*
G02X418626Y883423I-1225J-426D01*
G02X416032I-1297J0D01*
G02X417087Y884698I1298J0D01*
G01X417177Y884715D01*
X417984Y886112D01*
X417953Y886199D01*
G02X417880Y886627I1225J429D01*
G37*
G36*
G01X425280D02*
G02X427876I1298J0D01*
G02X426820Y885352I-1298J0D01*
G01X426730Y885335D01*
X425923Y883938D01*
X425954Y883851D01*
G02X426026Y883423I-1225J-426D01*
G02X423432I-1297J0D01*
G02X424487Y884698I1298J0D01*
G01X424577Y884715D01*
X425384Y886112D01*
X425353Y886199D01*
G02X425280Y886627I1225J429D01*
G37*
G36*
G01X432680D02*
G02X435276I1298J0D01*
G02X434220Y885352I-1298J0D01*
G01X434130Y885335D01*
X433323Y883938D01*
X433354Y883851D01*
G02X433426Y883423I-1225J-426D01*
G02X430832I-1297J0D01*
G02X431887Y884698I1298J0D01*
G01X431977Y884715D01*
X432784Y886112D01*
X432753Y886199D01*
G02X432680Y886627I1225J429D01*
G37*
G36*
G01X440080D02*
G02X442676I1298J0D01*
G02X441620Y885352I-1298J0D01*
G01X441530Y885335D01*
X440723Y883938D01*
X440754Y883851D01*
G02X440826Y883423I-1225J-426D01*
G02X438232I-1297J0D01*
G02X439287Y884698I1298J0D01*
G01X439377Y884715D01*
X440184Y886112D01*
X440153Y886199D01*
G02X440080Y886627I1225J429D01*
G37*
G36*
G01X447480D02*
G02X450076I1298J0D01*
G02X449020Y885352I-1298J0D01*
G01X448930Y885335D01*
X448123Y883938D01*
X448154Y883851D01*
G02X448226Y883423I-1225J-426D01*
G02X445632I-1297J0D01*
G02X446687Y884698I1298J0D01*
G01X446777Y884715D01*
X447584Y886112D01*
X447553Y886199D01*
G02X447480Y886627I1225J429D01*
G37*
G36*
G01X454880D02*
G02X457476I1298J0D01*
G02X456420Y885352I-1298J0D01*
G01X456330Y885335D01*
X455523Y883938D01*
X455554Y883851D01*
G02X455626Y883423I-1225J-426D01*
G02X453032I-1297J0D01*
G02X454087Y884698I1298J0D01*
G01X454177Y884715D01*
X454984Y886112D01*
X454953Y886199D01*
G02X454880Y886627I1225J429D01*
G37*
G36*
G01X462280D02*
G02X464876I1298J0D01*
G02X463820Y885352I-1298J0D01*
G01X463730Y885335D01*
X462923Y883938D01*
X462954Y883851D01*
G02X463026Y883423I-1225J-426D01*
G02X460432I-1297J0D01*
G02X461487Y884698I1298J0D01*
G01X461577Y884715D01*
X462384Y886112D01*
X462353Y886199D01*
G02X462280Y886627I1225J429D01*
G37*
G36*
G01X469680D02*
G02X472276I1298J0D01*
G02X471220Y885352I-1298J0D01*
G01X471130Y885335D01*
X470323Y883938D01*
X470354Y883851D01*
G02X470426Y883423I-1225J-426D01*
G02X467832I-1297J0D01*
G02X468887Y884698I1298J0D01*
G01X468977Y884715D01*
X469784Y886112D01*
X469753Y886199D01*
G02X469680Y886627I1225J429D01*
G37*
G36*
G01X477080D02*
G02X479676I1298J0D01*
G02X478620Y885352I-1298J0D01*
G01X478530Y885335D01*
X477723Y883938D01*
X477754Y883851D01*
G02X477826Y883423I-1225J-426D01*
G02X475232I-1297J0D01*
G02X476287Y884698I1298J0D01*
G01X476377Y884715D01*
X477184Y886112D01*
X477153Y886199D01*
G02X477080Y886627I1225J429D01*
G37*
G36*
G01X484480D02*
G02X487076I1298J0D01*
G02X486020Y885352I-1298J0D01*
G01X485930Y885335D01*
X485123Y883938D01*
X485154Y883851D01*
G02X485226Y883423I-1225J-426D01*
G02X482632I-1297J0D01*
G02X483687Y884698I1298J0D01*
G01X483777Y884715D01*
X484584Y886112D01*
X484553Y886199D01*
G02X484480Y886627I1225J429D01*
G37*
G36*
G01X491880D02*
G02X494476I1298J0D01*
G02X493420Y885352I-1298J0D01*
G01X493330Y885335D01*
X492523Y883938D01*
X492554Y883851D01*
G02X492626Y883423I-1225J-426D01*
G02X490032I-1297J0D01*
G02X491087Y884698I1298J0D01*
G01X491177Y884715D01*
X491984Y886112D01*
X491953Y886199D01*
G02X491880Y886627I1225J429D01*
G37*
G36*
G01X499280D02*
G02X501876I1298J0D01*
G02X500820Y885352I-1298J0D01*
G01X500730Y885335D01*
X499923Y883938D01*
X499954Y883851D01*
G02X500026Y883423I-1225J-426D01*
G02X497432I-1297J0D01*
G02X498487Y884698I1298J0D01*
G01X498577Y884715D01*
X499384Y886112D01*
X499353Y886199D01*
G02X499280Y886627I1225J429D01*
G37*
G36*
G01X506680D02*
G02X509276I1298J0D01*
G02X508220Y885352I-1298J0D01*
G01X508130Y885335D01*
X507323Y883938D01*
X507354Y883851D01*
G02X507426Y883423I-1225J-426D01*
G02X504832I-1297J0D01*
G02X505887Y884698I1298J0D01*
G01X505977Y884715D01*
X506784Y886112D01*
X506753Y886199D01*
G02X506680Y886627I1225J429D01*
G37*
G36*
G01X514080D02*
G02X516676I1298J0D01*
G02X515620Y885352I-1298J0D01*
G01X515530Y885335D01*
X514723Y883938D01*
X514754Y883851D01*
G02X514826Y883423I-1225J-426D01*
G02X512232I-1297J0D01*
G02X513287Y884698I1298J0D01*
G01X513377Y884715D01*
X514184Y886112D01*
X514153Y886199D01*
G02X514080Y886627I1225J429D01*
G37*
G36*
G01X521480D02*
G02X524076I1298J0D01*
G02X523020Y885352I-1298J0D01*
G01X522930Y885335D01*
X522123Y883938D01*
X522154Y883851D01*
G02X522226Y883423I-1225J-426D01*
G02X519632I-1297J0D01*
G02X520687Y884698I1298J0D01*
G01X520777Y884715D01*
X521584Y886112D01*
X521553Y886199D01*
G02X521480Y886627I1225J429D01*
G37*
G36*
G01X1349622D02*
G02X1352218I1298J0D01*
G02X1351162Y885352I-1298J0D01*
G01X1351072Y885335D01*
X1350265Y883938D01*
X1350296Y883851D01*
G02X1350368Y883423I-1225J-426D01*
G02X1347774I-1297J0D01*
G02X1348829Y884698I1298J0D01*
G01X1348919Y884715D01*
X1349726Y886112D01*
X1349695Y886199D01*
G02X1349622Y886627I1225J429D01*
G37*
G36*
G01X1357022D02*
G02X1359618I1298J0D01*
G02X1358562Y885352I-1298J0D01*
G01X1358472Y885335D01*
X1357665Y883938D01*
X1357696Y883851D01*
G02X1357768Y883423I-1225J-426D01*
G02X1355174I-1297J0D01*
G02X1356229Y884698I1298J0D01*
G01X1356319Y884715D01*
X1357126Y886112D01*
X1357095Y886199D01*
G02X1357022Y886627I1225J429D01*
G37*
G36*
G01X1364422D02*
G02X1367018I1298J0D01*
G02X1365962Y885352I-1298J0D01*
G01X1365872Y885335D01*
X1365065Y883938D01*
X1365096Y883851D01*
G02X1365168Y883423I-1225J-426D01*
G02X1362574I-1297J0D01*
G02X1363629Y884698I1298J0D01*
G01X1363719Y884715D01*
X1364526Y886112D01*
X1364495Y886199D01*
G02X1364422Y886627I1225J429D01*
G37*
G36*
G01X1371822D02*
G02X1374418I1298J0D01*
G02X1373362Y885352I-1298J0D01*
G01X1373272Y885335D01*
X1372465Y883938D01*
X1372496Y883851D01*
G02X1372568Y883423I-1225J-426D01*
G02X1369974I-1297J0D01*
G02X1371029Y884698I1298J0D01*
G01X1371119Y884715D01*
X1371926Y886112D01*
X1371895Y886199D01*
G02X1371822Y886627I1225J429D01*
G37*
G36*
G01X1379222D02*
G02X1381818I1298J0D01*
G02X1380762Y885352I-1298J0D01*
G01X1380672Y885335D01*
X1379865Y883938D01*
X1379896Y883851D01*
G02X1379968Y883423I-1225J-426D01*
G02X1377374I-1297J0D01*
G02X1378429Y884698I1298J0D01*
G01X1378519Y884715D01*
X1379326Y886112D01*
X1379295Y886199D01*
G02X1379222Y886627I1225J429D01*
G37*
G36*
G01X1386622D02*
G02X1389218I1298J0D01*
G02X1388162Y885352I-1298J0D01*
G01X1388072Y885335D01*
X1387265Y883938D01*
X1387296Y883851D01*
G02X1387368Y883423I-1225J-426D01*
G02X1384774I-1297J0D01*
G02X1385829Y884698I1298J0D01*
G01X1385919Y884715D01*
X1386726Y886112D01*
X1386695Y886199D01*
G02X1386622Y886627I1225J429D01*
G37*
G36*
G01X1394022D02*
G02X1396618I1298J0D01*
G02X1395562Y885352I-1298J0D01*
G01X1395472Y885335D01*
X1394665Y883938D01*
X1394696Y883851D01*
G02X1394768Y883423I-1225J-426D01*
G02X1392174I-1297J0D01*
G02X1393229Y884698I1298J0D01*
G01X1393319Y884715D01*
X1394126Y886112D01*
X1394095Y886199D01*
G02X1394022Y886627I1225J429D01*
G37*
G36*
G01X1401422D02*
G02X1404018I1298J0D01*
G02X1402962Y885352I-1298J0D01*
G01X1402872Y885335D01*
X1402065Y883938D01*
X1402096Y883851D01*
G02X1402168Y883423I-1225J-426D01*
G02X1399574I-1297J0D01*
G02X1400629Y884698I1298J0D01*
G01X1400719Y884715D01*
X1401526Y886112D01*
X1401495Y886199D01*
G02X1401422Y886627I1225J429D01*
G37*
G36*
G01X1408822D02*
G02X1411418I1298J0D01*
G02X1410362Y885352I-1298J0D01*
G01X1410272Y885335D01*
X1409465Y883938D01*
X1409496Y883851D01*
G02X1409568Y883423I-1225J-426D01*
G02X1406974I-1297J0D01*
G02X1408029Y884698I1298J0D01*
G01X1408119Y884715D01*
X1408926Y886112D01*
X1408895Y886199D01*
G02X1408822Y886627I1225J429D01*
G37*
G36*
G01X1416222D02*
G02X1418818I1298J0D01*
G02X1417762Y885352I-1298J0D01*
G01X1417672Y885335D01*
X1416865Y883938D01*
X1416896Y883851D01*
G02X1416968Y883423I-1225J-426D01*
G02X1414374I-1297J0D01*
G02X1415429Y884698I1298J0D01*
G01X1415519Y884715D01*
X1416326Y886112D01*
X1416295Y886199D01*
G02X1416222Y886627I1225J429D01*
G37*
G36*
G01X1423622D02*
G02X1426218I1298J0D01*
G02X1425162Y885352I-1298J0D01*
G01X1425072Y885335D01*
X1424265Y883938D01*
X1424296Y883851D01*
G02X1424368Y883423I-1225J-426D01*
G02X1421774I-1297J0D01*
G02X1422829Y884698I1298J0D01*
G01X1422919Y884715D01*
X1423726Y886112D01*
X1423695Y886199D01*
G02X1423622Y886627I1225J429D01*
G37*
G36*
G01X1431022D02*
G02X1433618I1298J0D01*
G02X1432562Y885352I-1298J0D01*
G01X1432472Y885335D01*
X1431665Y883938D01*
X1431696Y883851D01*
G02X1431768Y883423I-1225J-426D01*
G02X1429174I-1297J0D01*
G02X1430229Y884698I1298J0D01*
G01X1430319Y884715D01*
X1431126Y886112D01*
X1431095Y886199D01*
G02X1431022Y886627I1225J429D01*
G37*
G36*
G01X1438422D02*
G02X1441018I1298J0D01*
G02X1439962Y885352I-1298J0D01*
G01X1439872Y885335D01*
X1439065Y883938D01*
X1439096Y883851D01*
G02X1439168Y883423I-1225J-426D01*
G02X1436574I-1297J0D01*
G02X1437629Y884698I1298J0D01*
G01X1437719Y884715D01*
X1438526Y886112D01*
X1438495Y886199D01*
G02X1438422Y886627I1225J429D01*
G37*
G36*
G01X1445822D02*
G02X1448418I1298J0D01*
G02X1447362Y885352I-1298J0D01*
G01X1447272Y885335D01*
X1446465Y883938D01*
X1446496Y883851D01*
G02X1446568Y883423I-1225J-426D01*
G02X1443974I-1297J0D01*
G02X1445029Y884698I1298J0D01*
G01X1445119Y884715D01*
X1445926Y886112D01*
X1445895Y886199D01*
G02X1445822Y886627I1225J429D01*
G37*
G36*
G01X1453222D02*
G02X1455818I1298J0D01*
G02X1454762Y885352I-1298J0D01*
G01X1454672Y885335D01*
X1453865Y883938D01*
X1453896Y883851D01*
G02X1453968Y883423I-1225J-426D01*
G02X1451374I-1297J0D01*
G02X1452429Y884698I1298J0D01*
G01X1452519Y884715D01*
X1453326Y886112D01*
X1453295Y886199D01*
G02X1453222Y886627I1225J429D01*
G37*
G36*
G01X1460622D02*
G02X1463218I1298J0D01*
G02X1462162Y885352I-1298J0D01*
G01X1462072Y885335D01*
X1461265Y883938D01*
X1461296Y883851D01*
G02X1461368Y883423I-1225J-426D01*
G02X1458774I-1297J0D01*
G02X1459829Y884698I1298J0D01*
G01X1459919Y884715D01*
X1460726Y886112D01*
X1460695Y886199D01*
G02X1460622Y886627I1225J429D01*
G37*
G36*
G01X1468022D02*
G02X1470618I1298J0D01*
G02X1469562Y885352I-1298J0D01*
G01X1469472Y885335D01*
X1468665Y883938D01*
X1468696Y883851D01*
G02X1468768Y883423I-1225J-426D01*
G02X1466174I-1297J0D01*
G02X1467229Y884698I1298J0D01*
G01X1467319Y884715D01*
X1468126Y886112D01*
X1468095Y886199D01*
G02X1468022Y886627I1225J429D01*
G37*
G36*
G01X1475422D02*
G02X1478018I1298J0D01*
G02X1476962Y885352I-1298J0D01*
G01X1476872Y885335D01*
X1476065Y883938D01*
X1476096Y883851D01*
G02X1476168Y883423I-1225J-426D01*
G02X1473574I-1297J0D01*
G02X1474629Y884698I1298J0D01*
G01X1474719Y884715D01*
X1475526Y886112D01*
X1475495Y886199D01*
G02X1475422Y886627I1225J429D01*
G37*
G36*
G01X1482822D02*
G02X1485418I1298J0D01*
G02X1484362Y885352I-1298J0D01*
G01X1484272Y885335D01*
X1483465Y883938D01*
X1483496Y883851D01*
G02X1483568Y883423I-1225J-426D01*
G02X1480974I-1297J0D01*
G02X1482029Y884698I1298J0D01*
G01X1482119Y884715D01*
X1482926Y886112D01*
X1482895Y886199D01*
G02X1482822Y886627I1225J429D01*
G37*
G36*
G01X1490222D02*
G02X1492818I1298J0D01*
G02X1491762Y885352I-1298J0D01*
G01X1491672Y885335D01*
X1490865Y883938D01*
X1490896Y883851D01*
G02X1490968Y883423I-1225J-426D01*
G02X1488374I-1297J0D01*
G02X1489429Y884698I1298J0D01*
G01X1489519Y884715D01*
X1490326Y886112D01*
X1490295Y886199D01*
G02X1490222Y886627I1225J429D01*
G37*
G36*
G01X1497622D02*
G02X1500218I1298J0D01*
G02X1499162Y885352I-1298J0D01*
G01X1499072Y885335D01*
X1498265Y883938D01*
X1498296Y883851D01*
G02X1498368Y883423I-1225J-426D01*
G02X1495774I-1297J0D01*
G02X1496829Y884698I1298J0D01*
G01X1496919Y884715D01*
X1497726Y886112D01*
X1497695Y886199D01*
G02X1497622Y886627I1225J429D01*
G37*
G36*
G01X429414Y1079791D02*
G02X432008I1297J0D01*
G02X430953Y1078516I-1298J0D01*
G01X430863Y1078499D01*
X430056Y1077101D01*
X430086Y1077015D01*
G02X430158Y1076587I-1225J-426D01*
G02X427564I-1297J0D01*
G02X428620Y1077862I1298J0D01*
G01X428710Y1077879D01*
X429517Y1079276D01*
X429486Y1079363D01*
G02X429414Y1079791I1225J426D01*
G37*
G36*
G01X1405556D02*
G02X1408150I1297J0D01*
G02X1407095Y1078516I-1298J0D01*
G01X1407005Y1078499D01*
X1406198Y1077101D01*
X1406228Y1077015D01*
G02X1406300Y1076587I-1225J-426D01*
G02X1403706I-1297J0D01*
G02X1404762Y1077862I1298J0D01*
G01X1404852Y1077879D01*
X1405659Y1079276D01*
X1405628Y1079363D01*
G02X1405556Y1079791I1225J426D01*
G37*
G36*
G01X402962Y1084292D02*
G02X404001Y1083772I0J-1298D01*
G01X405623D01*
G02X406662Y1084292I1039J-778D01*
G02Y1081698I0J-1297D01*
G02X405623Y1082218I0J1298D01*
G01X404001D01*
G02X402962Y1081698I-1039J778D01*
G02Y1084292I0J1297D01*
G37*
G36*
G01X409064Y1082995D02*
G02X411660I1298J0D01*
G02X410604Y1081720I-1298J0D01*
G01X410514Y1081703D01*
X409706Y1080304D01*
X409736Y1080218D01*
G02X409808Y1079793I-1225J-426D01*
G01Y1079791D01*
G02X407214I-1297J0D01*
G02X408271Y1081066I1297J0D01*
G01X408361Y1081083D01*
X409168Y1082480D01*
X409137Y1082567D01*
G02X409064Y1082995I1225J429D01*
G37*
G36*
G01X1379104Y1084292D02*
G02X1380143Y1083772I0J-1298D01*
G01X1381765D01*
G02X1382804Y1084292I1039J-778D01*
G02Y1081698I0J-1297D01*
G02X1381765Y1082218I0J1298D01*
G01X1380143D01*
G02X1379104Y1081698I-1039J778D01*
G02Y1084292I0J1297D01*
G37*
G36*
G01X1385206Y1082995D02*
G02X1387802I1298J0D01*
G02X1386746Y1081720I-1298J0D01*
G01X1386656Y1081703D01*
X1385848Y1080304D01*
X1385878Y1080218D01*
G02X1385950Y1079793I-1225J-426D01*
G01Y1079791D01*
G02X1383356I-1297J0D01*
G02X1384413Y1081066I1297J0D01*
G01X1384503Y1081083D01*
X1385310Y1082480D01*
X1385279Y1082567D01*
G02X1385206Y1082995I1225J429D01*
G37*
G36*
G01X410914Y1086200D02*
G02X413508I1297J0D01*
G02X413436Y1085772I-1297J-2D01*
G01X413405Y1085685D01*
X414212Y1084287D01*
X414303Y1084270D01*
G02X415360Y1082995I-240J-1275D01*
G02X412764I-1298J0D01*
G02X412837Y1083422I1298J-2D01*
G01X412867Y1083509D01*
X412059Y1084908D01*
X411969Y1084925D01*
G02X410914Y1086200I243J1275D01*
G37*
G36*
G01X419611Y1087498D02*
G02X420650Y1086978I0J-1298D01*
G01X422272D01*
G02X423311Y1087498I1039J-778D01*
G02Y1084902I0J-1298D01*
G02X422272Y1085422I0J1298D01*
G01X420650D01*
G02X419611Y1084902I-1039J778D01*
G02Y1087498I0J1298D01*
G37*
G36*
G01X425714Y1086200D02*
G02X428310I1298J0D01*
G02X427254Y1084925I-1298J0D01*
G01X427164Y1084908D01*
X426356Y1083510D01*
X426387Y1083423D01*
G02X426460Y1082995I-1225J-429D01*
G02X423864I-1298J0D01*
G02X424920Y1084270I1298J0D01*
G01X425010Y1084287D01*
X425818Y1085685D01*
X425787Y1085772D01*
G02X425714Y1086200I1225J429D01*
G37*
G36*
G01X1387056D02*
G02X1389650I1297J0D01*
G02X1389578Y1085772I-1297J-2D01*
G01X1389547Y1085685D01*
X1390354Y1084287D01*
X1390445Y1084270D01*
G02X1391502Y1082995I-240J-1275D01*
G02X1388906I-1298J0D01*
G02X1388979Y1083422I1298J-2D01*
G01X1389009Y1083509D01*
X1388201Y1084908D01*
X1388111Y1084925D01*
G02X1387056Y1086200I243J1275D01*
G37*
G36*
G01X1395753Y1087498D02*
G02X1396792Y1086978I0J-1298D01*
G01X1398414D01*
G02X1399453Y1087498I1039J-778D01*
G02Y1084902I0J-1298D01*
G02X1398414Y1085422I0J1298D01*
G01X1396792D01*
G02X1395753Y1084902I-1039J778D01*
G02Y1087498I0J1298D01*
G37*
G36*
G01X1401856Y1086200D02*
G02X1404452I1298J0D01*
G02X1403396Y1084925I-1298J0D01*
G01X1403306Y1084908D01*
X1402498Y1083510D01*
X1402529Y1083423D01*
G02X1402602Y1082995I-1225J-429D01*
G02X1400006I-1298J0D01*
G02X1401062Y1084270I1298J0D01*
G01X1401152Y1084287D01*
X1401960Y1085685D01*
X1401929Y1085772D01*
G02X1401856Y1086200I1225J429D01*
G37*
G36*
G01X401664Y1089404D02*
G02X404258I1297J0D01*
G02X404186Y1088976I-1297J-2D01*
G01X404155Y1088889D01*
X404962Y1087492D01*
X405052Y1087475D01*
G02X406108Y1086200I-242J-1275D01*
G02X403514I-1297J0D01*
G02X403586Y1086628I1297J2D01*
G01X403616Y1086714D01*
X402809Y1088112D01*
X402719Y1088129D01*
G02X401664Y1089404I243J1275D01*
G37*
G36*
G01X410362Y1090702D02*
G02X411401Y1090182I0J-1298D01*
G01X413023D01*
G02X414062Y1090702I1039J-778D01*
G02Y1088106I0J-1298D01*
G02X413023Y1088626I0J1298D01*
G01X411401D01*
G02X410362Y1088106I-1039J778D01*
G02Y1090702I0J1298D01*
G37*
G36*
G01X427564Y1089404D02*
G02X430158I1297J0D01*
G02X430086Y1088976I-1297J-2D01*
G01X430055Y1088889D01*
X430862Y1087492D01*
X430952Y1087475D01*
G02X432008Y1086200I-242J-1275D01*
G02X429412I-1298J0D01*
G02X429485Y1086629I1297J0D01*
G01X429516Y1086715D01*
X428709Y1088112D01*
X428619Y1088129D01*
G02X427564Y1089404I243J1275D01*
G37*
G36*
G01X1377806D02*
G02X1380400I1297J0D01*
G02X1380328Y1088976I-1297J-2D01*
G01X1380297Y1088889D01*
X1381104Y1087492D01*
X1381194Y1087475D01*
G02X1382250Y1086200I-242J-1275D01*
G02X1379656I-1297J0D01*
G02X1379728Y1086628I1297J2D01*
G01X1379758Y1086714D01*
X1378951Y1088112D01*
X1378861Y1088129D01*
G02X1377806Y1089404I243J1275D01*
G37*
G36*
G01X1386504Y1090702D02*
G02X1387543Y1090182I0J-1298D01*
G01X1389165D01*
G02X1390204Y1090702I1039J-778D01*
G02Y1088106I0J-1298D01*
G02X1389165Y1088626I0J1298D01*
G01X1387543D01*
G02X1386504Y1088106I-1039J778D01*
G02Y1090702I0J1298D01*
G37*
G36*
G01X1403706Y1089404D02*
G02X1406300I1297J0D01*
G02X1406228Y1088976I-1297J-2D01*
G01X1406197Y1088889D01*
X1407004Y1087492D01*
X1407094Y1087475D01*
G02X1408150Y1086200I-242J-1275D01*
G02X1405554I-1298J0D01*
G02X1405627Y1086629I1297J0D01*
G01X1405658Y1086715D01*
X1404851Y1088112D01*
X1404761Y1088129D01*
G02X1403706Y1089404I243J1275D01*
G37*
G36*
G01X407214Y1092608D02*
G02X409808I1297J0D01*
G02X408753Y1091333I-1298J0D01*
G01X408663Y1091316D01*
X407856Y1089919D01*
X407887Y1089833D01*
G02X407960Y1089404I-1224J-429D01*
G02X405364I-1298J0D01*
G02X406420Y1090679I1298J0D01*
G01X406510Y1090696D01*
X407317Y1092093D01*
X407286Y1092180D01*
G02X407214Y1092608I1225J426D01*
G37*
G36*
G01X418314D02*
G02X420908I1297J0D01*
G02X420836Y1092180I-1297J-2D01*
G01X420805Y1092093D01*
X421612Y1090696D01*
X421702Y1090679D01*
G02X422760Y1089404I-239J-1275D01*
G02X420164I-1298J0D01*
G02X420237Y1089831I1298J-2D01*
G01X420267Y1089917D01*
X419459Y1091316D01*
X419369Y1091333D01*
G02X418314Y1092608I243J1275D01*
G37*
G36*
G01X427011Y1093906D02*
G02X428050Y1093386I0J-1298D01*
G01X429672D01*
G02X430711Y1093906I1039J-778D01*
G02Y1091310I0J-1298D01*
G02X429672Y1091830I0J1298D01*
G01X428050D01*
G02X427011Y1091310I-1039J778D01*
G02Y1093906I0J1298D01*
G37*
G36*
G01X1383356Y1092608D02*
G02X1385950I1297J0D01*
G02X1384895Y1091333I-1298J0D01*
G01X1384805Y1091316D01*
X1383998Y1089919D01*
X1384029Y1089833D01*
G02X1384102Y1089404I-1224J-429D01*
G02X1381506I-1298J0D01*
G02X1382562Y1090679I1298J0D01*
G01X1382652Y1090696D01*
X1383459Y1092093D01*
X1383428Y1092180D01*
G02X1383356Y1092608I1225J426D01*
G37*
G36*
G01X1394456D02*
G02X1397050I1297J0D01*
G02X1396978Y1092180I-1297J-2D01*
G01X1396947Y1092093D01*
X1397754Y1090696D01*
X1397844Y1090679D01*
G02X1398902Y1089404I-239J-1275D01*
G02X1396306I-1298J0D01*
G02X1396379Y1089831I1298J-2D01*
G01X1396409Y1089917D01*
X1395601Y1091316D01*
X1395511Y1091333D01*
G02X1394456Y1092608I243J1275D01*
G37*
G36*
G01X1403153Y1093906D02*
G02X1404192Y1093386I0J-1298D01*
G01X1405814D01*
G02X1406853Y1093906I1039J-778D01*
G02Y1091310I0J-1298D01*
G02X1405814Y1091830I0J1298D01*
G01X1404192D01*
G02X1403153Y1091310I-1039J778D01*
G02Y1093906I0J1298D01*
G37*
G36*
G01X423864Y1095813D02*
G02X426460I1298J0D01*
G02X425404Y1094538I-1298J0D01*
G01X425314Y1094521D01*
X424506Y1093122D01*
X424536Y1093035D01*
G02X424608Y1092610I-1225J-426D01*
G01Y1092608D01*
G02X422014I-1297J0D01*
G02X423070Y1093883I1298J0D01*
G01X423161Y1093900D01*
X423968Y1095298D01*
X423937Y1095385D01*
G02X423864Y1095813I1225J429D01*
G37*
G36*
G01X1400006D02*
G02X1402602I1298J0D01*
G02X1401546Y1094538I-1298J0D01*
G01X1401456Y1094521D01*
X1400648Y1093122D01*
X1400678Y1093035D01*
G02X1400750Y1092610I-1225J-426D01*
G01Y1092608D01*
G02X1398156I-1297J0D01*
G02X1399212Y1093883I1298J0D01*
G01X1399303Y1093900D01*
X1400110Y1095298D01*
X1400079Y1095385D01*
G02X1400006Y1095813I1225J429D01*
G37*
G36*
G01X404811Y1100314D02*
G02X405850Y1099794I0J-1298D01*
G01X407472D01*
G02X408511Y1100314I1039J-778D01*
G02Y1097720I0J-1297D01*
G02X407472Y1098240I0J1298D01*
G01X405850D01*
G02X404811Y1097720I-1039J778D01*
G02Y1100314I0J1297D01*
G37*
G36*
G01X1380953D02*
G02X1381992Y1099794I0J-1298D01*
G01X1383614D01*
G02X1384653Y1100314I1039J-778D01*
G02Y1097720I0J-1297D01*
G02X1383614Y1098240I0J1298D01*
G01X1381992D01*
G02X1380953Y1097720I-1039J778D01*
G02Y1100314I0J1297D01*
G37*
G36*
G01X351161Y1103518D02*
G02X352200Y1102998I0J-1298D01*
G01X353822D01*
G02X354861Y1103518I1039J-778D01*
G02Y1100924I0J-1297D01*
G02X353822Y1101444I0J1298D01*
G01X352200D01*
G02X351161Y1100924I-1039J778D01*
G02Y1103518I0J1297D01*
G37*
G36*
G01X401664Y1102221D02*
G02X404260I1298J0D01*
G02X403204Y1100946I-1298J0D01*
G01X403114Y1100929D01*
X402306Y1099530D01*
X402336Y1099444D01*
G02X402408Y1099019I-1225J-426D01*
G01Y1099017D01*
G02X399814I-1297J0D01*
G02X400871Y1100292I1297J0D01*
G01X400961Y1100309D01*
X401768Y1101706D01*
X401737Y1101793D01*
G02X401664Y1102221I1225J429D01*
G37*
G36*
G01X1327303Y1103518D02*
G02X1328342Y1102998I0J-1298D01*
G01X1329964D01*
G02X1331003Y1103518I1039J-778D01*
G02Y1100924I0J-1297D01*
G02X1329964Y1101444I0J1298D01*
G01X1328342D01*
G02X1327303Y1100924I-1039J778D01*
G02Y1103518I0J1297D01*
G37*
G36*
G01X1377806Y1102221D02*
G02X1380402I1298J0D01*
G02X1379346Y1100946I-1298J0D01*
G01X1379256Y1100929D01*
X1378448Y1099530D01*
X1378478Y1099444D01*
G02X1378550Y1099019I-1225J-426D01*
G01Y1099017D01*
G02X1375956I-1297J0D01*
G02X1377013Y1100292I1297J0D01*
G01X1377103Y1100309D01*
X1377910Y1101706D01*
X1377879Y1101793D01*
G02X1377806Y1102221I1225J429D01*
G37*
G36*
G01X375211Y1106724D02*
G02X376250Y1106204I0J-1298D01*
G01X377873D01*
G02X378912Y1106724I1039J-778D01*
G02Y1104128I0J-1298D01*
G02X377873Y1104648I0J1298D01*
G01X376250D01*
G02X375211Y1104128I-1039J778D01*
G02Y1106724I0J1298D01*
G37*
G36*
G01X381314Y1105426D02*
G02X383908I1297J0D01*
G02X382853Y1104151I-1298J0D01*
G01X382763Y1104134D01*
X381956Y1102737D01*
X381986Y1102650D01*
G02X382060Y1102221I-1223J-432D01*
G02X379464I-1298J0D01*
G02X380519Y1103496I1298J0D01*
G01X380609Y1103513D01*
X381417Y1104911D01*
X381386Y1104998D01*
G02X381314Y1105426I1225J426D01*
G37*
G36*
G01X410914D02*
G02X413508I1297J0D01*
G02X413436Y1104998I-1297J-2D01*
G01X413405Y1104911D01*
X414212Y1103513D01*
X414303Y1103496D01*
G02X415360Y1102221I-240J-1275D01*
G02X412764I-1298J0D01*
G02X412837Y1102648I1298J-2D01*
G01X412867Y1102735D01*
X412059Y1104134D01*
X411969Y1104151D01*
G02X410914Y1105426I243J1275D01*
G37*
G36*
G01X415911Y1106724D02*
G02X416950Y1106204I0J-1298D01*
G01X418572D01*
G02X419611Y1106724I1039J-778D01*
G02Y1104128I0J-1298D01*
G02X418572Y1104648I0J1298D01*
G01X416950D01*
G02X415911Y1104128I-1039J778D01*
G02Y1106724I0J1298D01*
G37*
G36*
G01X1351353D02*
G02X1352392Y1106204I0J-1298D01*
G01X1354015D01*
G02X1355054Y1106724I1039J-778D01*
G02Y1104128I0J-1298D01*
G02X1354015Y1104648I0J1298D01*
G01X1352392D01*
G02X1351353Y1104128I-1039J778D01*
G02Y1106724I0J1298D01*
G37*
G36*
G01X1357456Y1105426D02*
G02X1360050I1297J0D01*
G02X1358995Y1104151I-1298J0D01*
G01X1358905Y1104134D01*
X1358098Y1102737D01*
X1358128Y1102650D01*
G02X1358202Y1102221I-1223J-432D01*
G02X1355606I-1298J0D01*
G02X1356661Y1103496I1298J0D01*
G01X1356751Y1103513D01*
X1357559Y1104911D01*
X1357528Y1104998D01*
G02X1357456Y1105426I1225J426D01*
G37*
G36*
G01X1387056D02*
G02X1389650I1297J0D01*
G02X1389578Y1104998I-1297J-2D01*
G01X1389547Y1104911D01*
X1390354Y1103513D01*
X1390445Y1103496D01*
G02X1391502Y1102221I-240J-1275D01*
G02X1388906I-1298J0D01*
G02X1388979Y1102648I1298J-2D01*
G01X1389009Y1102735D01*
X1388201Y1104134D01*
X1388111Y1104151D01*
G02X1387056Y1105426I243J1275D01*
G37*
G36*
G01X1392053Y1106724D02*
G02X1393092Y1106204I0J-1298D01*
G01X1394714D01*
G02X1395753Y1106724I1039J-778D01*
G02Y1104128I0J-1298D01*
G02X1394714Y1104648I0J1298D01*
G01X1393092D01*
G02X1392053Y1104128I-1039J778D01*
G02Y1106724I0J1298D01*
G37*
G36*
G01X358561Y1109928D02*
G02X359600Y1109408I0J-1298D01*
G01X361222D01*
G02X362261Y1109928I1039J-778D01*
G02Y1107332I0J-1298D01*
G02X361222Y1107852I0J1298D01*
G01X359600D01*
G02X358561Y1107332I-1039J778D01*
G02Y1109928I0J1298D01*
G37*
G36*
G01X383164Y1108630D02*
G02X385760I1298J0D01*
G02X385687Y1108202I-1298J1D01*
G01X385656Y1108115D01*
X386463Y1106718D01*
X386553Y1106701D01*
G02X387608Y1105426I-243J-1275D01*
G02X385014I-1297J0D01*
G02X385086Y1105855I1297J3D01*
G01X385117Y1105941D01*
X384310Y1107338D01*
X384220Y1107355D01*
G02X383164Y1108630I242J1275D01*
G37*
G36*
G01X391862Y1109928D02*
G02X392901Y1109408I0J-1298D01*
G01X394523D01*
G02X395562Y1109928I1039J-778D01*
G02Y1107332I0J-1298D01*
G02X394523Y1107852I0J1298D01*
G01X392901D01*
G02X391862Y1107332I-1039J778D01*
G02Y1109928I0J1298D01*
G37*
G36*
G01X397964Y1108630D02*
G02X400560I1298J0D01*
G02X399504Y1107355I-1298J0D01*
G01X399414Y1107338D01*
X398606Y1105939D01*
X398636Y1105853D01*
G02X398708Y1105428I-1225J-426D01*
G01Y1105426D01*
G02X396114I-1297J0D01*
G02X397171Y1106701I1297J0D01*
G01X397261Y1106718D01*
X398068Y1108115D01*
X398037Y1108202D01*
G02X397964Y1108630I1225J429D01*
G37*
G36*
G01X409064D02*
G02X411660I1298J0D01*
G02X410604Y1107355I-1298J0D01*
G01X410514Y1107338D01*
X409706Y1105939D01*
X409736Y1105853D01*
G02X409808Y1105428I-1225J-426D01*
G01Y1105426D01*
G02X407214I-1297J0D01*
G02X408271Y1106701I1297J0D01*
G01X408361Y1106718D01*
X409168Y1108115D01*
X409137Y1108202D01*
G02X409064Y1108630I1225J429D01*
G37*
G36*
G01X1334703Y1109928D02*
G02X1335742Y1109408I0J-1298D01*
G01X1337364D01*
G02X1338403Y1109928I1039J-778D01*
G02Y1107332I0J-1298D01*
G02X1337364Y1107852I0J1298D01*
G01X1335742D01*
G02X1334703Y1107332I-1039J778D01*
G02Y1109928I0J1298D01*
G37*
G36*
G01X1359306Y1108630D02*
G02X1361902I1298J0D01*
G02X1361829Y1108202I-1298J1D01*
G01X1361798Y1108115D01*
X1362605Y1106718D01*
X1362695Y1106701D01*
G02X1363750Y1105426I-243J-1275D01*
G02X1361156I-1297J0D01*
G02X1361228Y1105855I1297J3D01*
G01X1361259Y1105941D01*
X1360452Y1107338D01*
X1360362Y1107355D01*
G02X1359306Y1108630I242J1275D01*
G37*
G36*
G01X1368004Y1109928D02*
G02X1369043Y1109408I0J-1298D01*
G01X1370665D01*
G02X1371704Y1109928I1039J-778D01*
G02Y1107332I0J-1298D01*
G02X1370665Y1107852I0J1298D01*
G01X1369043D01*
G02X1368004Y1107332I-1039J778D01*
G02Y1109928I0J1298D01*
G37*
G36*
G01X1374106Y1108630D02*
G02X1376702I1298J0D01*
G02X1375646Y1107355I-1298J0D01*
G01X1375556Y1107338D01*
X1374748Y1105939D01*
X1374778Y1105853D01*
G02X1374850Y1105428I-1225J-426D01*
G01Y1105426D01*
G02X1372256I-1297J0D01*
G02X1373313Y1106701I1297J0D01*
G01X1373403Y1106718D01*
X1374210Y1108115D01*
X1374179Y1108202D01*
G02X1374106Y1108630I1225J429D01*
G37*
G36*
G01X1385206D02*
G02X1387802I1298J0D01*
G02X1386746Y1107355I-1298J0D01*
G01X1386656Y1107338D01*
X1385848Y1105939D01*
X1385878Y1105853D01*
G02X1385950Y1105428I-1225J-426D01*
G01Y1105426D01*
G02X1383356I-1297J0D01*
G02X1384413Y1106701I1297J0D01*
G01X1384503Y1106718D01*
X1385310Y1108115D01*
X1385279Y1108202D01*
G02X1385206Y1108630I1225J429D01*
G37*
G36*
G01X366514Y1111834D02*
G02X369110I1298J0D01*
G02X369037Y1111406I-1298J1D01*
G01X369006Y1111319D01*
X369813Y1109922D01*
X369903Y1109905D01*
G02X370958Y1108630I-243J-1275D01*
G02X368364I-1297J0D01*
G02X368436Y1109059I1297J3D01*
G01X368467Y1109145D01*
X367660Y1110542D01*
X367570Y1110559D01*
G02X366514Y1111834I242J1275D01*
G37*
G36*
G01X373914D02*
G02X376508I1297J0D01*
G02X376436Y1111406I-1297J-2D01*
G01X376405Y1111319D01*
X377212Y1109922D01*
X377302Y1109905D01*
G02X378360Y1108630I-239J-1275D01*
G02X375764I-1298J0D01*
G02X375837Y1109057I1298J-2D01*
G01X375867Y1109143D01*
X375059Y1110542D01*
X374969Y1110559D01*
G02X373914Y1111834I243J1275D01*
G37*
G36*
G01X382611Y1113132D02*
G02X383650Y1112612I0J-1298D01*
G01X385272D01*
G02X386311Y1113132I1039J-778D01*
G02Y1110536I0J-1298D01*
G02X385272Y1111056I0J1298D01*
G01X383650D01*
G02X382611Y1110536I-1039J778D01*
G02Y1113132I0J1298D01*
G37*
G36*
G01X399814Y1111834D02*
G02X402408I1297J0D01*
G02X402336Y1111406I-1297J-2D01*
G01X402305Y1111319D01*
X403112Y1109922D01*
X403202Y1109905D01*
G02X404260Y1108630I-239J-1275D01*
G02X401664I-1298J0D01*
G02X401737Y1109057I1298J-2D01*
G01X401767Y1109143D01*
X400959Y1110542D01*
X400869Y1110559D01*
G02X399814Y1111834I243J1275D01*
G37*
G36*
G01X408511Y1113132D02*
G02X409550Y1112612I0J-1298D01*
G01X411172D01*
G02X412211Y1113132I1039J-778D01*
G02Y1110536I0J-1298D01*
G02X411172Y1111056I0J1298D01*
G01X409550D01*
G02X408511Y1110536I-1039J778D01*
G02Y1113132I0J1298D01*
G37*
G36*
G01X418314Y1111834D02*
G02X420908I1297J0D01*
G02X419853Y1110559I-1298J0D01*
G01X419763Y1110542D01*
X418956Y1109145D01*
X418987Y1109059D01*
G02X419060Y1108630I-1224J-429D01*
G02X416464I-1298J0D01*
G02X417520Y1109905I1298J0D01*
G01X417610Y1109922D01*
X418417Y1111319D01*
X418386Y1111406D01*
G02X418314Y1111834I1225J426D01*
G37*
G36*
G01X1342656D02*
G02X1345252I1298J0D01*
G02X1345179Y1111406I-1298J1D01*
G01X1345148Y1111319D01*
X1345955Y1109922D01*
X1346045Y1109905D01*
G02X1347100Y1108630I-243J-1275D01*
G02X1344506I-1297J0D01*
G02X1344578Y1109059I1297J3D01*
G01X1344609Y1109145D01*
X1343802Y1110542D01*
X1343712Y1110559D01*
G02X1342656Y1111834I242J1275D01*
G37*
G36*
G01X1350056D02*
G02X1352650I1297J0D01*
G02X1352578Y1111406I-1297J-2D01*
G01X1352547Y1111319D01*
X1353354Y1109922D01*
X1353444Y1109905D01*
G02X1354502Y1108630I-239J-1275D01*
G02X1351906I-1298J0D01*
G02X1351979Y1109057I1298J-2D01*
G01X1352009Y1109143D01*
X1351201Y1110542D01*
X1351111Y1110559D01*
G02X1350056Y1111834I243J1275D01*
G37*
G36*
G01X1358753Y1113132D02*
G02X1359792Y1112612I0J-1298D01*
G01X1361414D01*
G02X1362453Y1113132I1039J-778D01*
G02Y1110536I0J-1298D01*
G02X1361414Y1111056I0J1298D01*
G01X1359792D01*
G02X1358753Y1110536I-1039J778D01*
G02Y1113132I0J1298D01*
G37*
G36*
G01X1375956Y1111834D02*
G02X1378550I1297J0D01*
G02X1378478Y1111406I-1297J-2D01*
G01X1378447Y1111319D01*
X1379254Y1109922D01*
X1379344Y1109905D01*
G02X1380402Y1108630I-239J-1275D01*
G02X1377806I-1298J0D01*
G02X1377879Y1109057I1298J-2D01*
G01X1377909Y1109143D01*
X1377101Y1110542D01*
X1377011Y1110559D01*
G02X1375956Y1111834I243J1275D01*
G37*
G36*
G01X1384653Y1113132D02*
G02X1385692Y1112612I0J-1298D01*
G01X1387314D01*
G02X1388353Y1113132I1039J-778D01*
G02Y1110536I0J-1298D01*
G02X1387314Y1111056I0J1298D01*
G01X1385692D01*
G02X1384653Y1110536I-1039J778D01*
G02Y1113132I0J1298D01*
G37*
G36*
G01X1394456Y1111834D02*
G02X1397050I1297J0D01*
G02X1395995Y1110559I-1298J0D01*
G01X1395905Y1110542D01*
X1395098Y1109145D01*
X1395129Y1109059D01*
G02X1395202Y1108630I-1224J-429D01*
G02X1392606I-1298J0D01*
G02X1393662Y1109905I1298J0D01*
G01X1393752Y1109922D01*
X1394559Y1111319D01*
X1394528Y1111406D01*
G02X1394456Y1111834I1225J426D01*
G37*
G36*
G01X346164Y1115039D02*
G02X348758I1297J0D01*
G02X347703Y1113764I-1298J0D01*
G01X347613Y1113747D01*
X346805Y1112349D01*
X346836Y1112262D01*
G02X346908Y1111834I-1225J-426D01*
G02X344314I-1297J0D01*
G02X345369Y1113109I1298J0D01*
G01X345459Y1113126D01*
X346267Y1114524D01*
X346236Y1114611D01*
G02X346164Y1115039I1225J426D01*
G37*
G36*
G01X365961Y1116336D02*
G02X367000Y1115816I0J-1298D01*
G01X368622D01*
G02X369661Y1116336I1039J-778D01*
G02Y1113742I0J-1297D01*
G02X368622Y1114262I0J1298D01*
G01X367000D01*
G02X365961Y1113742I-1039J778D01*
G02Y1116336I0J1297D01*
G37*
G36*
G01X379464Y1115039D02*
G02X382060I1298J0D01*
G02X381004Y1113764I-1298J0D01*
G01X380914Y1113747D01*
X380106Y1112348D01*
X380136Y1112261D01*
G02X380208Y1111836I-1225J-426D01*
G01Y1111834D01*
G02X377614I-1297J0D01*
G02X378670Y1113109I1298J0D01*
G01X378761Y1113126D01*
X379568Y1114524D01*
X379537Y1114611D01*
G02X379464Y1115039I1225J429D01*
G37*
G36*
G01X390564D02*
G02X393160I1298J0D01*
G02X393087Y1114611I-1298J1D01*
G01X393056Y1114524D01*
X393864Y1113126D01*
X393954Y1113109D01*
G02X395008Y1111834I-244J-1275D01*
G02X392414I-1297J0D01*
G02X392487Y1112263I1297J0D01*
G01X392517Y1112350D01*
X391710Y1113747D01*
X391620Y1113764D01*
G02X390564Y1115039I242J1275D01*
G37*
G36*
G01X399262Y1116336D02*
G02X400301Y1115816I0J-1298D01*
G01X401923D01*
G02X402962Y1116336I1039J-778D01*
G02Y1113742I0J-1297D01*
G02X401923Y1114262I0J1298D01*
G01X400301D01*
G02X399262Y1113742I-1039J778D01*
G02Y1116336I0J1297D01*
G37*
G36*
G01X412764Y1115039D02*
G02X415360I1298J0D01*
G02X415287Y1114611I-1298J1D01*
G01X415256Y1114524D01*
X416064Y1113126D01*
X416154Y1113109D01*
G02X417208Y1111834I-244J-1275D01*
G02X414614I-1297J0D01*
G02X414687Y1112263I1297J0D01*
G01X414717Y1112350D01*
X413910Y1113747D01*
X413820Y1113764D01*
G02X412764Y1115039I242J1275D01*
G37*
G36*
G01X1322306D02*
G02X1324900I1297J0D01*
G02X1323845Y1113764I-1298J0D01*
G01X1323755Y1113747D01*
X1322947Y1112349D01*
X1322978Y1112262D01*
G02X1323050Y1111834I-1225J-426D01*
G02X1320456I-1297J0D01*
G02X1321511Y1113109I1298J0D01*
G01X1321601Y1113126D01*
X1322409Y1114524D01*
X1322378Y1114611D01*
G02X1322306Y1115039I1225J426D01*
G37*
G36*
G01X1342103Y1116336D02*
G02X1343142Y1115816I0J-1298D01*
G01X1344764D01*
G02X1345803Y1116336I1039J-778D01*
G02Y1113742I0J-1297D01*
G02X1344764Y1114262I0J1298D01*
G01X1343142D01*
G02X1342103Y1113742I-1039J778D01*
G02Y1116336I0J1297D01*
G37*
G36*
G01X1355606Y1115039D02*
G02X1358202I1298J0D01*
G02X1357146Y1113764I-1298J0D01*
G01X1357056Y1113747D01*
X1356248Y1112348D01*
X1356278Y1112261D01*
G02X1356350Y1111836I-1225J-426D01*
G01Y1111834D01*
G02X1353756I-1297J0D01*
G02X1354812Y1113109I1298J0D01*
G01X1354903Y1113126D01*
X1355710Y1114524D01*
X1355679Y1114611D01*
G02X1355606Y1115039I1225J429D01*
G37*
G36*
G01X1366706D02*
G02X1369302I1298J0D01*
G02X1369229Y1114611I-1298J1D01*
G01X1369198Y1114524D01*
X1370006Y1113126D01*
X1370096Y1113109D01*
G02X1371150Y1111834I-244J-1275D01*
G02X1368556I-1297J0D01*
G02X1368629Y1112263I1297J0D01*
G01X1368659Y1112350D01*
X1367852Y1113747D01*
X1367762Y1113764D01*
G02X1366706Y1115039I242J1275D01*
G37*
G36*
G01X1375404Y1116336D02*
G02X1376443Y1115816I0J-1298D01*
G01X1378065D01*
G02X1379104Y1116336I1039J-778D01*
G02Y1113742I0J-1297D01*
G02X1378065Y1114262I0J1298D01*
G01X1376443D01*
G02X1375404Y1113742I-1039J778D01*
G02Y1116336I0J1297D01*
G37*
G36*
G01X1388906Y1115039D02*
G02X1391502I1298J0D01*
G02X1391429Y1114611I-1298J1D01*
G01X1391398Y1114524D01*
X1392206Y1113126D01*
X1392296Y1113109D01*
G02X1393350Y1111834I-244J-1275D01*
G02X1390756I-1297J0D01*
G02X1390829Y1112263I1297J0D01*
G01X1390859Y1112350D01*
X1390052Y1113747D01*
X1389962Y1113764D01*
G02X1388906Y1115039I242J1275D01*
G37*
G36*
G01X342464Y1121447D02*
G02X345058I1297J0D01*
G02X344003Y1120172I-1298J0D01*
G01X343913Y1120155D01*
X343106Y1118758D01*
X343137Y1118671D01*
G02X343210Y1118243I-1225J-429D01*
G02X340614I-1298J0D01*
G02X341670Y1119518I1298J0D01*
G01X341760Y1119535D01*
X342567Y1120932D01*
X342536Y1121019D01*
G02X342464Y1121447I1225J426D01*
G37*
G36*
G01X1318606D02*
G02X1321200I1297J0D01*
G02X1320145Y1120172I-1298J0D01*
G01X1320055Y1120155D01*
X1319248Y1118758D01*
X1319279Y1118671D01*
G02X1319352Y1118243I-1225J-429D01*
G02X1316756I-1298J0D01*
G02X1317812Y1119518I1298J0D01*
G01X1317902Y1119535D01*
X1318709Y1120932D01*
X1318678Y1121019D01*
G02X1318606Y1121447I1225J426D01*
G37*
G36*
G01X355414Y1124651D02*
G02X358010I1298J0D01*
G02X357937Y1124223I-1298J1D01*
G01X357906Y1124136D01*
X358713Y1122739D01*
X358803Y1122722D01*
G02X359858Y1121447I-243J-1275D01*
G02X357264I-1297J0D01*
G02X357336Y1121876I1297J3D01*
G01X357367Y1121962D01*
X356560Y1123359D01*
X356470Y1123376D01*
G02X355414Y1124651I242J1275D01*
G37*
G36*
G01X362814D02*
G02X365408I1297J0D01*
G02X365336Y1124223I-1297J-2D01*
G01X365305Y1124136D01*
X366112Y1122739D01*
X366202Y1122722D01*
G02X367260Y1121447I-239J-1275D01*
G02X364664I-1298J0D01*
G02X364737Y1121874I1298J-2D01*
G01X364767Y1121960D01*
X363959Y1123359D01*
X363869Y1123376D01*
G02X362814Y1124651I243J1275D01*
G37*
G36*
G01X370214D02*
G02X372808I1297J0D01*
G02X372736Y1124223I-1297J-2D01*
G01X372705Y1124136D01*
X373512Y1122739D01*
X373602Y1122722D01*
G02X374660Y1121447I-239J-1275D01*
G02X372064I-1298J0D01*
G02X372137Y1121874I1298J-2D01*
G01X372167Y1121960D01*
X371359Y1123359D01*
X371269Y1123376D01*
G02X370214Y1124651I243J1275D01*
G37*
G36*
G01X377614D02*
G02X380208I1297J0D01*
G02X380136Y1124223I-1297J-2D01*
G01X380105Y1124136D01*
X380912Y1122739D01*
X381002Y1122722D01*
G02X382060Y1121447I-239J-1275D01*
G02X379464I-1298J0D01*
G02X379537Y1121874I1298J-2D01*
G01X379567Y1121960D01*
X378759Y1123359D01*
X378669Y1123376D01*
G02X377614Y1124651I243J1275D01*
G37*
G36*
G01X385014D02*
G02X387608I1297J0D01*
G02X387536Y1124223I-1297J-2D01*
G01X387505Y1124136D01*
X388312Y1122739D01*
X388402Y1122722D01*
G02X389460Y1121447I-239J-1275D01*
G02X386864I-1298J0D01*
G02X386937Y1121874I1298J-2D01*
G01X386967Y1121960D01*
X386159Y1123359D01*
X386069Y1123376D01*
G02X385014Y1124651I243J1275D01*
G37*
G36*
G01X392414D02*
G02X395008I1297J0D01*
G02X394936Y1124223I-1297J-2D01*
G01X394905Y1124136D01*
X395712Y1122739D01*
X395802Y1122722D01*
G02X396860Y1121447I-239J-1275D01*
G02X394264I-1298J0D01*
G02X394337Y1121874I1298J-2D01*
G01X394367Y1121960D01*
X393559Y1123359D01*
X393469Y1123376D01*
G02X392414Y1124651I243J1275D01*
G37*
G36*
G01X399814D02*
G02X402408I1297J0D01*
G02X402336Y1124223I-1297J-2D01*
G01X402305Y1124136D01*
X403112Y1122739D01*
X403202Y1122722D01*
G02X404260Y1121447I-239J-1275D01*
G02X401664I-1298J0D01*
G02X401737Y1121874I1298J-2D01*
G01X401767Y1121960D01*
X400959Y1123359D01*
X400869Y1123376D01*
G02X399814Y1124651I243J1275D01*
G37*
G36*
G01X407214D02*
G02X409808I1297J0D01*
G02X409736Y1124223I-1297J-2D01*
G01X409705Y1124136D01*
X410512Y1122739D01*
X410602Y1122722D01*
G02X411660Y1121447I-239J-1275D01*
G02X409064I-1298J0D01*
G02X409137Y1121874I1298J-2D01*
G01X409167Y1121960D01*
X408359Y1123359D01*
X408269Y1123376D01*
G02X407214Y1124651I243J1275D01*
G37*
G36*
G01X470114D02*
G02X472708I1297J0D01*
G02X471653Y1123376I-1298J0D01*
G01X471563Y1123359D01*
X470756Y1121962D01*
X470787Y1121875D01*
G02X470860Y1121447I-1225J-429D01*
G02X468264I-1298J0D01*
G02X469320Y1122722I1298J0D01*
G01X469410Y1122739D01*
X470217Y1124136D01*
X470186Y1124223D01*
G02X470114Y1124651I1225J426D01*
G37*
G36*
G01X477514D02*
G02X480108I1297J0D01*
G02X479053Y1123376I-1298J0D01*
G01X478963Y1123359D01*
X478156Y1121962D01*
X478187Y1121875D01*
G02X478260Y1121447I-1225J-429D01*
G02X475664I-1298J0D01*
G02X476720Y1122722I1298J0D01*
G01X476810Y1122739D01*
X477617Y1124136D01*
X477586Y1124223D01*
G02X477514Y1124651I1225J426D01*
G37*
G36*
G01X484914D02*
G02X487508I1297J0D01*
G02X486453Y1123376I-1298J0D01*
G01X486363Y1123359D01*
X485556Y1121962D01*
X485587Y1121875D01*
G02X485660Y1121447I-1225J-429D01*
G02X483064I-1298J0D01*
G02X484120Y1122722I1298J0D01*
G01X484210Y1122739D01*
X485017Y1124136D01*
X484986Y1124223D01*
G02X484914Y1124651I1225J426D01*
G37*
G36*
G01X492314D02*
G02X494908I1297J0D01*
G02X493853Y1123376I-1298J0D01*
G01X493763Y1123359D01*
X492956Y1121962D01*
X492987Y1121875D01*
G02X493060Y1121447I-1225J-429D01*
G02X490464I-1298J0D01*
G02X491520Y1122722I1298J0D01*
G01X491610Y1122739D01*
X492417Y1124136D01*
X492386Y1124223D01*
G02X492314Y1124651I1225J426D01*
G37*
G36*
G01X499714D02*
G02X502308I1297J0D01*
G02X501253Y1123376I-1298J0D01*
G01X501163Y1123359D01*
X500356Y1121962D01*
X500387Y1121875D01*
G02X500460Y1121447I-1225J-429D01*
G02X497864I-1298J0D01*
G02X498920Y1122722I1298J0D01*
G01X499010Y1122739D01*
X499817Y1124136D01*
X499786Y1124223D01*
G02X499714Y1124651I1225J426D01*
G37*
G36*
G01X507114D02*
G02X509708I1297J0D01*
G02X508653Y1123376I-1298J0D01*
G01X508563Y1123359D01*
X507756Y1121962D01*
X507787Y1121875D01*
G02X507860Y1121447I-1225J-429D01*
G02X505264I-1298J0D01*
G02X506320Y1122722I1298J0D01*
G01X506410Y1122739D01*
X507217Y1124136D01*
X507186Y1124223D01*
G02X507114Y1124651I1225J426D01*
G37*
G36*
G01X514514D02*
G02X517108I1297J0D01*
G02X516053Y1123376I-1298J0D01*
G01X515963Y1123359D01*
X515156Y1121962D01*
X515187Y1121875D01*
G02X515260Y1121447I-1225J-429D01*
G02X512664I-1298J0D01*
G02X513720Y1122722I1298J0D01*
G01X513810Y1122739D01*
X514617Y1124136D01*
X514586Y1124223D01*
G02X514514Y1124651I1225J426D01*
G37*
G36*
G01X521914D02*
G02X524508I1297J0D01*
G02X523453Y1123376I-1298J0D01*
G01X523363Y1123359D01*
X522556Y1121962D01*
X522587Y1121875D01*
G02X522660Y1121447I-1225J-429D01*
G02X520064I-1298J0D01*
G02X521120Y1122722I1298J0D01*
G01X521210Y1122739D01*
X522017Y1124136D01*
X521986Y1124223D01*
G02X521914Y1124651I1225J426D01*
G37*
G36*
G01X1331556D02*
G02X1334152I1298J0D01*
G02X1334079Y1124223I-1298J1D01*
G01X1334048Y1124136D01*
X1334855Y1122739D01*
X1334945Y1122722D01*
G02X1336000Y1121447I-243J-1275D01*
G02X1333406I-1297J0D01*
G02X1333478Y1121876I1297J3D01*
G01X1333509Y1121962D01*
X1332702Y1123359D01*
X1332612Y1123376D01*
G02X1331556Y1124651I242J1275D01*
G37*
G36*
G01X1338956D02*
G02X1341550I1297J0D01*
G02X1341478Y1124223I-1297J-2D01*
G01X1341447Y1124136D01*
X1342254Y1122739D01*
X1342344Y1122722D01*
G02X1343402Y1121447I-239J-1275D01*
G02X1340806I-1298J0D01*
G02X1340879Y1121874I1298J-2D01*
G01X1340909Y1121960D01*
X1340101Y1123359D01*
X1340011Y1123376D01*
G02X1338956Y1124651I243J1275D01*
G37*
G36*
G01X1346356D02*
G02X1348950I1297J0D01*
G02X1348878Y1124223I-1297J-2D01*
G01X1348847Y1124136D01*
X1349654Y1122739D01*
X1349744Y1122722D01*
G02X1350802Y1121447I-239J-1275D01*
G02X1348206I-1298J0D01*
G02X1348279Y1121874I1298J-2D01*
G01X1348309Y1121960D01*
X1347501Y1123359D01*
X1347411Y1123376D01*
G02X1346356Y1124651I243J1275D01*
G37*
G36*
G01X1353756D02*
G02X1356350I1297J0D01*
G02X1356278Y1124223I-1297J-2D01*
G01X1356247Y1124136D01*
X1357054Y1122739D01*
X1357144Y1122722D01*
G02X1358202Y1121447I-239J-1275D01*
G02X1355606I-1298J0D01*
G02X1355679Y1121874I1298J-2D01*
G01X1355709Y1121960D01*
X1354901Y1123359D01*
X1354811Y1123376D01*
G02X1353756Y1124651I243J1275D01*
G37*
G36*
G01X1361156D02*
G02X1363750I1297J0D01*
G02X1363678Y1124223I-1297J-2D01*
G01X1363647Y1124136D01*
X1364454Y1122739D01*
X1364544Y1122722D01*
G02X1365602Y1121447I-239J-1275D01*
G02X1363006I-1298J0D01*
G02X1363079Y1121874I1298J-2D01*
G01X1363109Y1121960D01*
X1362301Y1123359D01*
X1362211Y1123376D01*
G02X1361156Y1124651I243J1275D01*
G37*
G36*
G01X1368556D02*
G02X1371150I1297J0D01*
G02X1371078Y1124223I-1297J-2D01*
G01X1371047Y1124136D01*
X1371854Y1122739D01*
X1371944Y1122722D01*
G02X1373002Y1121447I-239J-1275D01*
G02X1370406I-1298J0D01*
G02X1370479Y1121874I1298J-2D01*
G01X1370509Y1121960D01*
X1369701Y1123359D01*
X1369611Y1123376D01*
G02X1368556Y1124651I243J1275D01*
G37*
G36*
G01X1375956D02*
G02X1378550I1297J0D01*
G02X1378478Y1124223I-1297J-2D01*
G01X1378447Y1124136D01*
X1379254Y1122739D01*
X1379344Y1122722D01*
G02X1380402Y1121447I-239J-1275D01*
G02X1377806I-1298J0D01*
G02X1377879Y1121874I1298J-2D01*
G01X1377909Y1121960D01*
X1377101Y1123359D01*
X1377011Y1123376D01*
G02X1375956Y1124651I243J1275D01*
G37*
G36*
G01X1383356D02*
G02X1385950I1297J0D01*
G02X1385878Y1124223I-1297J-2D01*
G01X1385847Y1124136D01*
X1386654Y1122739D01*
X1386744Y1122722D01*
G02X1387802Y1121447I-239J-1275D01*
G02X1385206I-1298J0D01*
G02X1385279Y1121874I1298J-2D01*
G01X1385309Y1121960D01*
X1384501Y1123359D01*
X1384411Y1123376D01*
G02X1383356Y1124651I243J1275D01*
G37*
G36*
G01X1446256D02*
G02X1448850I1297J0D01*
G02X1447795Y1123376I-1298J0D01*
G01X1447705Y1123359D01*
X1446898Y1121962D01*
X1446929Y1121875D01*
G02X1447002Y1121447I-1225J-429D01*
G02X1444406I-1298J0D01*
G02X1445462Y1122722I1298J0D01*
G01X1445552Y1122739D01*
X1446359Y1124136D01*
X1446328Y1124223D01*
G02X1446256Y1124651I1225J426D01*
G37*
G36*
G01X1453656D02*
G02X1456250I1297J0D01*
G02X1455195Y1123376I-1298J0D01*
G01X1455105Y1123359D01*
X1454298Y1121962D01*
X1454329Y1121875D01*
G02X1454402Y1121447I-1225J-429D01*
G02X1451806I-1298J0D01*
G02X1452862Y1122722I1298J0D01*
G01X1452952Y1122739D01*
X1453759Y1124136D01*
X1453728Y1124223D01*
G02X1453656Y1124651I1225J426D01*
G37*
G36*
G01X1461056D02*
G02X1463650I1297J0D01*
G02X1462595Y1123376I-1298J0D01*
G01X1462505Y1123359D01*
X1461698Y1121962D01*
X1461729Y1121875D01*
G02X1461802Y1121447I-1225J-429D01*
G02X1459206I-1298J0D01*
G02X1460262Y1122722I1298J0D01*
G01X1460352Y1122739D01*
X1461159Y1124136D01*
X1461128Y1124223D01*
G02X1461056Y1124651I1225J426D01*
G37*
G36*
G01X1468456D02*
G02X1471050I1297J0D01*
G02X1469995Y1123376I-1298J0D01*
G01X1469905Y1123359D01*
X1469098Y1121962D01*
X1469129Y1121875D01*
G02X1469202Y1121447I-1225J-429D01*
G02X1466606I-1298J0D01*
G02X1467662Y1122722I1298J0D01*
G01X1467752Y1122739D01*
X1468559Y1124136D01*
X1468528Y1124223D01*
G02X1468456Y1124651I1225J426D01*
G37*
G36*
G01X1475856D02*
G02X1478450I1297J0D01*
G02X1477395Y1123376I-1298J0D01*
G01X1477305Y1123359D01*
X1476498Y1121962D01*
X1476529Y1121875D01*
G02X1476602Y1121447I-1225J-429D01*
G02X1474006I-1298J0D01*
G02X1475062Y1122722I1298J0D01*
G01X1475152Y1122739D01*
X1475959Y1124136D01*
X1475928Y1124223D01*
G02X1475856Y1124651I1225J426D01*
G37*
G36*
G01X1483256D02*
G02X1485850I1297J0D01*
G02X1484795Y1123376I-1298J0D01*
G01X1484705Y1123359D01*
X1483898Y1121962D01*
X1483929Y1121875D01*
G02X1484002Y1121447I-1225J-429D01*
G02X1481406I-1298J0D01*
G02X1482462Y1122722I1298J0D01*
G01X1482552Y1122739D01*
X1483359Y1124136D01*
X1483328Y1124223D01*
G02X1483256Y1124651I1225J426D01*
G37*
G36*
G01X1490656D02*
G02X1493250I1297J0D01*
G02X1492195Y1123376I-1298J0D01*
G01X1492105Y1123359D01*
X1491298Y1121962D01*
X1491329Y1121875D01*
G02X1491402Y1121447I-1225J-429D01*
G02X1488806I-1298J0D01*
G02X1489862Y1122722I1298J0D01*
G01X1489952Y1122739D01*
X1490759Y1124136D01*
X1490728Y1124223D01*
G02X1490656Y1124651I1225J426D01*
G37*
G36*
G01X1498056D02*
G02X1500650I1297J0D01*
G02X1499595Y1123376I-1298J0D01*
G01X1499505Y1123359D01*
X1498698Y1121962D01*
X1498729Y1121875D01*
G02X1498802Y1121447I-1225J-429D01*
G02X1496206I-1298J0D01*
G02X1497262Y1122722I1298J0D01*
G01X1497352Y1122739D01*
X1498159Y1124136D01*
X1498128Y1124223D01*
G02X1498056Y1124651I1225J426D01*
G37*
G36*
G01X353564Y1127856D02*
G02X356158I1297J0D01*
G02X355103Y1126581I-1298J0D01*
G01X355013Y1126564D01*
X354205Y1125166D01*
X354236Y1125079D01*
G02X354308Y1124651I-1225J-426D01*
G02X351714I-1297J0D01*
G02X352769Y1125926I1298J0D01*
G01X352859Y1125943D01*
X353667Y1127341D01*
X353636Y1127428D01*
G02X353564Y1127856I1225J426D01*
G37*
G36*
G01X360964D02*
G02X363560I1298J0D01*
G02X362504Y1126581I-1298J0D01*
G01X362414Y1126564D01*
X361606Y1125166D01*
X361637Y1125079D01*
G02X361710Y1124651I-1225J-429D01*
G02X359114I-1298J0D01*
G02X360170Y1125926I1298J0D01*
G01X360260Y1125943D01*
X361068Y1127341D01*
X361037Y1127428D01*
G02X360964Y1127856I1225J429D01*
G37*
G36*
G01X368364D02*
G02X370960I1298J0D01*
G02X369904Y1126581I-1298J0D01*
G01X369814Y1126564D01*
X369006Y1125165D01*
X369036Y1125078D01*
G02X369108Y1124653I-1225J-426D01*
G01Y1124651D01*
G02X366514I-1297J0D01*
G02X367570Y1125926I1298J0D01*
G01X367661Y1125943D01*
X368468Y1127341D01*
X368437Y1127428D01*
G02X368364Y1127856I1225J429D01*
G37*
G36*
G01X375764D02*
G02X378360I1298J0D01*
G02X377304Y1126581I-1298J0D01*
G01X377214Y1126564D01*
X376406Y1125165D01*
X376436Y1125078D01*
G02X376508Y1124653I-1225J-426D01*
G01Y1124651D01*
G02X373914I-1297J0D01*
G02X374970Y1125926I1298J0D01*
G01X375061Y1125943D01*
X375868Y1127341D01*
X375837Y1127428D01*
G02X375764Y1127856I1225J429D01*
G37*
G36*
G01X383164D02*
G02X385760I1298J0D01*
G02X384704Y1126581I-1298J0D01*
G01X384614Y1126564D01*
X383806Y1125165D01*
X383836Y1125078D01*
G02X383908Y1124653I-1225J-426D01*
G01Y1124651D01*
G02X381314I-1297J0D01*
G02X382370Y1125926I1298J0D01*
G01X382461Y1125943D01*
X383268Y1127341D01*
X383237Y1127428D01*
G02X383164Y1127856I1225J429D01*
G37*
G36*
G01X390564D02*
G02X393160I1298J0D01*
G02X392104Y1126581I-1298J0D01*
G01X392014Y1126564D01*
X391206Y1125165D01*
X391236Y1125078D01*
G02X391308Y1124653I-1225J-426D01*
G01Y1124651D01*
G02X388714I-1297J0D01*
G02X389770Y1125926I1298J0D01*
G01X389861Y1125943D01*
X390668Y1127341D01*
X390637Y1127428D01*
G02X390564Y1127856I1225J429D01*
G37*
G36*
G01X397964D02*
G02X400560I1298J0D01*
G02X399504Y1126581I-1298J0D01*
G01X399414Y1126564D01*
X398606Y1125165D01*
X398636Y1125078D01*
G02X398708Y1124653I-1225J-426D01*
G01Y1124651D01*
G02X396114I-1297J0D01*
G02X397170Y1125926I1298J0D01*
G01X397261Y1125943D01*
X398068Y1127341D01*
X398037Y1127428D01*
G02X397964Y1127856I1225J429D01*
G37*
G36*
G01X405364D02*
G02X407960I1298J0D01*
G02X406904Y1126581I-1298J0D01*
G01X406814Y1126564D01*
X406006Y1125165D01*
X406036Y1125078D01*
G02X406108Y1124653I-1225J-426D01*
G01Y1124651D01*
G02X403514I-1297J0D01*
G02X404570Y1125926I1298J0D01*
G01X404661Y1125943D01*
X405468Y1127341D01*
X405437Y1127428D01*
G02X405364Y1127856I1225J429D01*
G37*
G36*
G01X471964D02*
G02X474560I1298J0D01*
G02X474487Y1127427I-1297J0D01*
G01X474456Y1127341D01*
X475263Y1125943D01*
X475353Y1125926D01*
G02X476408Y1124651I-243J-1275D01*
G02X473814I-1297J0D01*
G02X473886Y1125080I1297J3D01*
G01X473917Y1125166D01*
X473110Y1126564D01*
X473020Y1126581D01*
G02X471964Y1127856I242J1275D01*
G37*
G36*
G01X479364D02*
G02X481960I1298J0D01*
G02X481887Y1127427I-1297J0D01*
G01X481856Y1127341D01*
X482663Y1125943D01*
X482753Y1125926D01*
G02X483808Y1124651I-243J-1275D01*
G02X481214I-1297J0D01*
G02X481286Y1125080I1297J3D01*
G01X481317Y1125166D01*
X480510Y1126564D01*
X480420Y1126581D01*
G02X479364Y1127856I242J1275D01*
G37*
G36*
G01X486764D02*
G02X489360I1298J0D01*
G02X489287Y1127427I-1297J0D01*
G01X489256Y1127341D01*
X490063Y1125943D01*
X490153Y1125926D01*
G02X491208Y1124651I-243J-1275D01*
G02X488614I-1297J0D01*
G02X488686Y1125080I1297J3D01*
G01X488717Y1125166D01*
X487910Y1126564D01*
X487820Y1126581D01*
G02X486764Y1127856I242J1275D01*
G37*
G36*
G01X494164D02*
G02X496760I1298J0D01*
G02X496687Y1127427I-1297J0D01*
G01X496656Y1127341D01*
X497463Y1125943D01*
X497553Y1125926D01*
G02X498608Y1124651I-243J-1275D01*
G02X496014I-1297J0D01*
G02X496086Y1125080I1297J3D01*
G01X496117Y1125166D01*
X495310Y1126564D01*
X495220Y1126581D01*
G02X494164Y1127856I242J1275D01*
G37*
G36*
G01X501564D02*
G02X504160I1298J0D01*
G02X504087Y1127427I-1297J0D01*
G01X504056Y1127341D01*
X504863Y1125943D01*
X504953Y1125926D01*
G02X506008Y1124651I-243J-1275D01*
G02X503414I-1297J0D01*
G02X503486Y1125080I1297J3D01*
G01X503517Y1125166D01*
X502710Y1126564D01*
X502620Y1126581D01*
G02X501564Y1127856I242J1275D01*
G37*
G36*
G01X508964D02*
G02X511560I1298J0D01*
G02X511487Y1127427I-1297J0D01*
G01X511456Y1127341D01*
X512263Y1125943D01*
X512353Y1125926D01*
G02X513408Y1124651I-243J-1275D01*
G02X510814I-1297J0D01*
G02X510886Y1125080I1297J3D01*
G01X510917Y1125166D01*
X510110Y1126564D01*
X510020Y1126581D01*
G02X508964Y1127856I242J1275D01*
G37*
G36*
G01X516364D02*
G02X518960I1298J0D01*
G02X518887Y1127427I-1297J0D01*
G01X518856Y1127341D01*
X519663Y1125943D01*
X519753Y1125926D01*
G02X520808Y1124651I-243J-1275D01*
G02X518214I-1297J0D01*
G02X518286Y1125080I1297J3D01*
G01X518317Y1125166D01*
X517510Y1126564D01*
X517420Y1126581D01*
G02X516364Y1127856I242J1275D01*
G37*
G36*
G01X523764D02*
G02X526360I1298J0D01*
G02X526287Y1127427I-1297J0D01*
G01X526256Y1127341D01*
X527063Y1125943D01*
X527153Y1125926D01*
G02X528208Y1124651I-243J-1275D01*
G02X525614I-1297J0D01*
G02X525686Y1125080I1297J3D01*
G01X525717Y1125166D01*
X524910Y1126564D01*
X524820Y1126581D01*
G02X523764Y1127856I242J1275D01*
G37*
G36*
G01X1329706D02*
G02X1332300I1297J0D01*
G02X1331245Y1126581I-1298J0D01*
G01X1331155Y1126564D01*
X1330347Y1125166D01*
X1330378Y1125079D01*
G02X1330450Y1124651I-1225J-426D01*
G02X1327856I-1297J0D01*
G02X1328911Y1125926I1298J0D01*
G01X1329001Y1125943D01*
X1329809Y1127341D01*
X1329778Y1127428D01*
G02X1329706Y1127856I1225J426D01*
G37*
G36*
G01X1337106D02*
G02X1339702I1298J0D01*
G02X1338646Y1126581I-1298J0D01*
G01X1338556Y1126564D01*
X1337748Y1125166D01*
X1337779Y1125079D01*
G02X1337852Y1124651I-1225J-429D01*
G02X1335256I-1298J0D01*
G02X1336312Y1125926I1298J0D01*
G01X1336402Y1125943D01*
X1337210Y1127341D01*
X1337179Y1127428D01*
G02X1337106Y1127856I1225J429D01*
G37*
G36*
G01X1344506D02*
G02X1347102I1298J0D01*
G02X1346046Y1126581I-1298J0D01*
G01X1345956Y1126564D01*
X1345148Y1125165D01*
X1345178Y1125078D01*
G02X1345250Y1124653I-1225J-426D01*
G01Y1124651D01*
G02X1342656I-1297J0D01*
G02X1343712Y1125926I1298J0D01*
G01X1343803Y1125943D01*
X1344610Y1127341D01*
X1344579Y1127428D01*
G02X1344506Y1127856I1225J429D01*
G37*
G36*
G01X1351906D02*
G02X1354502I1298J0D01*
G02X1353446Y1126581I-1298J0D01*
G01X1353356Y1126564D01*
X1352548Y1125165D01*
X1352578Y1125078D01*
G02X1352650Y1124653I-1225J-426D01*
G01Y1124651D01*
G02X1350056I-1297J0D01*
G02X1351112Y1125926I1298J0D01*
G01X1351203Y1125943D01*
X1352010Y1127341D01*
X1351979Y1127428D01*
G02X1351906Y1127856I1225J429D01*
G37*
G36*
G01X1359306D02*
G02X1361902I1298J0D01*
G02X1360846Y1126581I-1298J0D01*
G01X1360756Y1126564D01*
X1359948Y1125165D01*
X1359978Y1125078D01*
G02X1360050Y1124653I-1225J-426D01*
G01Y1124651D01*
G02X1357456I-1297J0D01*
G02X1358512Y1125926I1298J0D01*
G01X1358603Y1125943D01*
X1359410Y1127341D01*
X1359379Y1127428D01*
G02X1359306Y1127856I1225J429D01*
G37*
G36*
G01X1366706D02*
G02X1369302I1298J0D01*
G02X1368246Y1126581I-1298J0D01*
G01X1368156Y1126564D01*
X1367348Y1125165D01*
X1367378Y1125078D01*
G02X1367450Y1124653I-1225J-426D01*
G01Y1124651D01*
G02X1364856I-1297J0D01*
G02X1365912Y1125926I1298J0D01*
G01X1366003Y1125943D01*
X1366810Y1127341D01*
X1366779Y1127428D01*
G02X1366706Y1127856I1225J429D01*
G37*
G36*
G01X1374106D02*
G02X1376702I1298J0D01*
G02X1375646Y1126581I-1298J0D01*
G01X1375556Y1126564D01*
X1374748Y1125165D01*
X1374778Y1125078D01*
G02X1374850Y1124653I-1225J-426D01*
G01Y1124651D01*
G02X1372256I-1297J0D01*
G02X1373312Y1125926I1298J0D01*
G01X1373403Y1125943D01*
X1374210Y1127341D01*
X1374179Y1127428D01*
G02X1374106Y1127856I1225J429D01*
G37*
G36*
G01X1381506D02*
G02X1384102I1298J0D01*
G02X1383046Y1126581I-1298J0D01*
G01X1382956Y1126564D01*
X1382148Y1125165D01*
X1382178Y1125078D01*
G02X1382250Y1124653I-1225J-426D01*
G01Y1124651D01*
G02X1379656I-1297J0D01*
G02X1380712Y1125926I1298J0D01*
G01X1380803Y1125943D01*
X1381610Y1127341D01*
X1381579Y1127428D01*
G02X1381506Y1127856I1225J429D01*
G37*
G36*
G01X1448106D02*
G02X1450702I1298J0D01*
G02X1450629Y1127427I-1297J0D01*
G01X1450598Y1127341D01*
X1451405Y1125943D01*
X1451495Y1125926D01*
G02X1452550Y1124651I-243J-1275D01*
G02X1449956I-1297J0D01*
G02X1450028Y1125080I1297J3D01*
G01X1450059Y1125166D01*
X1449252Y1126564D01*
X1449162Y1126581D01*
G02X1448106Y1127856I242J1275D01*
G37*
G36*
G01X1455506D02*
G02X1458102I1298J0D01*
G02X1458029Y1127427I-1297J0D01*
G01X1457998Y1127341D01*
X1458805Y1125943D01*
X1458895Y1125926D01*
G02X1459950Y1124651I-243J-1275D01*
G02X1457356I-1297J0D01*
G02X1457428Y1125080I1297J3D01*
G01X1457459Y1125166D01*
X1456652Y1126564D01*
X1456562Y1126581D01*
G02X1455506Y1127856I242J1275D01*
G37*
G36*
G01X1462906D02*
G02X1465502I1298J0D01*
G02X1465429Y1127427I-1297J0D01*
G01X1465398Y1127341D01*
X1466205Y1125943D01*
X1466295Y1125926D01*
G02X1467350Y1124651I-243J-1275D01*
G02X1464756I-1297J0D01*
G02X1464828Y1125080I1297J3D01*
G01X1464859Y1125166D01*
X1464052Y1126564D01*
X1463962Y1126581D01*
G02X1462906Y1127856I242J1275D01*
G37*
G36*
G01X1470306D02*
G02X1472902I1298J0D01*
G02X1472829Y1127427I-1297J0D01*
G01X1472798Y1127341D01*
X1473605Y1125943D01*
X1473695Y1125926D01*
G02X1474750Y1124651I-243J-1275D01*
G02X1472156I-1297J0D01*
G02X1472228Y1125080I1297J3D01*
G01X1472259Y1125166D01*
X1471452Y1126564D01*
X1471362Y1126581D01*
G02X1470306Y1127856I242J1275D01*
G37*
G36*
G01X1477706D02*
G02X1480302I1298J0D01*
G02X1480229Y1127427I-1297J0D01*
G01X1480198Y1127341D01*
X1481005Y1125943D01*
X1481095Y1125926D01*
G02X1482150Y1124651I-243J-1275D01*
G02X1479556I-1297J0D01*
G02X1479628Y1125080I1297J3D01*
G01X1479659Y1125166D01*
X1478852Y1126564D01*
X1478762Y1126581D01*
G02X1477706Y1127856I242J1275D01*
G37*
G36*
G01X1485106D02*
G02X1487702I1298J0D01*
G02X1487629Y1127427I-1297J0D01*
G01X1487598Y1127341D01*
X1488405Y1125943D01*
X1488495Y1125926D01*
G02X1489550Y1124651I-243J-1275D01*
G02X1486956I-1297J0D01*
G02X1487028Y1125080I1297J3D01*
G01X1487059Y1125166D01*
X1486252Y1126564D01*
X1486162Y1126581D01*
G02X1485106Y1127856I242J1275D01*
G37*
G36*
G01X1492506D02*
G02X1495102I1298J0D01*
G02X1495029Y1127427I-1297J0D01*
G01X1494998Y1127341D01*
X1495805Y1125943D01*
X1495895Y1125926D01*
G02X1496950Y1124651I-243J-1275D01*
G02X1494356I-1297J0D01*
G02X1494428Y1125080I1297J3D01*
G01X1494459Y1125166D01*
X1493652Y1126564D01*
X1493562Y1126581D01*
G02X1492506Y1127856I242J1275D01*
G37*
G36*
G01X1499906D02*
G02X1502502I1298J0D01*
G02X1502429Y1127427I-1297J0D01*
G01X1502398Y1127341D01*
X1503205Y1125943D01*
X1503295Y1125926D01*
G02X1504350Y1124651I-243J-1275D01*
G02X1501756I-1297J0D01*
G02X1501828Y1125080I1297J3D01*
G01X1501859Y1125166D01*
X1501052Y1126564D01*
X1500962Y1126581D01*
G02X1499906Y1127856I242J1275D01*
G37*
G36*
G01X340614Y1131060D02*
G02X343208I1297J0D01*
G02X342153Y1129785I-1298J0D01*
G01X342063Y1129768D01*
X341256Y1128370D01*
X341286Y1128284D01*
G02X341358Y1127856I-1225J-426D01*
G02X338764I-1297J0D01*
G02X339819Y1129131I1298J0D01*
G01X339909Y1129148D01*
X340716Y1130546D01*
X340686Y1130632D01*
G02X340614Y1131060I1225J426D01*
G37*
G36*
G01X1316756D02*
G02X1319350I1297J0D01*
G02X1318295Y1129785I-1298J0D01*
G01X1318205Y1129768D01*
X1317398Y1128370D01*
X1317428Y1128284D01*
G02X1317500Y1127856I-1225J-426D01*
G02X1314906I-1297J0D01*
G02X1315961Y1129131I1298J0D01*
G01X1316051Y1129148D01*
X1316858Y1130546D01*
X1316828Y1130632D01*
G02X1316756Y1131060I1225J426D01*
G37*
G36*
G01X348014Y1137469D02*
G02X350610I1298J0D01*
G02X350537Y1137040I-1297J0D01*
G01X350506Y1136954D01*
X351313Y1135556D01*
X351403Y1135539D01*
G02X352458Y1134264I-243J-1275D01*
G02X349864I-1297J0D01*
G02X349936Y1134693I1297J3D01*
G01X349967Y1134779D01*
X349160Y1136177D01*
X349070Y1136194D01*
G02X348014Y1137469I242J1275D01*
G37*
G36*
G01X355414D02*
G02X358010I1298J0D01*
G02X357937Y1137040I-1297J0D01*
G01X357906Y1136954D01*
X358713Y1135556D01*
X358803Y1135539D01*
G02X359858Y1134264I-243J-1275D01*
G02X357264I-1297J0D01*
G02X357336Y1134693I1297J3D01*
G01X357367Y1134779D01*
X356560Y1136177D01*
X356470Y1136194D01*
G02X355414Y1137469I242J1275D01*
G37*
G36*
G01X362814D02*
G02X365410I1298J0D01*
G02X365337Y1137041I-1298J1D01*
G01X365306Y1136954D01*
X366114Y1135556D01*
X366204Y1135539D01*
G02X367260Y1134264I-242J-1275D01*
G02X364664I-1298J0D01*
G02X364737Y1134692I1298J-1D01*
G01X364768Y1134779D01*
X363960Y1136177D01*
X363870Y1136194D01*
G02X362814Y1137469I242J1275D01*
G37*
G36*
G01X370214D02*
G02X372810I1298J0D01*
G02X372737Y1137041I-1298J1D01*
G01X372706Y1136954D01*
X373514Y1135556D01*
X373604Y1135539D01*
G02X374660Y1134264I-242J-1275D01*
G02X372064I-1298J0D01*
G02X372137Y1134692I1298J-1D01*
G01X372168Y1134779D01*
X371360Y1136177D01*
X371270Y1136194D01*
G02X370214Y1137469I242J1275D01*
G37*
G36*
G01X377614D02*
G02X380210I1298J0D01*
G02X380137Y1137041I-1298J1D01*
G01X380106Y1136954D01*
X380914Y1135556D01*
X381004Y1135539D01*
G02X382060Y1134264I-242J-1275D01*
G02X379464I-1298J0D01*
G02X379537Y1134692I1298J-1D01*
G01X379568Y1134779D01*
X378760Y1136177D01*
X378670Y1136194D01*
G02X377614Y1137469I242J1275D01*
G37*
G36*
G01X385014D02*
G02X387610I1298J0D01*
G02X387537Y1137041I-1298J1D01*
G01X387506Y1136954D01*
X388314Y1135556D01*
X388404Y1135539D01*
G02X389460Y1134264I-242J-1275D01*
G02X386864I-1298J0D01*
G02X386937Y1134692I1298J-1D01*
G01X386968Y1134779D01*
X386160Y1136177D01*
X386070Y1136194D01*
G02X385014Y1137469I242J1275D01*
G37*
G36*
G01X392414D02*
G02X395010I1298J0D01*
G02X394937Y1137041I-1298J1D01*
G01X394906Y1136954D01*
X395714Y1135556D01*
X395804Y1135539D01*
G02X396860Y1134264I-242J-1275D01*
G02X394264I-1298J0D01*
G02X394337Y1134692I1298J-1D01*
G01X394368Y1134779D01*
X393560Y1136177D01*
X393470Y1136194D01*
G02X392414Y1137469I242J1275D01*
G37*
G36*
G01X399814D02*
G02X402410I1298J0D01*
G02X402337Y1137041I-1298J1D01*
G01X402306Y1136954D01*
X403114Y1135556D01*
X403204Y1135539D01*
G02X404260Y1134264I-242J-1275D01*
G02X401664I-1298J0D01*
G02X401737Y1134692I1298J-1D01*
G01X401768Y1134779D01*
X400960Y1136177D01*
X400870Y1136194D01*
G02X399814Y1137469I242J1275D01*
G37*
G36*
G01X407214D02*
G02X409810I1298J0D01*
G02X409737Y1137041I-1298J1D01*
G01X409706Y1136954D01*
X410514Y1135556D01*
X410604Y1135539D01*
G02X411660Y1134264I-242J-1275D01*
G02X409064I-1298J0D01*
G02X409137Y1134692I1298J-1D01*
G01X409168Y1134779D01*
X408360Y1136177D01*
X408270Y1136194D01*
G02X407214Y1137469I242J1275D01*
G37*
G36*
G01X477514D02*
G02X480110I1298J0D01*
G02X479054Y1136194I-1298J0D01*
G01X478964Y1136177D01*
X478156Y1134779D01*
X478187Y1134692D01*
G02X478260Y1134264I-1225J-429D01*
G02X475664I-1298J0D01*
G02X476720Y1135539I1298J0D01*
G01X476810Y1135556D01*
X477618Y1136954D01*
X477587Y1137041D01*
G02X477514Y1137469I1225J429D01*
G37*
G36*
G01X484914D02*
G02X487510I1298J0D01*
G02X486454Y1136194I-1298J0D01*
G01X486364Y1136177D01*
X485557Y1134779D01*
X485587Y1134692D01*
G02X485660Y1134264I-1225J-429D01*
G02X483064I-1298J0D01*
G02X484121Y1135539I1297J0D01*
G01X484211Y1135556D01*
X485018Y1136954D01*
X484987Y1137041D01*
G02X484914Y1137469I1225J429D01*
G37*
G36*
G01X492314D02*
G02X494910I1298J0D01*
G02X493854Y1136194I-1298J0D01*
G01X493764Y1136177D01*
X492957Y1134779D01*
X492987Y1134692D01*
G02X493060Y1134264I-1225J-429D01*
G02X490464I-1298J0D01*
G02X491521Y1135539I1297J0D01*
G01X491611Y1135556D01*
X492418Y1136954D01*
X492387Y1137041D01*
G02X492314Y1137469I1225J429D01*
G37*
G36*
G01X499714D02*
G02X502310I1298J0D01*
G02X501254Y1136194I-1298J0D01*
G01X501164Y1136177D01*
X500357Y1134779D01*
X500387Y1134692D01*
G02X500460Y1134264I-1225J-429D01*
G02X497864I-1298J0D01*
G02X498921Y1135539I1297J0D01*
G01X499011Y1135556D01*
X499818Y1136954D01*
X499787Y1137041D01*
G02X499714Y1137469I1225J429D01*
G37*
G36*
G01X507114D02*
G02X509710I1298J0D01*
G02X508654Y1136194I-1298J0D01*
G01X508564Y1136177D01*
X507757Y1134779D01*
X507787Y1134692D01*
G02X507860Y1134264I-1225J-429D01*
G02X505264I-1298J0D01*
G02X506321Y1135539I1297J0D01*
G01X506411Y1135556D01*
X507218Y1136954D01*
X507187Y1137041D01*
G02X507114Y1137469I1225J429D01*
G37*
G36*
G01X514514D02*
G02X517110I1298J0D01*
G02X516054Y1136194I-1298J0D01*
G01X515964Y1136177D01*
X515157Y1134779D01*
X515187Y1134692D01*
G02X515260Y1134264I-1225J-429D01*
G02X512664I-1298J0D01*
G02X513721Y1135539I1297J0D01*
G01X513811Y1135556D01*
X514618Y1136954D01*
X514587Y1137041D01*
G02X514514Y1137469I1225J429D01*
G37*
G36*
G01X521914D02*
G02X524510I1298J0D01*
G02X523454Y1136194I-1298J0D01*
G01X523364Y1136177D01*
X522557Y1134779D01*
X522587Y1134692D01*
G02X522660Y1134264I-1225J-429D01*
G02X520064I-1298J0D01*
G02X521121Y1135539I1297J0D01*
G01X521211Y1135556D01*
X522018Y1136954D01*
X521987Y1137041D01*
G02X521914Y1137469I1225J429D01*
G37*
G36*
G01X533014D02*
G02X535610I1298J0D01*
G02X534554Y1136194I-1298J0D01*
G01X534464Y1136177D01*
X533656Y1134779D01*
X533687Y1134692D01*
G02X533760Y1134264I-1225J-429D01*
G02X531164I-1298J0D01*
G02X532220Y1135539I1298J0D01*
G01X532310Y1135556D01*
X533118Y1136954D01*
X533087Y1137041D01*
G02X533014Y1137469I1225J429D01*
G37*
G36*
G01X1324156D02*
G02X1326752I1298J0D01*
G02X1326679Y1137040I-1297J0D01*
G01X1326648Y1136954D01*
X1327455Y1135556D01*
X1327545Y1135539D01*
G02X1328600Y1134264I-243J-1275D01*
G02X1326006I-1297J0D01*
G02X1326078Y1134693I1297J3D01*
G01X1326109Y1134779D01*
X1325302Y1136177D01*
X1325212Y1136194D01*
G02X1324156Y1137469I242J1275D01*
G37*
G36*
G01X1331556D02*
G02X1334152I1298J0D01*
G02X1334079Y1137040I-1297J0D01*
G01X1334048Y1136954D01*
X1334855Y1135556D01*
X1334945Y1135539D01*
G02X1336000Y1134264I-243J-1275D01*
G02X1333406I-1297J0D01*
G02X1333478Y1134693I1297J3D01*
G01X1333509Y1134779D01*
X1332702Y1136177D01*
X1332612Y1136194D01*
G02X1331556Y1137469I242J1275D01*
G37*
G36*
G01X1338956D02*
G02X1341552I1298J0D01*
G02X1341479Y1137041I-1298J1D01*
G01X1341448Y1136954D01*
X1342256Y1135556D01*
X1342346Y1135539D01*
G02X1343402Y1134264I-242J-1275D01*
G02X1340806I-1298J0D01*
G02X1340879Y1134692I1298J-1D01*
G01X1340910Y1134779D01*
X1340102Y1136177D01*
X1340012Y1136194D01*
G02X1338956Y1137469I242J1275D01*
G37*
G36*
G01X1346356D02*
G02X1348952I1298J0D01*
G02X1348879Y1137041I-1298J1D01*
G01X1348848Y1136954D01*
X1349656Y1135556D01*
X1349746Y1135539D01*
G02X1350802Y1134264I-242J-1275D01*
G02X1348206I-1298J0D01*
G02X1348279Y1134692I1298J-1D01*
G01X1348310Y1134779D01*
X1347502Y1136177D01*
X1347412Y1136194D01*
G02X1346356Y1137469I242J1275D01*
G37*
G36*
G01X1353756D02*
G02X1356352I1298J0D01*
G02X1356279Y1137041I-1298J1D01*
G01X1356248Y1136954D01*
X1357056Y1135556D01*
X1357146Y1135539D01*
G02X1358202Y1134264I-242J-1275D01*
G02X1355606I-1298J0D01*
G02X1355679Y1134692I1298J-1D01*
G01X1355710Y1134779D01*
X1354902Y1136177D01*
X1354812Y1136194D01*
G02X1353756Y1137469I242J1275D01*
G37*
G36*
G01X1361156D02*
G02X1363752I1298J0D01*
G02X1363679Y1137041I-1298J1D01*
G01X1363648Y1136954D01*
X1364456Y1135556D01*
X1364546Y1135539D01*
G02X1365602Y1134264I-242J-1275D01*
G02X1363006I-1298J0D01*
G02X1363079Y1134692I1298J-1D01*
G01X1363110Y1134779D01*
X1362302Y1136177D01*
X1362212Y1136194D01*
G02X1361156Y1137469I242J1275D01*
G37*
G36*
G01X1368556D02*
G02X1371152I1298J0D01*
G02X1371079Y1137041I-1298J1D01*
G01X1371048Y1136954D01*
X1371856Y1135556D01*
X1371946Y1135539D01*
G02X1373002Y1134264I-242J-1275D01*
G02X1370406I-1298J0D01*
G02X1370479Y1134692I1298J-1D01*
G01X1370510Y1134779D01*
X1369702Y1136177D01*
X1369612Y1136194D01*
G02X1368556Y1137469I242J1275D01*
G37*
G36*
G01X1375956D02*
G02X1378552I1298J0D01*
G02X1378479Y1137041I-1298J1D01*
G01X1378448Y1136954D01*
X1379256Y1135556D01*
X1379346Y1135539D01*
G02X1380402Y1134264I-242J-1275D01*
G02X1377806I-1298J0D01*
G02X1377879Y1134692I1298J-1D01*
G01X1377910Y1134779D01*
X1377102Y1136177D01*
X1377012Y1136194D01*
G02X1375956Y1137469I242J1275D01*
G37*
G36*
G01X1383356D02*
G02X1385952I1298J0D01*
G02X1385879Y1137041I-1298J1D01*
G01X1385848Y1136954D01*
X1386656Y1135556D01*
X1386746Y1135539D01*
G02X1387802Y1134264I-242J-1275D01*
G02X1385206I-1298J0D01*
G02X1385279Y1134692I1298J-1D01*
G01X1385310Y1134779D01*
X1384502Y1136177D01*
X1384412Y1136194D01*
G02X1383356Y1137469I242J1275D01*
G37*
G36*
G01X1453656D02*
G02X1456252I1298J0D01*
G02X1455196Y1136194I-1298J0D01*
G01X1455106Y1136177D01*
X1454298Y1134779D01*
X1454329Y1134692D01*
G02X1454402Y1134264I-1225J-429D01*
G02X1451806I-1298J0D01*
G02X1452862Y1135539I1298J0D01*
G01X1452952Y1135556D01*
X1453760Y1136954D01*
X1453729Y1137041D01*
G02X1453656Y1137469I1225J429D01*
G37*
G36*
G01X1461056D02*
G02X1463652I1298J0D01*
G02X1462596Y1136194I-1298J0D01*
G01X1462506Y1136177D01*
X1461699Y1134779D01*
X1461729Y1134692D01*
G02X1461802Y1134264I-1225J-429D01*
G02X1459206I-1298J0D01*
G02X1460263Y1135539I1297J0D01*
G01X1460353Y1135556D01*
X1461160Y1136954D01*
X1461129Y1137041D01*
G02X1461056Y1137469I1225J429D01*
G37*
G36*
G01X1468456D02*
G02X1471052I1298J0D01*
G02X1469996Y1136194I-1298J0D01*
G01X1469906Y1136177D01*
X1469099Y1134779D01*
X1469129Y1134692D01*
G02X1469202Y1134264I-1225J-429D01*
G02X1466606I-1298J0D01*
G02X1467663Y1135539I1297J0D01*
G01X1467753Y1135556D01*
X1468560Y1136954D01*
X1468529Y1137041D01*
G02X1468456Y1137469I1225J429D01*
G37*
G36*
G01X1475856D02*
G02X1478452I1298J0D01*
G02X1477396Y1136194I-1298J0D01*
G01X1477306Y1136177D01*
X1476499Y1134779D01*
X1476529Y1134692D01*
G02X1476602Y1134264I-1225J-429D01*
G02X1474006I-1298J0D01*
G02X1475063Y1135539I1297J0D01*
G01X1475153Y1135556D01*
X1475960Y1136954D01*
X1475929Y1137041D01*
G02X1475856Y1137469I1225J429D01*
G37*
G36*
G01X1483256D02*
G02X1485852I1298J0D01*
G02X1484796Y1136194I-1298J0D01*
G01X1484706Y1136177D01*
X1483899Y1134779D01*
X1483929Y1134692D01*
G02X1484002Y1134264I-1225J-429D01*
G02X1481406I-1298J0D01*
G02X1482463Y1135539I1297J0D01*
G01X1482553Y1135556D01*
X1483360Y1136954D01*
X1483329Y1137041D01*
G02X1483256Y1137469I1225J429D01*
G37*
G36*
G01X1490656D02*
G02X1493252I1298J0D01*
G02X1492196Y1136194I-1298J0D01*
G01X1492106Y1136177D01*
X1491299Y1134779D01*
X1491329Y1134692D01*
G02X1491402Y1134264I-1225J-429D01*
G02X1488806I-1298J0D01*
G02X1489863Y1135539I1297J0D01*
G01X1489953Y1135556D01*
X1490760Y1136954D01*
X1490729Y1137041D01*
G02X1490656Y1137469I1225J429D01*
G37*
G36*
G01X1498056D02*
G02X1500652I1298J0D01*
G02X1499596Y1136194I-1298J0D01*
G01X1499506Y1136177D01*
X1498699Y1134779D01*
X1498729Y1134692D01*
G02X1498802Y1134264I-1225J-429D01*
G02X1496206I-1298J0D01*
G02X1497263Y1135539I1297J0D01*
G01X1497353Y1135556D01*
X1498160Y1136954D01*
X1498129Y1137041D01*
G02X1498056Y1137469I1225J429D01*
G37*
G36*
G01X1509156D02*
G02X1511752I1298J0D01*
G02X1510696Y1136194I-1298J0D01*
G01X1510606Y1136177D01*
X1509798Y1134779D01*
X1509829Y1134692D01*
G02X1509902Y1134264I-1225J-429D01*
G02X1507306I-1298J0D01*
G02X1508362Y1135539I1298J0D01*
G01X1508452Y1135556D01*
X1509260Y1136954D01*
X1509229Y1137041D01*
G02X1509156Y1137469I1225J429D01*
G37*
G36*
G01X360964Y1140973D02*
G02X363558I1297J0D01*
G02X362496Y1139697I-1298J0D01*
G01X362401Y1139679D01*
X361559Y1138084D01*
X361598Y1137995D01*
G02X361710Y1137469I-1186J-527D01*
G02X359114I-1298J0D01*
G02X360177Y1138745I1297J0D01*
G01X360272Y1138763D01*
X361114Y1140358D01*
X361075Y1140447D01*
G02X360964Y1140971I1186J525D01*
G01Y1140973D01*
G37*
G36*
G01X368364D02*
G02X370958I1297J0D01*
G02X369896Y1139697I-1298J0D01*
G01X369801Y1139679D01*
X368959Y1138084D01*
X368998Y1137995D01*
G02X369110Y1137469I-1186J-527D01*
G02X366514I-1298J0D01*
G02X367577Y1138745I1297J0D01*
G01X367672Y1138763D01*
X368514Y1140358D01*
X368475Y1140447D01*
G02X368364Y1140971I1186J525D01*
G01Y1140973D01*
G37*
G36*
G01X375764D02*
G02X378358I1297J0D01*
G02X377296Y1139697I-1298J0D01*
G01X377201Y1139679D01*
X376359Y1138084D01*
X376398Y1137995D01*
G02X376510Y1137469I-1186J-527D01*
G02X373914I-1298J0D01*
G02X374977Y1138745I1297J0D01*
G01X375072Y1138763D01*
X375914Y1140358D01*
X375875Y1140447D01*
G02X375764Y1140971I1186J525D01*
G01Y1140973D01*
G37*
G36*
G01X383164D02*
G02X385758I1297J0D01*
G02X384696Y1139697I-1298J0D01*
G01X384601Y1139679D01*
X383759Y1138084D01*
X383798Y1137995D01*
G02X383910Y1137469I-1186J-527D01*
G02X381314I-1298J0D01*
G02X382377Y1138745I1297J0D01*
G01X382472Y1138763D01*
X383314Y1140358D01*
X383275Y1140447D01*
G02X383164Y1140971I1186J525D01*
G01Y1140973D01*
G37*
G36*
G01X390564D02*
G02X393158I1297J0D01*
G02X392096Y1139697I-1298J0D01*
G01X392001Y1139679D01*
X391159Y1138084D01*
X391198Y1137995D01*
G02X391310Y1137469I-1186J-527D01*
G02X388714I-1298J0D01*
G02X389777Y1138745I1297J0D01*
G01X389872Y1138763D01*
X390714Y1140358D01*
X390675Y1140447D01*
G02X390564Y1140971I1186J525D01*
G01Y1140973D01*
G37*
G36*
G01X397964D02*
G02X400558I1297J0D01*
G02X399496Y1139697I-1298J0D01*
G01X399401Y1139679D01*
X398559Y1138084D01*
X398598Y1137995D01*
G02X398710Y1137469I-1186J-527D01*
G02X396114I-1298J0D01*
G02X397177Y1138745I1297J0D01*
G01X397272Y1138763D01*
X398114Y1140358D01*
X398075Y1140447D01*
G02X397964Y1140971I1186J525D01*
G01Y1140973D01*
G37*
G36*
G01X405364D02*
G02X407958I1297J0D01*
G02X406896Y1139697I-1298J0D01*
G01X406801Y1139679D01*
X405959Y1138084D01*
X405998Y1137995D01*
G02X406110Y1137469I-1186J-527D01*
G02X403514I-1298J0D01*
G02X404577Y1138745I1297J0D01*
G01X404672Y1138763D01*
X405514Y1140358D01*
X405475Y1140447D01*
G02X405364Y1140971I1186J525D01*
G01Y1140973D01*
G37*
G36*
G01X471964D02*
G02X474558I1297J0D01*
G02X474447Y1140448I-1297J0D01*
G01X474408Y1140359D01*
X475252Y1138763D01*
X475347Y1138745D01*
G02X476410Y1137469I-234J-1276D01*
G02X473814I-1298J0D01*
G02X473926Y1137994I1297J-2D01*
G01X473965Y1138083D01*
X473121Y1139679D01*
X473026Y1139697D01*
G02X471964Y1140973I236J1276D01*
G37*
G36*
G01X479364D02*
G02X481958I1297J0D01*
G02X481847Y1140448I-1297J0D01*
G01X481808Y1140359D01*
X482652Y1138763D01*
X482747Y1138745D01*
G02X483810Y1137469I-234J-1276D01*
G02X481214I-1298J0D01*
G02X481326Y1137994I1297J-2D01*
G01X481365Y1138083D01*
X480521Y1139679D01*
X480426Y1139697D01*
G02X479364Y1140973I236J1276D01*
G37*
G36*
G01X486764D02*
G02X489358I1297J0D01*
G02X489247Y1140448I-1297J0D01*
G01X489208Y1140359D01*
X490052Y1138763D01*
X490147Y1138745D01*
G02X491210Y1137469I-234J-1276D01*
G02X488614I-1298J0D01*
G02X488726Y1137994I1297J-2D01*
G01X488765Y1138083D01*
X487921Y1139679D01*
X487826Y1139697D01*
G02X486764Y1140973I236J1276D01*
G37*
G36*
G01X494164D02*
G02X496758I1297J0D01*
G02X496647Y1140448I-1297J0D01*
G01X496608Y1140359D01*
X497452Y1138763D01*
X497547Y1138745D01*
G02X498610Y1137469I-234J-1276D01*
G02X496014I-1298J0D01*
G02X496126Y1137994I1297J-2D01*
G01X496165Y1138083D01*
X495321Y1139679D01*
X495226Y1139697D01*
G02X494164Y1140973I236J1276D01*
G37*
G36*
G01X501564D02*
G02X504158I1297J0D01*
G02X504047Y1140448I-1297J0D01*
G01X504008Y1140359D01*
X504852Y1138763D01*
X504947Y1138745D01*
G02X506010Y1137469I-234J-1276D01*
G02X503414I-1298J0D01*
G02X503526Y1137994I1297J-2D01*
G01X503565Y1138083D01*
X502721Y1139679D01*
X502626Y1139697D01*
G02X501564Y1140973I236J1276D01*
G37*
G36*
G01X508964D02*
G02X511558I1297J0D01*
G02X511447Y1140448I-1297J0D01*
G01X511408Y1140359D01*
X512252Y1138763D01*
X512347Y1138745D01*
G02X513410Y1137469I-234J-1276D01*
G02X510814I-1298J0D01*
G02X510926Y1137994I1297J-2D01*
G01X510965Y1138083D01*
X510121Y1139679D01*
X510026Y1139697D01*
G02X508964Y1140973I236J1276D01*
G37*
G36*
G01X516364D02*
G02X518958I1297J0D01*
G02X518847Y1140448I-1297J0D01*
G01X518808Y1140359D01*
X519652Y1138763D01*
X519747Y1138745D01*
G02X520810Y1137469I-234J-1276D01*
G02X518214I-1298J0D01*
G02X518326Y1137994I1297J-2D01*
G01X518365Y1138083D01*
X517521Y1139679D01*
X517426Y1139697D01*
G02X516364Y1140973I236J1276D01*
G37*
G36*
G01X523764D02*
G02X526358I1297J0D01*
G02X526247Y1140448I-1297J0D01*
G01X526208Y1140359D01*
X527052Y1138763D01*
X527147Y1138745D01*
G02X528210Y1137469I-234J-1276D01*
G02X525614I-1298J0D01*
G02X525726Y1137994I1297J-2D01*
G01X525765Y1138083D01*
X524921Y1139679D01*
X524826Y1139697D01*
G02X523764Y1140973I236J1276D01*
G37*
G36*
G01X1337106D02*
G02X1339700I1297J0D01*
G02X1338638Y1139697I-1298J0D01*
G01X1338543Y1139679D01*
X1337701Y1138084D01*
X1337740Y1137995D01*
G02X1337852Y1137469I-1186J-527D01*
G02X1335256I-1298J0D01*
G02X1336319Y1138745I1297J0D01*
G01X1336414Y1138763D01*
X1337256Y1140358D01*
X1337217Y1140447D01*
G02X1337106Y1140971I1186J525D01*
G01Y1140973D01*
G37*
G36*
G01X1344506D02*
G02X1347100I1297J0D01*
G02X1346038Y1139697I-1298J0D01*
G01X1345943Y1139679D01*
X1345101Y1138084D01*
X1345140Y1137995D01*
G02X1345252Y1137469I-1186J-527D01*
G02X1342656I-1298J0D01*
G02X1343719Y1138745I1297J0D01*
G01X1343814Y1138763D01*
X1344656Y1140358D01*
X1344617Y1140447D01*
G02X1344506Y1140971I1186J525D01*
G01Y1140973D01*
G37*
G36*
G01X1351906D02*
G02X1354500I1297J0D01*
G02X1353438Y1139697I-1298J0D01*
G01X1353343Y1139679D01*
X1352501Y1138084D01*
X1352540Y1137995D01*
G02X1352652Y1137469I-1186J-527D01*
G02X1350056I-1298J0D01*
G02X1351119Y1138745I1297J0D01*
G01X1351214Y1138763D01*
X1352056Y1140358D01*
X1352017Y1140447D01*
G02X1351906Y1140971I1186J525D01*
G01Y1140973D01*
G37*
G36*
G01X1359306D02*
G02X1361900I1297J0D01*
G02X1360838Y1139697I-1298J0D01*
G01X1360743Y1139679D01*
X1359901Y1138084D01*
X1359940Y1137995D01*
G02X1360052Y1137469I-1186J-527D01*
G02X1357456I-1298J0D01*
G02X1358519Y1138745I1297J0D01*
G01X1358614Y1138763D01*
X1359456Y1140358D01*
X1359417Y1140447D01*
G02X1359306Y1140971I1186J525D01*
G01Y1140973D01*
G37*
G36*
G01X1366706D02*
G02X1369300I1297J0D01*
G02X1368238Y1139697I-1298J0D01*
G01X1368143Y1139679D01*
X1367301Y1138084D01*
X1367340Y1137995D01*
G02X1367452Y1137469I-1186J-527D01*
G02X1364856I-1298J0D01*
G02X1365919Y1138745I1297J0D01*
G01X1366014Y1138763D01*
X1366856Y1140358D01*
X1366817Y1140447D01*
G02X1366706Y1140971I1186J525D01*
G01Y1140973D01*
G37*
G36*
G01X1374106D02*
G02X1376700I1297J0D01*
G02X1375638Y1139697I-1298J0D01*
G01X1375543Y1139679D01*
X1374701Y1138084D01*
X1374740Y1137995D01*
G02X1374852Y1137469I-1186J-527D01*
G02X1372256I-1298J0D01*
G02X1373319Y1138745I1297J0D01*
G01X1373414Y1138763D01*
X1374256Y1140358D01*
X1374217Y1140447D01*
G02X1374106Y1140971I1186J525D01*
G01Y1140973D01*
G37*
G36*
G01X1381506D02*
G02X1384100I1297J0D01*
G02X1383038Y1139697I-1298J0D01*
G01X1382943Y1139679D01*
X1382101Y1138084D01*
X1382140Y1137995D01*
G02X1382252Y1137469I-1186J-527D01*
G02X1379656I-1298J0D01*
G02X1380719Y1138745I1297J0D01*
G01X1380814Y1138763D01*
X1381656Y1140358D01*
X1381617Y1140447D01*
G02X1381506Y1140971I1186J525D01*
G01Y1140973D01*
G37*
G36*
G01X1448106D02*
G02X1450700I1297J0D01*
G02X1450589Y1140448I-1297J0D01*
G01X1450550Y1140359D01*
X1451394Y1138763D01*
X1451489Y1138745D01*
G02X1452552Y1137469I-234J-1276D01*
G02X1449956I-1298J0D01*
G02X1450068Y1137994I1297J-2D01*
G01X1450107Y1138083D01*
X1449263Y1139679D01*
X1449168Y1139697D01*
G02X1448106Y1140973I236J1276D01*
G37*
G36*
G01X1455506D02*
G02X1458100I1297J0D01*
G02X1457989Y1140448I-1297J0D01*
G01X1457950Y1140359D01*
X1458794Y1138763D01*
X1458889Y1138745D01*
G02X1459952Y1137469I-234J-1276D01*
G02X1457356I-1298J0D01*
G02X1457468Y1137994I1297J-2D01*
G01X1457507Y1138083D01*
X1456663Y1139679D01*
X1456568Y1139697D01*
G02X1455506Y1140973I236J1276D01*
G37*
G36*
G01X1462906D02*
G02X1465500I1297J0D01*
G02X1465389Y1140448I-1297J0D01*
G01X1465350Y1140359D01*
X1466194Y1138763D01*
X1466289Y1138745D01*
G02X1467352Y1137469I-234J-1276D01*
G02X1464756I-1298J0D01*
G02X1464868Y1137994I1297J-2D01*
G01X1464907Y1138083D01*
X1464063Y1139679D01*
X1463968Y1139697D01*
G02X1462906Y1140973I236J1276D01*
G37*
G36*
G01X1470306D02*
G02X1472900I1297J0D01*
G02X1472789Y1140448I-1297J0D01*
G01X1472750Y1140359D01*
X1473594Y1138763D01*
X1473689Y1138745D01*
G02X1474752Y1137469I-234J-1276D01*
G02X1472156I-1298J0D01*
G02X1472268Y1137994I1297J-2D01*
G01X1472307Y1138083D01*
X1471463Y1139679D01*
X1471368Y1139697D01*
G02X1470306Y1140973I236J1276D01*
G37*
G36*
G01X1477706D02*
G02X1480300I1297J0D01*
G02X1480189Y1140448I-1297J0D01*
G01X1480150Y1140359D01*
X1480994Y1138763D01*
X1481089Y1138745D01*
G02X1482152Y1137469I-234J-1276D01*
G02X1479556I-1298J0D01*
G02X1479668Y1137994I1297J-2D01*
G01X1479707Y1138083D01*
X1478863Y1139679D01*
X1478768Y1139697D01*
G02X1477706Y1140973I236J1276D01*
G37*
G36*
G01X1485106D02*
G02X1487700I1297J0D01*
G02X1487589Y1140448I-1297J0D01*
G01X1487550Y1140359D01*
X1488394Y1138763D01*
X1488489Y1138745D01*
G02X1489552Y1137469I-234J-1276D01*
G02X1486956I-1298J0D01*
G02X1487068Y1137994I1297J-2D01*
G01X1487107Y1138083D01*
X1486263Y1139679D01*
X1486168Y1139697D01*
G02X1485106Y1140973I236J1276D01*
G37*
G36*
G01X1492506D02*
G02X1495100I1297J0D01*
G02X1494989Y1140448I-1297J0D01*
G01X1494950Y1140359D01*
X1495794Y1138763D01*
X1495889Y1138745D01*
G02X1496952Y1137469I-234J-1276D01*
G02X1494356I-1298J0D01*
G02X1494468Y1137994I1297J-2D01*
G01X1494507Y1138083D01*
X1493663Y1139679D01*
X1493568Y1139697D01*
G02X1492506Y1140973I236J1276D01*
G37*
G36*
G01X1499906D02*
G02X1502500I1297J0D01*
G02X1502389Y1140448I-1297J0D01*
G01X1502350Y1140359D01*
X1503194Y1138763D01*
X1503289Y1138745D01*
G02X1504352Y1137469I-234J-1276D01*
G02X1501756I-1298J0D01*
G02X1501868Y1137994I1297J-2D01*
G01X1501907Y1138083D01*
X1501063Y1139679D01*
X1500968Y1139697D01*
G02X1499906Y1140973I236J1276D01*
G37*
G36*
G01X1143020Y1540382D02*
G03X1143411Y1540758I-8J400D01*
G02X1145410Y1542642I1999J-119D01*
G02X1147412Y1540640I0J-2002D01*
G02X1145450Y1538638I-2002J0D01*
G03X1145059Y1538262I8J-400D01*
G02X1143060Y1536378I-1999J119D01*
G02X1141058Y1538380I0J2002D01*
G02X1143020Y1540382I2002J0D01*
G37*
G36*
G01X1162980Y1551449D02*
G03X1163635I328J229D01*
G02X1166917I1641J-1147D01*
G03X1167572I327J229D01*
G02X1169213Y1552304I1641J-1147D01*
G02Y1548298I0J-2003D01*
G02X1167572Y1549153I0J2002D01*
G03X1166917I-328J-229D01*
G02X1163635I-1641J1147D01*
G03X1162980I-327J-229D01*
G02X1159698I-1641J1147D01*
G03X1159043I-328J-229D01*
G02X1155761I-1641J1147D01*
G03X1155106I-328J-229D01*
G02X1151824I-1641J1147D01*
G03X1151169I-328J-229D01*
G02X1149528Y1548298I-1641J1147D01*
G02Y1552304I0J2003D01*
G02X1151169Y1551449I0J-2002D01*
G03X1151824I327J229D01*
G02X1155106I1641J-1147D01*
G03X1155761I328J229D01*
G02X1159043I1641J-1147D01*
G03X1159698I327J229D01*
G02X1162980I1641J-1147D01*
G37*
G36*
G01X1139652Y1550301D02*
Y1550302D01*
G02X1140157Y1551631I2002J0D01*
G02X1139688Y1552918I1533J1288D01*
G01Y1552920D01*
G02X1143692I2002J0D01*
G01Y1552919D01*
G02X1143187Y1551590I-2002J0D01*
G02X1143656Y1550303I-1533J-1288D01*
G01Y1550301D01*
G02X1139652I-2002J0D01*
G37*
G36*
G01X1101405Y1550386D02*
G03X1101083Y1550900I-382J119D01*
G02X1098098Y1554364I517J3464D01*
G02X1105102I3502J0D01*
G02X1104945Y1553324I-3502J-3D01*
G03X1105267Y1552810I382J-119D01*
G02X1108252Y1549346I-517J-3464D01*
G02X1101248I-3502J0D01*
G02X1101405Y1550386I3502J3D01*
G37*
G36*
G01X1143823Y1573272D02*
G03X1143551I-136J-147D01*
G02X1142188Y1572736I-1363J1466D01*
G01X1142187D01*
G02Y1576740I0J2002D01*
G01X1142188D01*
G02X1143551Y1576204I0J-2002D01*
G03X1143823I136J147D01*
G02X1145186Y1576740I1363J-1466D01*
G01X1145187D01*
G02Y1572736I0J-2002D01*
G01X1145186D01*
G02X1143823Y1573272I0J2002D01*
G37*
G36*
G01X1153823D02*
G03X1153551I-136J-147D01*
G02X1152188Y1572736I-1363J1466D01*
G01X1152187D01*
G02Y1576740I0J2002D01*
G01X1152188D01*
G02X1153551Y1576204I0J-2002D01*
G03X1153823I136J147D01*
G02X1155186Y1576740I1363J-1466D01*
G01X1155187D01*
G02Y1572736I0J-2002D01*
G01X1155186D01*
G02X1153823Y1573272I0J2002D01*
G37*
G36*
G01X1163231D02*
G03X1162959I-136J-147D01*
G02X1161596Y1572736I-1363J1466D01*
G01X1161595D01*
G02Y1576740I0J2002D01*
G01X1161596D01*
G02X1162959Y1576204I0J-2002D01*
G03X1163231I136J147D01*
G02X1164594Y1576740I1363J-1466D01*
G01X1164595D01*
G02Y1572736I0J-2002D01*
G01X1164594D01*
G02X1163231Y1573272I0J2002D01*
G37*
G36*
G01X1173231D02*
G03X1172959I-136J-147D01*
G02X1171596Y1572736I-1363J1466D01*
G01X1171595D01*
G02Y1576740I0J2002D01*
G01X1171596D01*
G02X1172959Y1576204I0J-2002D01*
G03X1173231I136J147D01*
G02X1174594Y1576740I1363J-1466D01*
G01X1174595D01*
G02Y1572736I0J-2002D01*
G01X1174594D01*
G02X1173231Y1573272I0J2002D01*
G37*
G36*
G01X1133823Y1581272D02*
G03X1133551I-136J-147D01*
G02X1132188Y1580736I-1363J1466D01*
G01X1132187D01*
G02Y1584740I0J2002D01*
G01X1132188D01*
G02X1133551Y1584204I0J-2002D01*
G03X1133823I136J147D01*
G02X1135186Y1584740I1363J-1466D01*
G01X1135187D01*
G02Y1580736I0J-2002D01*
G01X1135186D01*
G02X1133823Y1581272I0J2002D01*
G37*
G36*
G01X1143823D02*
G03X1143551I-136J-147D01*
G02X1142188Y1580736I-1363J1466D01*
G01X1142187D01*
G02Y1584740I0J2002D01*
G01X1142188D01*
G02X1143551Y1584204I0J-2002D01*
G03X1143823I136J147D01*
G02X1145186Y1584740I1363J-1466D01*
G01X1145187D01*
G02Y1580736I0J-2002D01*
G01X1145186D01*
G02X1143823Y1581272I0J2002D01*
G37*
G36*
G01X1153823D02*
G03X1153551I-136J-147D01*
G02X1152188Y1580736I-1363J1466D01*
G01X1152187D01*
G02Y1584740I0J2002D01*
G01X1152188D01*
G02X1153551Y1584204I0J-2002D01*
G03X1153823I136J147D01*
G02X1155186Y1584740I1363J-1466D01*
G01X1155187D01*
G02Y1580736I0J-2002D01*
G01X1155186D01*
G02X1153823Y1581272I0J2002D01*
G37*
G36*
G01X1163231D02*
G03X1162959I-136J-147D01*
G02X1161596Y1580736I-1363J1466D01*
G01X1161595D01*
G02Y1584740I0J2002D01*
G01X1161596D01*
G02X1162959Y1584204I0J-2002D01*
G03X1163231I136J147D01*
G02X1164594Y1584740I1363J-1466D01*
G01X1164595D01*
G02Y1580736I0J-2002D01*
G01X1164594D01*
G02X1163231Y1581272I0J2002D01*
G37*
G36*
G01X1173231D02*
G03X1172959I-136J-147D01*
G02X1171596Y1580736I-1363J1466D01*
G01X1171595D01*
G02Y1584740I0J2002D01*
G01X1171596D01*
G02X1172959Y1584204I0J-2002D01*
G03X1173231I136J147D01*
G02X1174594Y1584740I1363J-1466D01*
G01X1174595D01*
G02Y1580736I0J-2002D01*
G01X1174594D01*
G02X1173231Y1581272I0J2002D01*
G37*
G36*
G01X1133823Y1589272D02*
G03X1133551I-136J-147D01*
G02X1132188Y1588736I-1363J1466D01*
G01X1132187D01*
G02Y1592740I0J2002D01*
G01X1132188D01*
G02X1133551Y1592204I0J-2002D01*
G03X1133823I136J147D01*
G02X1135186Y1592740I1363J-1466D01*
G01X1135187D01*
G02Y1588736I0J-2002D01*
G01X1135186D01*
G02X1133823Y1589272I0J2002D01*
G37*
G36*
G01X1143823D02*
G03X1143551I-136J-147D01*
G02X1142188Y1588736I-1363J1466D01*
G01X1142187D01*
G02Y1592740I0J2002D01*
G01X1142188D01*
G02X1143551Y1592204I0J-2002D01*
G03X1143823I136J147D01*
G02X1145186Y1592740I1363J-1466D01*
G01X1145187D01*
G02Y1588736I0J-2002D01*
G01X1145186D01*
G02X1143823Y1589272I0J2002D01*
G37*
G36*
G01X1153823D02*
G03X1153551I-136J-147D01*
G02X1152188Y1588736I-1363J1466D01*
G01X1152187D01*
G02Y1592740I0J2002D01*
G01X1152188D01*
G02X1153551Y1592204I0J-2002D01*
G03X1153823I136J147D01*
G02X1155186Y1592740I1363J-1466D01*
G01X1155187D01*
G02Y1588736I0J-2002D01*
G01X1155186D01*
G02X1153823Y1589272I0J2002D01*
G37*
G36*
G01X1163231D02*
G03X1162959I-136J-147D01*
G02X1161596Y1588736I-1363J1466D01*
G01X1161595D01*
G02Y1592740I0J2002D01*
G01X1161596D01*
G02X1162959Y1592204I0J-2002D01*
G03X1163231I136J147D01*
G02X1164594Y1592740I1363J-1466D01*
G01X1164595D01*
G02Y1588736I0J-2002D01*
G01X1164594D01*
G02X1163231Y1589272I0J2002D01*
G37*
G36*
G01X1173231D02*
G03X1172959I-136J-147D01*
G02X1171596Y1588736I-1363J1466D01*
G01X1171595D01*
G02Y1592740I0J2002D01*
G01X1171596D01*
G02X1172959Y1592204I0J-2002D01*
G03X1173231I136J147D01*
G02X1174594Y1592740I1363J-1466D01*
G01X1174595D01*
G02Y1588736I0J-2002D01*
G01X1174594D01*
G02X1173231Y1589272I0J2002D01*
G37*
G36*
G01X810826Y1715542D02*
X816058Y1720774D01*
G02X816942Y1721140I884J-885D01*
G01X901218D01*
G02X902102Y1720774I0J-1251D01*
G01X909144Y1713732D01*
G02X909510Y1712848I-885J-884D01*
G01Y1667748D01*
X918748Y1658510D01*
X1064960D01*
G02X1065844Y1658144I0J-1251D01*
G01X1085888Y1638100D01*
X1102078D01*
G02X1102962Y1637734I0J-1251D01*
G01X1105274Y1635422D01*
G02X1105640Y1634538I-885J-884D01*
G01Y1606962D01*
G02X1105274Y1606078I-1251J0D01*
G01X1103642Y1604446D01*
G02X1102758Y1604080I-884J885D01*
G01X1081112D01*
X1080194Y1603162D01*
Y1602842D01*
X1081707Y1601328D01*
G02X1082362Y1600268I-1907J-1911D01*
G03X1083025Y1600111I380J126D01*
G01X1083178Y1600264D01*
G02X1084062Y1600630I884J-885D01*
G01X1095052D01*
G02X1095199Y1600621I-3J-1250D01*
G01X1095210Y1600620D01*
X1106448D01*
G02X1107332Y1600254I0J-1251D01*
G01X1108636Y1598950D01*
G02X1109002Y1598066I-885J-884D01*
G01Y1565342D01*
G02X1108636Y1564458I-1251J0D01*
G01X1106544Y1562366D01*
G02X1105660Y1562000I-884J885D01*
G01X1084682D01*
G02X1083798Y1562366I0J1251D01*
G01X1082380Y1563784D01*
G03X1081801Y1563770I-283J-283D01*
G02X1081707Y1563672I-1995J1819D01*
G01X1080842Y1562807D01*
X1080645Y1562602D01*
G02X1080216Y1562313I-898J870D01*
G01X1079671Y1562092D01*
G02X1079201Y1562000I-471J1158D01*
G01X945581D01*
G02X943672Y1562793I2J2700D01*
G01X941807Y1564658D01*
X941602Y1564855D01*
G02X941313Y1565284I870J898D01*
G01X941092Y1565829D01*
G02X941000Y1566299I1158J471D01*
G01Y1599900D01*
X940822Y1600078D01*
X940214D01*
X936892Y1596756D01*
G02X936008Y1596390I-884J885D01*
G01X927766D01*
X923290Y1591914D01*
Y1578352D01*
G02X922924Y1577468I-1251J0D01*
G01X922132Y1576676D01*
G02X921248Y1576310I-884J885D01*
G01X906872D01*
G02X905988Y1576676I0J1251D01*
G01X905196Y1577468D01*
G02X904830Y1578352I885J884D01*
G01Y1591896D01*
X904388Y1592338D01*
G02X904022Y1593222I885J884D01*
G01Y1603382D01*
X896864Y1610540D01*
X889128D01*
X882022Y1603434D01*
Y1593152D01*
G02X881656Y1592268I-1251J0D01*
G01X881310Y1591922D01*
Y1578402D01*
G02X880944Y1577518I-1251J0D01*
G01X880112Y1576686D01*
G02X879228Y1576320I-884J885D01*
G01X864892D01*
G02X864008Y1576686I0J1251D01*
G01X863206Y1577488D01*
G02X862840Y1578372I885J884D01*
G01Y1591966D01*
X862488Y1592318D01*
G02X862122Y1593202I885J884D01*
G01Y1602864D01*
X854886Y1610100D01*
X846166D01*
X839980Y1603914D01*
Y1593162D01*
G02X839614Y1592278I-1251J0D01*
G01X839280Y1591944D01*
Y1578322D01*
G02X838914Y1577438I-1251J0D01*
G01X838162Y1576686D01*
G02X837278Y1576320I-884J885D01*
G01X822872D01*
G02X821988Y1576686I0J1251D01*
G01X821236Y1577438D01*
G02X820870Y1578322I885J884D01*
G01Y1591816D01*
X820488Y1592198D01*
G02X820122Y1593082I885J884D01*
G01Y1603042D01*
X812654Y1610510D01*
X804298D01*
X798022Y1604234D01*
Y1593104D01*
G02X797656Y1592220I-1251J0D01*
G01X797290Y1591854D01*
Y1578352D01*
G02X796924Y1577468I-1251J0D01*
G01X796142Y1576686D01*
G02X795258Y1576320I-884J885D01*
G01X780872D01*
G02X779988Y1576686I0J1251D01*
G01X779236Y1577438D01*
G02X778870Y1578322I885J884D01*
G01Y1591954D01*
X774954Y1595870D01*
X751976D01*
X751087Y1594981D01*
X751101Y1594883D01*
G02X751114Y1594683I-1489J-197D01*
G02X749612Y1593181I-1502J0D01*
G02X749412Y1593194I-3J1502D01*
G01X749314Y1593208D01*
X748022Y1591915D01*
Y1590733D01*
G02X747656Y1589849I-1251J0D01*
G01X746824Y1589017D01*
G02X745940Y1588651I-884J885D01*
G01X745090D01*
Y1578308D01*
G02X744730Y1577431I-1250J1D01*
G01X743935Y1576624D01*
G02X743045Y1576251I-891J877D01*
G01X727872D01*
G02X726622Y1577501I0J1250D01*
G01Y1600869D01*
G02X726988Y1601753I1251J0D01*
G01X727560Y1602325D01*
X727554Y1602415D01*
G02X727550Y1602518I1498J110D01*
G02X727922Y1603507I1501J0D01*
G01Y1606915D01*
X727488Y1607349D01*
G02X727122Y1608233I885J884D01*
G01Y1626762D01*
G02X727488Y1627646I1251J0D01*
G01X757926Y1658084D01*
G02X758810Y1658450I884J-885D01*
G01X776714D01*
X810460Y1692196D01*
Y1714658D01*
G02X810826Y1715542I1251J0D01*
G37*
G36*
G01X1411037Y1711457D02*
G03X1411142Y1712134I-151J370D01*
G02X1421732I5295J6330D01*
G03X1421837Y1711457I256J-307D01*
G02X1430690Y1698267I-5399J-13190D01*
G02X1402184I-14253J0D01*
G02X1411037Y1711457I14252J0D01*
G37*
G36*
G01X435643Y1711458D02*
G03X435748Y1712135I-151J370D01*
G02X446338I5295J6330D01*
G03X446443Y1711458I256J-307D01*
G02X455296Y1698268I-5399J-13190D01*
G02X426790I-14253J0D01*
G02X435643Y1711458I14252J0D01*
G37*
G54D111*
X1137717Y1558020D03*
G54D105*
X1290005Y293768D03*
G54D114*
X136522Y1598410D03*
G54D100*
X1455787Y1421784D03*
X1710550Y691327D03*
X479646Y1421784D03*
X93547Y692260D03*
G54D112*
X659877Y188373D03*
X546110Y100647D03*
G54D115*
X136518Y1602410D03*
X733879Y83664D03*
X737929Y83714D03*
G54D109*
X1175215Y1532913D03*
X1131715D03*
G54D83*
X1307572Y-26511D03*
X1040152Y-16511D03*
X1015152D03*
X1307572Y13489D03*
X1282572Y23489D03*
X1307572D03*
X1282572Y13489D03*
X1040152Y23489D03*
Y13489D03*
X973180Y-6500D03*
X998180D03*
X1015152Y13489D03*
X1282572Y-16511D03*
X973180Y-26500D03*
X998180D03*
Y-16500D03*
X1015152Y23489D03*
X1307572Y-16511D03*
X973180Y-16500D03*
X1474931Y23489D03*
X1499931D03*
X705760Y-26500D03*
X730760D03*
X705760Y-6500D03*
Y-16500D03*
X730760D03*
Y-6500D03*
X1474931Y13489D03*
X998180Y3500D03*
X973180D03*
X1499931Y13489D03*
X998180Y13500D03*
Y23500D03*
X973180D03*
Y13500D03*
X1499931Y-16511D03*
X1474931D03*
X1324471Y23489D03*
X1349471D03*
X822720Y3500D03*
X847720D03*
X822720Y23500D03*
Y13500D03*
X847720D03*
Y23500D03*
X1324471Y-16511D03*
X1349471D03*
X1324471Y13489D03*
X1349471D03*
X1307572Y-36511D03*
X1282572D03*
Y-26511D03*
X1307572Y-6511D03*
Y3489D03*
X1282572D03*
Y-6511D03*
X1015152Y-36511D03*
Y-26511D03*
X1040152D03*
Y-36511D03*
X1015152Y3489D03*
Y-6511D03*
X1040152D03*
Y3489D03*
X1499931Y-26511D03*
Y-36511D03*
X1474931D03*
Y-26511D03*
X1499931Y-6511D03*
Y3489D03*
X1474931D03*
Y-6511D03*
X1324471Y-36511D03*
Y-26511D03*
X1349471D03*
Y-36511D03*
X1324471Y3489D03*
Y-6511D03*
X1349471D03*
Y3489D03*
G54D113*
X659872Y192372D03*
X548942Y97821D03*
G54D92*
X70472Y173228D03*
Y236220D03*
G54D96*
X1565236Y184783D03*
Y264035D03*
G54D106*
X553055Y109175D03*
Y114687D03*
X554629D03*
Y109175D03*
G54D97*
X929331Y160413D03*
X922441Y237697D03*
X1534712Y20354D03*
X1787330Y24291D03*
X505185Y41142D03*
X757803Y45079D03*
X312921Y24291D03*
G54D107*
X48325Y439450D03*
X46751Y444962D03*
X48325D03*
X46751Y439450D03*
G54D95*
X676508Y224606D03*
G54D94*
Y145866D03*
G54D89*
X1829725Y130315D03*
G54D85*
X791280Y1704890D03*
X1066280D03*
G54D103*
X1405118Y112008D03*
G54D82*
X1341752Y-21511D03*
Y-1511D03*
X1482650Y-21511D03*
Y-1511D03*
X90998Y1517237D03*
X78120Y1517136D03*
X99750Y1563678D03*
X75922Y1560674D03*
X404030Y1593690D03*
X957156Y228863D03*
X899830Y973184D03*
X1380522Y261936D03*
X1388754Y255503D03*
X1380638Y247394D03*
X1386630Y240351D03*
X397406Y1634842D03*
X1031950Y385471D03*
X736710Y605542D03*
X527310Y96447D03*
X414406Y1626692D03*
X460910Y1627472D03*
X64410Y1600802D03*
X1340420Y540122D03*
X704770Y204921D03*
X896060Y482922D03*
X716698Y210721D03*
X704770Y216732D03*
X895340Y499582D03*
X907470Y213680D03*
X902350Y220768D03*
X953970Y206575D03*
X716698Y198887D03*
X704770Y193110D03*
Y181299D03*
X947496Y227835D03*
X705800Y169488D03*
X947496Y213697D03*
X907470Y227854D03*
X941050Y530552D03*
X968286Y482241D03*
X716698Y175387D03*
X902350Y206594D03*
X944032Y435931D03*
X716698Y187387D03*
X944250Y196189D03*
X954420Y512952D03*
Y498852D03*
G54D104*
X1247638Y269488D03*
G54D108*
X520265Y111060D03*
X517115D03*
Y107550D03*
X520265D03*
G54D99*
X1550708Y991220D03*
X525275Y1171319D03*
X1332204D03*
X1326240Y811122D03*
X1501417Y1171319D03*
X1507381Y811122D03*
X1282913Y991220D03*
X306771D03*
X574566D03*
X350098Y811122D03*
X531240D03*
X356062Y1171319D03*
G54D81*
X723041Y-11500D03*
X840001Y18500D03*
X980899Y-11500D03*
Y18500D03*
X1032433Y-21511D03*
Y-1511D03*
X1290291Y-21511D03*
Y-1511D03*
X62813Y414300D03*
X47619Y417205D03*
X1386273Y270370D03*
X615573Y178034D03*
X628195Y174214D03*
X1282645Y253971D03*
X941059Y426211D03*
X901829Y514430D03*
X889439Y491299D03*
X1407029Y154432D03*
X922879Y530276D03*
X946727Y506252D03*
G54D116*
X508133Y100007D03*
Y106897D03*
X498487Y100007D03*
Y106897D03*
G54D98*
X1819208Y1420330D03*
X38346D03*
G54D84*
X19685Y-29134D03*
X1837795D03*
X1808192Y1569255D03*
X41870Y1511291D03*
X1812980Y502472D03*
X49280Y337402D03*
X441043Y1672205D03*
X1416437Y1672204D03*
X2081889Y1803261D03*
Y-29134D03*
G54D101*
X493384Y101473D03*
X491284D03*
X493384Y98373D03*
X491284D03*
G54D90*
X663561Y38286D03*
Y36186D03*
G54D93*
X1057658Y204724D03*
X805690D03*
G54D91*
X666889Y38287D03*
Y36187D03*
G54D102*
X763602Y605413D03*
X1739744D03*
X1094075Y605378D03*
X117933D03*
G54D110*
X841240Y1420330D03*
X1016240D03*
G54D88*
X1680327Y277236D03*
X1153555Y277208D03*
X704185Y277236D03*
X177413Y277208D03*
G54D86*
X177311Y1657953D03*
G54D87*
X1680232D03*
%LPC*%
G75*
G36*
G01X817460Y1718640D02*
X900700D01*
X907010Y1712330D01*
Y1667230D01*
G03X907376Y1666346I1251J0D01*
G01X917346Y1656376D01*
G03X918230Y1656010I884J885D01*
G01X1044142D01*
X1047300Y1652852D01*
Y1640370D01*
G03X1047666Y1639486I1251J0D01*
G01X1051186Y1635966D01*
G03X1052070Y1635600I884J885D01*
G01X1101560D01*
X1103140Y1634020D01*
Y1607480D01*
X1102240Y1606580D01*
X943932D01*
X943914Y1606583D01*
G03X943698Y1606602I-217J-1231D01*
G03X942686Y1606086I0J-1250D01*
G01X935490Y1598890D01*
X927248D01*
G03X926364Y1598524I0J-1251D01*
G01X921156Y1593316D01*
G03X920790Y1592432I885J-884D01*
G01Y1578870D01*
X920730Y1578810D01*
X907390D01*
X907330Y1578870D01*
Y1592414D01*
G03X906964Y1593298I-1251J0D01*
G01X906522Y1593740D01*
Y1603900D01*
G03X906156Y1604784I-1251J0D01*
G01X898266Y1612674D01*
G03X897382Y1613040I-884J-885D01*
G01X888610D01*
G03X887726Y1612674I0J-1251D01*
G01X879888Y1604836D01*
G03X879522Y1603952I885J-884D01*
G01Y1593670D01*
X879176Y1593324D01*
G03X878810Y1592440I885J-884D01*
G01Y1578920D01*
X878710Y1578820D01*
X865410D01*
X865340Y1578890D01*
Y1592484D01*
G03X864974Y1593368I-1251J0D01*
G01X864622Y1593720D01*
Y1603382D01*
G03X864256Y1604266I-1251J0D01*
G01X856288Y1612234D01*
G03X855404Y1612600I-884J-885D01*
G01X845648D01*
G03X844764Y1612234I0J-1251D01*
G01X837846Y1605316D01*
G03X837480Y1604432I885J-884D01*
G01Y1593680D01*
X837146Y1593346D01*
G03X836780Y1592462I885J-884D01*
G01Y1578840D01*
X836760Y1578820D01*
X823390D01*
X823370Y1578840D01*
Y1592334D01*
G03X823004Y1593218I-1251J0D01*
G01X822622Y1593600D01*
Y1603560D01*
G03X822256Y1604444I-1251J0D01*
G01X814056Y1612644D01*
G03X813172Y1613010I-884J-885D01*
G01X803780D01*
G03X802896Y1612644I0J-1251D01*
G01X795888Y1605636D01*
G03X795522Y1604752I885J-884D01*
G01Y1593622D01*
X795156Y1593256D01*
G03X794790Y1592372I885J-884D01*
G01Y1578870D01*
X794740Y1578820D01*
X781390D01*
X781370Y1578840D01*
Y1592472D01*
G03X781004Y1593356I-1251J0D01*
G01X776356Y1598004D01*
G03X775472Y1598370I-884J-885D01*
G01X751458D01*
G03X750574Y1598004I0J-1251D01*
G01X745888Y1593317D01*
G03X745522Y1592433I885J-884D01*
G01Y1591251D01*
X745422Y1591151D01*
X744540D01*
G03X743656Y1590785I0J-1251D01*
G01X742956Y1590085D01*
G03X742590Y1589201I885J-884D01*
G01Y1578820D01*
X742522Y1578751D01*
X729122D01*
Y1600351D01*
X730056Y1601285D01*
G03X730360Y1601779I-884J885D01*
G03X730554Y1602518I-1308J738D01*
G03X730438Y1603098I-1502J1D01*
G01X730422Y1603135D01*
Y1607433D01*
G03X730056Y1608317I-1251J0D01*
G01X729622Y1608751D01*
Y1626244D01*
X759328Y1655950D01*
X777232D01*
G03X778116Y1656316I0J1251D01*
G01X812594Y1690794D01*
G03X812960Y1691678I-885J884D01*
G01Y1714140D01*
X817460Y1718640D01*
G37*
G36*
G01X1077918Y1601500D02*
G02X1078058Y1601442I-1J-200D01*
G01X1079940Y1599560D01*
G03X1080000Y1599504I882J885D01*
G01Y1565496D01*
G03X1079940Y1565440I822J-941D01*
G01X1079067Y1564567D01*
G03X1079004Y1564500I879J-889D01*
G01X945496D01*
G03X945440Y1564560I-941J-822D01*
G01X943567Y1566433D01*
X943566Y1566434D01*
G03X943500Y1566496I-888J-880D01*
G01Y1600504D01*
G03X943560Y1600560I-822J941D01*
G01X944440Y1601440D01*
G03X944496Y1601500I-885J882D01*
G01X1077918D01*
G37*
G36*
G01X1105930Y1598120D02*
X1106502Y1597548D01*
Y1565860D01*
X1105142Y1564500D01*
X1085200D01*
X1084200Y1565500D01*
Y1597750D01*
X1084580Y1598130D01*
X1094904D01*
X1094915Y1598129D01*
G03X1095062Y1598120I150J1241D01*
G01X1105930D01*
G37*
%LPD*%
G75*
G54D15*
X16925Y203366D03*
X17061Y196368D03*
X24720Y216362D03*
Y232362D03*
Y224362D03*
Y240362D03*
X16420Y420662D03*
X26500Y672862D03*
Y675862D03*
X27300Y764200D03*
X27520Y1245162D03*
X33500Y200862D03*
X33670Y192862D03*
Y208362D03*
X30795Y213358D03*
X33670Y232362D03*
X42500Y224409D03*
X30795Y227366D03*
X33670Y240362D03*
X40000Y298707D03*
X36000Y295952D03*
X40000Y293392D03*
X33105Y304972D03*
X35740Y363337D03*
X39320Y392269D03*
X40940Y387302D03*
X43020Y382942D03*
X41933Y395652D03*
X45960Y428806D03*
X45812Y451602D03*
X38220Y589862D03*
Y592862D03*
X33020Y595232D03*
X32720Y598402D03*
X34790Y666595D03*
X31390D03*
X38470Y688122D03*
Y683122D03*
Y680622D03*
Y685622D03*
Y693122D03*
Y690622D03*
Y695622D03*
X34899Y711400D03*
X45700Y724100D03*
X45800Y726874D03*
X43841Y1248688D03*
X44833Y1656759D03*
X48269Y1672771D03*
X62020Y295952D03*
X62731Y305426D03*
X59322Y360702D03*
X51114Y360862D03*
X53406Y402862D03*
X49360Y428806D03*
X61171D03*
X47619Y418655D03*
X47618Y415613D03*
X49212Y451602D03*
X48400Y586000D03*
X57595Y603476D03*
X59500Y738700D03*
X56777Y1314165D03*
X56799Y1520094D03*
Y1536094D03*
Y1540094D03*
Y1560094D03*
X59833Y1604359D03*
X54333Y1613359D03*
X50333D03*
X54478Y1663669D03*
X54535Y1658447D03*
X57833Y1671809D03*
X53333Y1671862D03*
X65000Y1681900D03*
X58325Y1679275D03*
X65937Y28403D03*
Y48720D03*
X77165Y278798D03*
Y295798D03*
Y286262D03*
Y303262D03*
X63429Y360702D03*
X67681D03*
X77220Y379022D03*
Y381522D03*
X68020Y395222D03*
X75516Y420319D03*
Y424319D03*
X64571Y428806D03*
X63540Y438802D03*
X72610Y441262D03*
Y444762D03*
X72981Y466385D03*
X77000Y485362D03*
X74550Y487812D03*
X80300Y641862D03*
X80241Y659011D03*
X80123Y664031D03*
X80135Y667933D03*
X74559Y667814D03*
X78080Y701832D03*
X63930Y739300D03*
X73759Y754726D03*
X68315Y765664D03*
X73759Y759246D03*
X72485Y1304152D03*
X75485D03*
X78485D03*
X72485Y1307152D03*
X75485D03*
X69485Y1304152D03*
Y1307152D03*
X65600Y1318588D03*
X65240Y1326068D03*
X75485Y1316152D03*
X72485Y1313152D03*
Y1310152D03*
X75485Y1313152D03*
Y1310152D03*
X69485D03*
X69809Y1333918D03*
Y1331418D03*
Y1336418D03*
X72809Y1333918D03*
Y1331418D03*
Y1336418D03*
X75809Y1333918D03*
Y1331418D03*
Y1336418D03*
X72909Y1339938D03*
X79009Y1340238D03*
X75909Y1339938D03*
X73027Y1347925D03*
X73059Y1345138D03*
X72987Y1342535D03*
X75909Y1342438D03*
X79009Y1342738D03*
Y1345238D03*
X78977Y1348025D03*
X75859Y1348138D03*
Y1345138D03*
X76680Y1530482D03*
X72774Y1546519D03*
X77040Y1601102D03*
X64410Y1599102D03*
X65120Y1609909D03*
X65520Y1615972D03*
X64410Y1602502D03*
X74100Y1613300D03*
X77833Y1678902D03*
X73833Y1674252D03*
X69833Y1678582D03*
X87620Y285321D03*
X87845Y278798D03*
Y295798D03*
X87820Y302821D03*
X87520Y395865D03*
Y391391D03*
Y382219D03*
X85826Y428319D03*
X84410Y438519D03*
X83320Y445212D03*
X94439Y450081D03*
X81505Y447377D03*
X79400Y482862D03*
X91027Y643276D03*
X89859Y628246D03*
X86459D03*
X82961Y657111D03*
X95725Y654540D03*
X95860Y659622D03*
X83165Y652564D03*
X91078Y649584D03*
X83208Y646436D03*
X83250Y665428D03*
X84470Y668702D03*
X86433Y688160D03*
X81285Y689804D03*
X84035Y697604D03*
X93547Y692260D03*
X83004Y705141D03*
X97295Y699786D03*
X85095Y722164D03*
X95849Y716358D03*
X91610Y721414D03*
X82357Y737803D03*
X84623Y741249D03*
X81966Y759246D03*
X85877Y759275D03*
X93485Y1304152D03*
X87485D03*
X90485D03*
X93485Y1307152D03*
X84485Y1304152D03*
X81485D03*
X93485Y1318152D03*
Y1315652D03*
Y1310152D03*
Y1313152D03*
X94209Y1337738D03*
X81809Y1340238D03*
X84809D03*
X87809D03*
X90809D03*
X94209D03*
X84809Y1345238D03*
X81809Y1342738D03*
X84809D03*
X81809Y1348238D03*
Y1345238D03*
X84809Y1348238D03*
X87809D03*
Y1345238D03*
Y1342738D03*
X94209D03*
Y1348238D03*
Y1345238D03*
X90809Y1348238D03*
Y1345238D03*
Y1342738D03*
X88520Y1484482D03*
Y1491482D03*
Y1487982D03*
Y1494982D03*
X87500Y1567069D03*
X91500D03*
X90713Y1581852D03*
Y1597867D03*
X81008Y1589872D03*
X90788Y1615821D03*
Y1601867D03*
X81900Y1613300D03*
X85800D03*
X90698Y1630362D03*
X90788Y1619821D03*
X90698Y1642362D03*
X90407Y1656672D03*
X88333Y1661334D03*
X81833Y1674526D03*
X86245Y1694362D03*
X96420Y1693803D03*
X86030Y1683092D03*
X113490Y216596D03*
X113400Y232128D03*
X110937Y285495D03*
Y302854D03*
X107200Y393562D03*
X107301Y388071D03*
X107419Y487807D03*
X104875Y490980D03*
X102384Y505374D03*
X112480Y507792D03*
X110689Y498271D03*
X110464Y505374D03*
X101983Y518100D03*
X99880Y526300D03*
X110060Y515279D03*
X99773Y515606D03*
X105587Y520727D03*
X106110Y633732D03*
X107489Y630917D03*
X110374Y630879D03*
X102269Y634466D03*
X107045Y661917D03*
X99021Y663732D03*
X103397Y667272D03*
X102120Y688650D03*
X102060Y692100D03*
X102420Y697262D03*
X96626Y736187D03*
X110527Y758869D03*
X108465Y1304292D03*
Y1307292D03*
X105475Y1304222D03*
Y1307222D03*
X102485Y1304152D03*
X99485D03*
X96485D03*
X102485Y1307152D03*
X99485D03*
X96485D03*
X108465Y1318292D03*
Y1310292D03*
Y1313292D03*
Y1315792D03*
X105475Y1318222D03*
Y1310222D03*
Y1313222D03*
Y1315722D03*
X99485Y1318152D03*
X96485D03*
Y1315652D03*
Y1310152D03*
Y1313152D03*
X99485Y1310152D03*
Y1313152D03*
Y1315652D03*
X102485Y1318152D03*
Y1310152D03*
Y1313152D03*
Y1315652D03*
X96809Y1340238D03*
Y1345238D03*
Y1348238D03*
Y1342738D03*
X112270Y1518907D03*
X99274Y1529169D03*
X96570Y1546187D03*
X99750Y1565378D03*
Y1561978D03*
X103902Y1584337D03*
X104318Y1589352D03*
X100620Y1596367D03*
X101500Y1604400D03*
X100020Y1615821D03*
X98738Y1605867D03*
X104400Y1632385D03*
X104430Y1628012D03*
X104318Y1637862D03*
X99600Y1668332D03*
X99645Y1663217D03*
X99980Y1687921D03*
Y1698921D03*
X115850Y186362D03*
X122000Y207362D03*
X116920Y207462D03*
X118920Y278875D03*
X119220Y306236D03*
X119920Y379362D03*
X119457Y392071D03*
Y388071D03*
X125070Y486736D03*
X125013Y491829D03*
X124124Y495883D03*
X116171Y485041D03*
X112483Y510637D03*
X116411Y497707D03*
X118652Y528860D03*
X129762Y531942D03*
X115793Y528188D03*
X112393D03*
X111920Y632922D03*
X114540Y633032D03*
X117750Y633232D03*
X120440Y633347D03*
X121400Y638062D03*
X125890Y644163D03*
X122329Y654660D03*
X122280Y651934D03*
X124431Y649570D03*
X122575Y671930D03*
X118019Y661371D03*
X124737Y735726D03*
X118737D03*
X121737D03*
Y738726D03*
X118737D03*
X124737D03*
X123220Y1324662D03*
X120220D03*
X112749Y1532594D03*
Y1528594D03*
Y1552594D03*
Y1556594D03*
X117707Y1553759D03*
X125033Y1589352D03*
X116798D03*
X123230Y1597350D03*
X119500Y1622380D03*
X124795Y1681846D03*
X128195Y1674362D03*
X114645Y1698862D03*
X117220Y1683437D03*
X127195Y1696362D03*
Y1700362D03*
Y1704362D03*
X125082Y1727092D03*
X123394Y1723472D03*
X117426Y1726622D03*
X125720Y1719262D03*
X141520Y181462D03*
X139720Y179162D03*
X143470Y184012D03*
X133590Y212382D03*
X129394Y278875D03*
X129375Y274800D03*
X129394Y306236D03*
X135220Y397071D03*
X132490Y420062D03*
X138042Y480238D03*
X132833D03*
X136982Y497090D03*
X131737Y496295D03*
X135006Y487753D03*
X131295Y487822D03*
X141325Y503806D03*
X141462Y507600D03*
X141329Y510487D03*
X141220Y498810D03*
X138878Y512550D03*
X138408Y507366D03*
X139153Y516453D03*
X133160Y532002D03*
X132600Y537072D03*
Y540472D03*
X133467Y634531D03*
X131740Y640103D03*
X131600Y646861D03*
X131330Y665740D03*
X142960Y690807D03*
X140460D03*
X142754Y698811D03*
X140254D03*
X142778Y706835D03*
X140278D03*
X140326Y721660D03*
X142826D03*
X140142Y1392545D03*
Y1396275D03*
X129627Y1556360D03*
X129586Y1553759D03*
X129813Y1604367D03*
X130533Y1622321D03*
X129533Y1637862D03*
X137420Y1708362D03*
X144520Y1717562D03*
X141642Y1717592D03*
X134557Y1722778D03*
X137852Y1726572D03*
X147924Y28258D03*
X148784Y48720D03*
X145720Y186462D03*
Y202862D03*
Y206362D03*
X156670Y344542D03*
X159170D03*
X154220Y375682D03*
X158110Y376172D03*
X160090Y391170D03*
Y397470D03*
X152826Y439397D03*
Y434362D03*
X156306Y449045D03*
X153360Y449112D03*
X149557Y494353D03*
X150113Y488487D03*
X161267Y503143D03*
X149472Y506810D03*
X160000Y510052D03*
X152470Y495383D03*
X151378Y526924D03*
X149512Y514810D03*
X150800Y512021D03*
X153737Y514893D03*
X149504Y519881D03*
X154647Y521783D03*
X150877Y757969D03*
X151277Y1339183D03*
X153877D03*
X156477D03*
X156417Y1336343D03*
X151217Y1336393D03*
X153817D03*
X156417Y1333843D03*
X151217Y1333893D03*
X153817D03*
X151277Y1346883D03*
X153877D03*
X151277Y1349383D03*
X153877D03*
X156477Y1346883D03*
Y1349383D03*
Y1344383D03*
X151277D03*
X153877D03*
X156477Y1341883D03*
X151277D03*
X153877D03*
X147307Y1404745D03*
X149568Y1395145D03*
Y1397695D03*
X152684Y1403451D03*
X157490Y1421454D03*
X154990D03*
X159858Y1409361D03*
X155858Y1406669D03*
Y1409390D03*
X157530Y1432124D03*
X155030D03*
X157530Y1424124D03*
X155030D03*
X157530Y1429124D03*
X155030Y1426624D03*
Y1429124D03*
X157530Y1426624D03*
Y1435124D03*
X155030D03*
X157530Y1437754D03*
X155030D03*
X146390Y1504240D03*
X153600Y1505600D03*
X147067Y1545985D03*
X157441Y1581932D03*
X152026Y1614138D03*
X158335Y1614452D03*
X155180Y1619872D03*
X156070Y1695702D03*
X145745Y1712362D03*
X161310Y1708022D03*
X148145Y1701862D03*
X155145Y1713517D03*
X164830Y344542D03*
X161670D03*
X173275Y393497D03*
X164000Y415362D03*
X163926Y425383D03*
X164000Y420362D03*
X172507Y417205D03*
X163926Y430883D03*
Y443319D03*
Y439397D03*
Y435383D03*
X178546Y453806D03*
X172632Y454095D03*
X165176Y500782D03*
X176393Y575189D03*
X173793D03*
X176393Y572689D03*
X173793D03*
X171293D03*
Y575189D03*
X173793Y577790D03*
X171293D03*
X176393D03*
X176651Y596883D03*
Y594163D03*
X173878Y597027D03*
Y594307D03*
X176651Y599603D03*
X173878Y599747D03*
X161126Y721660D03*
X161078Y706835D03*
X163626Y721660D03*
X163578Y706835D03*
X170877Y1333783D03*
Y1336383D03*
X176077Y1333783D03*
X173477D03*
X176077Y1336383D03*
X173477D03*
X170907Y1339233D03*
X176107D03*
X173507D03*
X170877Y1341883D03*
X176077D03*
X173477D03*
Y1349383D03*
Y1346883D03*
Y1344383D03*
X176077D03*
Y1346883D03*
Y1349383D03*
X170877D03*
Y1346883D03*
Y1344383D03*
X176358Y1403669D03*
X176258Y1400669D03*
X173892Y1402749D03*
Y1405649D03*
X170922Y1399255D03*
X166262D03*
X173252Y1400005D03*
X168592D03*
X160490Y1421454D03*
X164000Y1408862D03*
X162257Y1406594D03*
X160530Y1432124D03*
Y1424124D03*
Y1429124D03*
Y1426624D03*
Y1435124D03*
Y1437754D03*
X165500Y1440362D03*
X173727Y1452134D03*
Y1448734D03*
X170570Y1509250D03*
X173331Y1579399D03*
X172099Y1588141D03*
X164920Y1712017D03*
X163060Y1717017D03*
X178226Y1726517D03*
X172962Y1721234D03*
X169777Y1726517D03*
X178142Y1720652D03*
X186120Y24162D03*
X188620D03*
X190880Y383012D03*
Y387162D03*
Y391082D03*
X178375Y396571D03*
X181845Y401071D03*
X187371Y425383D03*
X187532Y421387D03*
X187371Y430883D03*
Y443383D03*
X180740Y437562D03*
X184550Y435712D03*
X187371Y440742D03*
X194440Y433895D03*
Y439565D03*
X187371Y447172D03*
X177871D03*
X181994Y453932D03*
X180640Y447172D03*
X185211Y453942D03*
X185191Y502439D03*
X186793Y575189D03*
X184193D03*
X186793Y572689D03*
X184193D03*
X181593Y575189D03*
X178993D03*
X181593Y572689D03*
X178993D03*
X189293Y575189D03*
X186793Y577790D03*
X184193D03*
X189293D03*
X181593D03*
X178993D03*
X181651Y596883D03*
X179151D03*
X186796Y594195D03*
Y596915D03*
X184151Y596883D03*
X179151Y594163D03*
X181651D03*
X184151D03*
X181651Y599603D03*
X179151D03*
X186796Y599635D03*
X184151Y599603D03*
X186720Y737862D03*
X180720D03*
X183720D03*
Y734862D03*
X180720D03*
X186720D03*
X185835Y757057D03*
X188978Y756855D03*
X191602Y756839D03*
X189377Y1333783D03*
X191977D03*
X189377Y1336383D03*
X191977D03*
X191947Y1339263D03*
X189347D03*
X189377Y1349383D03*
X191977D03*
X189377Y1346883D03*
X191977D03*
Y1344383D03*
X189377D03*
X191977Y1341883D03*
X189377D03*
X187711Y1395170D03*
Y1397670D03*
X190827Y1403451D03*
X180977Y1396173D03*
X178458Y1399269D03*
Y1402169D03*
Y1405069D03*
X188211Y1406691D03*
X186165Y1422589D03*
X183135Y1419784D03*
X180510Y1420258D03*
X177510D03*
X186135Y1419784D03*
X183165Y1422589D03*
X177510Y1423278D03*
X180510D03*
X183075Y1430424D03*
Y1425424D03*
Y1427924D03*
X186075Y1430424D03*
Y1425424D03*
Y1427924D03*
X183075Y1432924D03*
X186075D03*
X192600Y1557360D03*
X185895Y1557875D03*
X189600Y1566300D03*
X187400Y1568132D03*
X187542Y1729092D03*
X193293Y1722197D03*
X188794Y1725092D03*
X195050Y412055D03*
X199149Y425755D03*
Y420255D03*
Y414755D03*
X204699Y423242D03*
Y428742D03*
X195050Y417465D03*
X199149Y436755D03*
Y442255D03*
Y431255D03*
Y453255D03*
Y447755D03*
X197650Y455712D03*
X199149Y468255D03*
X208200Y493510D03*
X202338Y568746D03*
X201392Y574271D03*
X198336D03*
X204610Y571097D03*
X199164Y582481D03*
X200654Y578271D03*
X201622Y581009D03*
X208056Y591665D03*
X208806Y589335D03*
X208056Y587005D03*
X208806Y584675D03*
X202262Y592305D03*
X205162D03*
X202338Y602746D03*
X201392Y608271D03*
X198336D03*
X203892Y594471D03*
X202492Y596571D03*
X208292D03*
X206892Y594371D03*
X205392Y596571D03*
X204610Y605097D03*
X199164Y616481D03*
X200654Y612271D03*
X201622Y615009D03*
X208806Y618675D03*
X208056Y621005D03*
X208806Y623335D03*
X202338Y636746D03*
X208056Y625665D03*
X203892Y628471D03*
X202492Y630571D03*
X202262Y626305D03*
X208292Y630571D03*
X206892Y628371D03*
X205162Y626305D03*
X205392Y630571D03*
X204610Y639097D03*
X201392Y642271D03*
X199164Y650481D03*
X200654Y646271D03*
X201622Y649009D03*
X198336Y642271D03*
X208056Y655005D03*
X208806Y657335D03*
Y652675D03*
X207620Y671262D03*
X198420Y672662D03*
X198495Y669487D03*
X208056Y659665D03*
X205392Y664571D03*
X205162Y660305D03*
X206892Y662371D03*
X202262Y660305D03*
X202492Y664571D03*
X203892Y662471D03*
X208292Y664571D03*
X196049Y678195D03*
X194196Y687061D03*
X200018Y677492D03*
X193332Y678195D03*
X207129Y690027D03*
X203199Y690006D03*
X197086Y686326D03*
X203179Y693626D03*
X207140Y693636D03*
X195735Y696469D03*
X198235Y698969D03*
Y696469D03*
X200735Y698969D03*
Y696469D03*
X207140Y738462D03*
X205220Y736562D03*
X201220Y736662D03*
X203660Y731802D03*
X195602Y756839D03*
X203602Y756855D03*
X208977Y1336383D03*
Y1333783D03*
X194577D03*
Y1336383D03*
X209007Y1339263D03*
X194547D03*
X208977Y1341883D03*
X194577Y1349383D03*
Y1346883D03*
Y1344383D03*
X208977D03*
Y1346883D03*
Y1349383D03*
X194577Y1341883D03*
X206735Y1400005D03*
X209065Y1399255D03*
X204405D03*
X198001Y1409361D03*
X193941Y1407029D03*
X200797Y1409605D03*
X200492Y1406686D03*
X193941Y1409750D03*
X195966Y1542863D03*
X203120Y1624782D03*
X208115Y1624217D03*
X195590Y1714517D03*
X196010Y1709017D03*
X208295Y1703362D03*
X199050Y1726431D03*
X204600Y1733022D03*
X225407Y321831D03*
X209530Y426192D03*
X217770Y428262D03*
X224210Y431501D03*
X224305Y422977D03*
X219995Y426267D03*
X224210Y436619D03*
X218140Y440735D03*
X218010Y432735D03*
X223664Y443125D03*
X220000Y448735D03*
X212891Y566632D03*
X210391Y567981D03*
X212891Y601981D03*
X210391D03*
Y635981D03*
X212891D03*
X210320Y671262D03*
X224900Y713293D03*
X209720Y731862D03*
X220033Y756844D03*
X211602Y756855D03*
X216842Y756865D03*
X214177Y1336383D03*
X211577D03*
X214177Y1333783D03*
X211577D03*
X214207Y1339263D03*
X211607D03*
X214177Y1341883D03*
X211577D03*
X214177Y1349383D03*
Y1346883D03*
Y1344383D03*
X211577D03*
Y1346883D03*
Y1349383D03*
X211395Y1400005D03*
X214201Y1404169D03*
X212035Y1402899D03*
X214101Y1401169D03*
X216554Y1399264D03*
Y1402164D03*
Y1405064D03*
X212035Y1405799D03*
X219587Y1435402D03*
X217469Y1454725D03*
X219587Y1443402D03*
Y1439402D03*
X220869Y1454725D03*
X209820Y1631142D03*
X210593Y1714017D03*
X212120Y1703062D03*
X214120Y1713462D03*
X233339Y17662D03*
X235701Y21582D03*
X241310Y20322D03*
X229135Y26474D03*
X225735D03*
X238063Y26232D03*
X235701Y39570D03*
X229131Y50646D03*
X225731D03*
X239820Y54362D03*
X239720Y71862D03*
X239010Y78542D03*
X238297Y129703D03*
X234902Y174047D03*
X226800Y359464D03*
X230359Y461683D03*
X227430Y719772D03*
X238940Y716652D03*
X230864Y1254295D03*
X246510Y20362D03*
X242220Y39362D03*
X246220D03*
X250220D03*
X254050Y39422D03*
X246360Y26852D03*
X248820Y48962D03*
X252320D03*
X255820D03*
X257520Y51562D03*
X254020D03*
X250520D03*
X249885Y69623D03*
X245220Y67862D03*
X248097Y92143D03*
X247897Y100543D03*
X244822Y115543D03*
Y111543D03*
X253910Y115722D03*
X253878Y111771D03*
X243892Y140912D03*
X259933Y141122D03*
X257256Y156727D03*
X245490Y159702D03*
X252000Y395400D03*
X255810Y405582D03*
X252500Y415862D03*
X258066Y426735D03*
X256695Y461117D03*
X257750Y450842D03*
X254713Y518465D03*
X245700Y513262D03*
X250100Y521783D03*
X256885Y574805D03*
X254385D03*
X256855Y571995D03*
X251885Y574805D03*
X249800Y563262D03*
X254355Y589235D03*
X256855D03*
X251855D03*
X256855Y605995D03*
X251885Y608805D03*
X257643Y594220D03*
X255043D03*
Y596820D03*
X257643D03*
X256885Y608805D03*
X254385D03*
X256855Y603495D03*
X251855Y623265D03*
X254355D03*
X256855D03*
Y639995D03*
Y637495D03*
X257643Y628220D03*
X255043D03*
Y630820D03*
X257643D03*
X256885Y642805D03*
X254385D03*
X251855Y657265D03*
X251885Y642805D03*
X254355Y657265D03*
X256855D03*
X257643Y662220D03*
X255043D03*
Y664820D03*
X257643D03*
X253819Y675567D03*
X253849Y678077D03*
X256419Y675567D03*
X256449Y678077D03*
X251219Y675567D03*
X251249Y678077D03*
X248649D03*
X248989Y698827D03*
X249019Y693767D03*
X251589Y698827D03*
X251649Y696277D03*
X254189Y698827D03*
X251619Y693767D03*
X256849Y696277D03*
X256789Y698827D03*
X256819Y693767D03*
X254249Y696277D03*
X254219Y693767D03*
X248300Y703862D03*
X242460Y716652D03*
X253057Y755345D03*
X245487Y755435D03*
X259510Y757822D03*
X251187Y1255025D03*
X263240Y38122D03*
X266990Y41832D03*
X275120Y28562D03*
X275900Y48872D03*
X259320Y48962D03*
X261020Y51562D03*
X263520D03*
X261820Y48962D03*
X264740Y49182D03*
X266497Y69536D03*
Y72036D03*
X264720Y56362D03*
Y60362D03*
Y64362D03*
X266597Y77526D03*
Y80026D03*
X263320Y87662D03*
X261420Y100662D03*
X264920D03*
X268420D03*
X262920Y97962D03*
X266420D03*
X269920D03*
X273620Y96662D03*
X263550Y120922D03*
X269191Y121092D03*
X275797Y120245D03*
X265910Y125492D03*
X266975Y140107D03*
X260600Y151062D03*
X272800Y140162D03*
X264578Y151203D03*
X260100Y159562D03*
X265500Y227862D03*
X263000D03*
X260500Y227362D03*
Y224862D03*
X270240Y245332D03*
X271821Y251962D03*
X267759D03*
X259224Y419532D03*
X263430Y422235D03*
X259869Y431039D03*
X262963Y443735D03*
X272500Y447735D03*
X263040Y448752D03*
X272500Y452862D03*
X264055Y574505D03*
X264025Y571995D03*
X261555Y574505D03*
X261525Y571995D03*
X264055Y566935D03*
X263995Y569485D03*
X261495D03*
X261555Y566935D03*
X266555Y574505D03*
X266525Y571995D03*
X266495Y569485D03*
X266555Y566935D03*
X269055Y574505D03*
X269025Y571995D03*
X268995Y569485D03*
X269055Y566935D03*
X261465Y592115D03*
X261525Y589565D03*
X264025D03*
X263965Y592115D03*
X266525Y589565D03*
X266465Y592115D03*
X269025Y589565D03*
X268965Y592115D03*
X264025Y605995D03*
X261525D03*
X264055Y608505D03*
X261555D03*
X261435Y597175D03*
X261495Y594625D03*
X263995D03*
X263935Y597175D03*
X266525Y605995D03*
X266555Y608505D03*
X266435Y597175D03*
X266495Y594625D03*
X261525Y603495D03*
X264025D03*
X266525D03*
X269025Y605995D03*
X269055Y608505D03*
X268935Y597175D03*
X268995Y594625D03*
X269025Y603495D03*
X261495Y621055D03*
X263995D03*
X261525Y623565D03*
X264025D03*
X263995Y611055D03*
X261495D03*
X266495Y621055D03*
X266525Y623565D03*
X266495Y611055D03*
X268995Y621055D03*
X269025Y623565D03*
X268995Y611055D03*
X261525Y639995D03*
X264025D03*
X261525Y637495D03*
X266525Y639995D03*
X269025D03*
X264025Y637495D03*
X266525D03*
X269025D03*
X263965Y626115D03*
X261465D03*
X266465D03*
X268965D03*
X261495Y655055D03*
X263995D03*
X261525Y657565D03*
X264025D03*
X263995Y645055D03*
X264055Y642505D03*
X261495Y645055D03*
X261555Y642505D03*
X266495Y655055D03*
X266525Y657565D03*
X266495Y645055D03*
X266555Y642505D03*
X268995Y655055D03*
X269025Y657565D03*
X268995Y645055D03*
X269055Y642505D03*
X261465Y660115D03*
X263965D03*
X266465D03*
X268965D03*
X259049Y678077D03*
X259019Y675567D03*
X259419Y693767D03*
X259389Y698827D03*
X259449Y696277D03*
X269600Y715792D03*
X274247Y727165D03*
X268331Y738029D03*
X273046Y735662D03*
X270100Y727262D03*
X264000Y726262D03*
X266700Y730962D03*
X271570Y746422D03*
X265997Y747535D03*
X272208Y768516D03*
X271057Y765525D03*
Y762425D03*
X287000Y20862D03*
X284233Y26474D03*
X280833D03*
X290799Y28362D03*
X284230Y50646D03*
X280830D03*
X289400Y54222D03*
X285357Y105003D03*
X288557D03*
X280857Y107303D03*
X285857Y115603D03*
X282857D03*
X280857Y109903D03*
X275797Y129592D03*
X287000Y139862D03*
X283053Y139728D03*
X276825Y140462D03*
X290685Y165447D03*
X286481Y251962D03*
X281077D03*
X276491D03*
X289274Y290662D03*
X284515D03*
X276500Y444862D03*
X274850Y442562D03*
X279500Y455362D03*
X277578Y509039D03*
X284482Y566022D03*
X286582Y637809D03*
Y634283D03*
X284287Y716015D03*
X277046Y725709D03*
Y735442D03*
X284358Y732562D03*
X283350Y728483D03*
X289137Y735275D03*
X279507Y727025D03*
X285046Y737964D03*
X281046Y737938D03*
X275210Y738102D03*
X287607Y754962D03*
X277046Y746702D03*
X281046D03*
X285046D03*
X299500Y22862D03*
X295520Y12762D03*
X302610Y26362D03*
X292060Y24472D03*
X295520Y26362D03*
X300248Y28362D03*
X304927Y24654D03*
X304972Y28362D03*
X302720Y38182D03*
X292590Y53982D03*
X293161Y50522D03*
X306570Y50222D03*
X290720Y40017D03*
X294720D03*
X295524Y52092D03*
X301310Y52482D03*
X298550Y51602D03*
X303715Y50857D03*
X292942Y71499D03*
X305747Y64013D03*
Y61113D03*
X305247Y71567D03*
X301600Y82457D03*
X302310Y75673D03*
X295357Y88903D03*
X307820Y95724D03*
X301183Y107103D03*
Y110003D03*
Y112803D03*
X296478Y149203D03*
X296800Y139762D03*
X306000Y165662D03*
X295685Y165447D03*
X296478Y158703D03*
X306730Y173842D03*
X304651Y251962D03*
X291759D03*
X306736Y290662D03*
X302765D03*
X298184D03*
X293763D03*
X298587Y508074D03*
X300520Y552262D03*
X307987Y577658D03*
X293805Y569397D03*
Y565997D03*
X298000Y587890D03*
X308417Y585158D03*
X308447Y592255D03*
X306144Y602225D03*
X305612Y622530D03*
Y625030D03*
Y627530D03*
X296405Y630732D03*
Y634132D03*
X295962Y679374D03*
X294679Y688446D03*
Y685046D03*
X291600Y705162D03*
X298273Y715400D03*
X297087Y721249D03*
X304602Y727968D03*
X293027Y755985D03*
X303647Y1307981D03*
X303723Y1353316D03*
Y1355853D03*
X304051Y1365453D03*
X306667Y1361597D03*
X302805Y1379941D03*
Y1376541D03*
X296170Y1622852D03*
X310400Y50362D03*
X314657Y71803D03*
Y68903D03*
X323040Y73122D03*
X323117Y81168D03*
Y76938D03*
X322875Y84318D03*
X316364Y89212D03*
X310459Y75892D03*
X320430Y78002D03*
X313357Y89503D03*
X313457Y96803D03*
X311057Y107103D03*
Y110003D03*
Y112803D03*
X308175Y144202D03*
X308500Y165662D03*
X311200Y165562D03*
X309230Y173842D03*
X309756Y177449D03*
Y181449D03*
X310970Y195362D03*
X308790Y197622D03*
X320270Y200462D03*
X319370Y214492D03*
X316370D03*
X319370Y217492D03*
X316370D03*
X323314Y210645D03*
X306910Y228162D03*
X309910D03*
X306910Y225162D03*
X309910D03*
X322658Y229254D03*
X319718Y223750D03*
X317981Y237724D03*
X320940Y238372D03*
X317129Y251962D03*
X316463Y290662D03*
X316444Y559125D03*
X317860Y572322D03*
X319520Y577658D03*
X312007Y588675D03*
X319520Y582658D03*
X316127Y592785D03*
X318560Y587632D03*
X321276Y599298D03*
X317386Y623207D03*
X308605Y629525D03*
Y627025D03*
X319557Y736225D03*
X317967Y746985D03*
Y771875D03*
X320578Y1290197D03*
X323028Y1297967D03*
X320428D03*
Y1295467D03*
X323028D03*
Y1292967D03*
X320428D03*
X320245Y1357401D03*
X313841Y1365553D03*
X309841Y1364815D03*
X318051Y1367043D03*
X316579Y1364585D03*
X309841Y1367871D03*
X322575Y1358151D03*
X332500Y150738D03*
X326216Y138787D03*
X326900Y162287D03*
X323420Y207549D03*
X326168Y207580D03*
X334485Y216809D03*
X337000Y216862D03*
X335575Y214170D03*
X328588Y209677D03*
X334500Y219362D03*
X337000D03*
X328939Y229139D03*
X335385Y235309D03*
X335412Y222176D03*
X329648Y252202D03*
X341295Y290239D03*
X329002Y290662D03*
X330674Y365702D03*
X328167Y379073D03*
X336270Y402992D03*
X329050Y607402D03*
X331339Y709313D03*
X328120Y710862D03*
X335677Y715215D03*
X327107Y732665D03*
X335467Y725335D03*
X338097Y736235D03*
X335126Y728323D03*
X327096Y736005D03*
X336446Y746486D03*
X338667Y772452D03*
X341527Y778362D03*
X339148Y1269717D03*
X339088Y1272287D03*
X339028Y1274887D03*
X325688Y1290167D03*
X325718Y1287587D03*
X328078Y1288747D03*
X323178Y1290197D03*
X323208Y1287617D03*
X328168Y1280967D03*
X325748Y1284987D03*
X328108Y1286147D03*
X328138Y1283567D03*
X328018Y1291317D03*
X339035Y1280218D03*
X339040Y1277594D03*
X328065Y1299248D03*
X325538Y1297937D03*
Y1292937D03*
Y1295437D03*
X328058Y1293917D03*
X328070Y1296624D03*
X335679Y1330518D03*
X334973Y1333353D03*
X338795Y1338799D03*
X336179Y1342753D03*
X324905Y1357401D03*
X327235Y1358151D03*
X332475Y1357945D03*
X327875Y1363945D03*
Y1361045D03*
X330041Y1362315D03*
X329941Y1359315D03*
X332475Y1363345D03*
Y1360445D03*
X340440Y120552D03*
X343450Y131167D03*
X342700Y139662D03*
X355189Y144267D03*
X351100Y150412D03*
X348100Y185162D03*
X345600Y188162D03*
X356295Y219362D03*
X353145D03*
X342000Y252612D03*
X354672Y252693D03*
X354145Y290591D03*
X345411Y364702D03*
Y376923D03*
X343354Y391643D03*
X347340Y407462D03*
X348880Y703442D03*
X354100Y720743D03*
X352879Y728657D03*
X348037Y728735D03*
X348730Y735098D03*
Y731698D03*
X344264Y1272455D03*
X341754Y1272485D03*
X344252Y1269948D03*
X341742Y1269978D03*
X344258Y1267117D03*
X341748Y1267147D03*
X341754Y1274985D03*
X344264Y1274955D03*
X355036Y1272433D03*
Y1269933D03*
X355378Y1262027D03*
X355318Y1264597D03*
X355258Y1267197D03*
X355036Y1274933D03*
X341605Y1280248D03*
X344115Y1280218D03*
X344264Y1277455D03*
X341754Y1277485D03*
X355048Y1277440D03*
X355025Y1280248D03*
X352373Y1334603D03*
X354703Y1335353D03*
X345969Y1342755D03*
X341969Y1342017D03*
X350179Y1344245D03*
X348707Y1341787D03*
X341969Y1345073D03*
X354850Y1371908D03*
X351850D03*
X349260Y1373418D03*
X351850Y1375408D03*
X354850D03*
X351850Y1378408D03*
X354850D03*
X351850Y1381408D03*
X354850D03*
X349260Y1376918D03*
Y1379918D03*
X349636Y1399601D03*
X352713Y1399336D03*
X355513Y1402306D03*
X352513D03*
X349513D03*
X355325Y1405386D03*
X349463Y1405286D03*
X352463D03*
X355325Y1408386D03*
X346426Y1414401D03*
X352401Y1414432D03*
X355325Y1414386D03*
Y1417386D03*
X352401Y1411432D03*
X355325Y1411386D03*
X352401Y1408432D03*
X349123Y1411376D03*
X349323Y1408406D03*
X349073Y1414356D03*
X346256Y1417301D03*
X352231Y1417332D03*
X348903Y1417256D03*
X363625Y127662D03*
X361800Y122522D03*
X366060Y133912D03*
X363525Y158702D03*
X361190Y210762D03*
X357303Y213159D03*
X371551Y224862D03*
X367306Y252811D03*
X366498Y290264D03*
X357660Y318850D03*
X364014Y366391D03*
Y378649D03*
X364179Y392037D03*
X370200Y409582D03*
X373720Y431362D03*
X365720Y440562D03*
X365771Y449480D03*
X359669Y686744D03*
X359639Y690114D03*
X360470Y705965D03*
X363101Y697348D03*
Y693948D03*
X360990Y726862D03*
X358902Y736225D03*
X355946Y728800D03*
X359790Y729835D03*
X358902Y739755D03*
Y743035D03*
Y754945D03*
Y746405D03*
Y773352D03*
X371578Y1248967D03*
X371458Y1254137D03*
X371330Y1256687D03*
X371518Y1251537D03*
X371278Y1259257D03*
X360198Y1269777D03*
X357546Y1272403D03*
Y1269903D03*
X360138Y1272347D03*
X357828Y1264567D03*
X357888Y1261997D03*
X360378Y1264627D03*
X360438Y1262057D03*
X357768Y1267167D03*
X360318Y1267227D03*
X357546Y1274903D03*
X360128Y1274957D03*
X371218Y1261857D03*
X371225Y1267188D03*
X371230Y1264564D03*
X357558Y1277410D03*
X357535Y1280218D03*
X360120Y1277654D03*
X367694Y1317092D03*
X367807Y1319592D03*
X368391Y1328161D03*
X370923Y1325373D03*
X357033Y1334603D03*
X359363Y1335353D03*
X362147Y1336553D03*
X360003Y1338247D03*
X364269Y1338017D03*
X364073Y1334903D03*
X360003Y1341147D03*
X362147Y1339653D03*
X364347Y1340853D03*
X364647Y1371990D03*
X361647D03*
X358647D03*
X367647D03*
X370552Y1372073D03*
X364647Y1375490D03*
X361647D03*
X358647D03*
Y1378490D03*
X370552Y1375573D03*
X367647Y1375490D03*
X355713Y1399336D03*
X361703Y1399386D03*
X364703D03*
X367703D03*
X370703D03*
X358703Y1402386D03*
X361703D03*
X364703D03*
X367703D03*
X370703D03*
X358713Y1399336D03*
X358573Y1405336D03*
X361573D03*
X364573D03*
X367573D03*
X370573D03*
X358703Y1414606D03*
X361703D03*
X364703D03*
X361703Y1417386D03*
X358703D03*
X364703D03*
X367703D03*
Y1414606D03*
X358217Y1411405D03*
X370517Y1414615D03*
X370717Y1417405D03*
X357917Y1408205D03*
X367948Y1531529D03*
X371850Y1534062D03*
X368600Y1543200D03*
X367140Y1645390D03*
X366700Y1649000D03*
X370500Y1654362D03*
X370635Y1675820D03*
X369300Y1680400D03*
Y1682900D03*
X380930Y122022D03*
X383160Y124322D03*
X383060Y128491D03*
X372530Y122972D03*
X373200Y126052D03*
X379295Y131002D03*
X379860Y252162D03*
X379112Y290386D03*
X385720Y320902D03*
X376500Y366391D03*
Y378649D03*
X377136Y390307D03*
X390220Y392062D03*
X383060Y403542D03*
X379220Y436362D03*
X376220D03*
X382220D03*
X389920Y461362D03*
X379220Y470962D03*
X387500Y495362D03*
X389020Y522862D03*
X371970Y683892D03*
X381010Y734732D03*
X376638Y1248997D03*
X374088Y1248937D03*
X374028Y1251507D03*
X373823Y1256896D03*
X376333Y1256866D03*
X376518Y1254167D03*
X376578Y1251567D03*
X373968Y1254107D03*
X373835Y1259403D03*
X376345Y1259373D03*
X387478Y1248967D03*
X387358Y1254137D03*
X387117Y1256851D03*
X387418Y1251537D03*
X387117Y1259351D03*
X373835Y1261903D03*
Y1264403D03*
X376345Y1261873D03*
Y1264373D03*
X376285Y1267218D03*
X373735Y1267158D03*
X387117Y1261851D03*
X387129Y1264358D03*
X387125Y1267188D03*
X384501Y1321177D03*
X386831Y1321927D03*
X378097Y1329329D03*
X374097Y1328591D03*
X382307Y1330819D03*
X380835Y1328361D03*
X374097Y1331647D03*
X373552Y1372073D03*
X377025Y1371990D03*
X380025D03*
X373532Y1378598D03*
X373552Y1375573D03*
X380025Y1378490D03*
X377025D03*
X380025Y1375490D03*
X377025D03*
Y1381490D03*
X380025D03*
X376825Y1399386D03*
X379825D03*
X373703D03*
X379825Y1402386D03*
X376825D03*
X373703D03*
X376825Y1405386D03*
X379825D03*
X373573Y1405336D03*
X374027Y1411365D03*
X373703Y1414606D03*
X376825Y1414386D03*
X379825D03*
X376825Y1417386D03*
Y1411386D03*
X379825D03*
X373703Y1417386D03*
X376825Y1408386D03*
X379825D03*
X374307Y1408135D03*
X382489Y1428478D03*
X385667Y1433425D03*
X386827Y1429525D03*
X377830Y1534342D03*
X374900Y1534102D03*
X381120D03*
X377720Y1539862D03*
X374720D03*
X374800Y1546400D03*
X385100Y1539700D03*
X381800Y1539600D03*
X381000Y1546500D03*
X384000D03*
X378000Y1546400D03*
X387930Y1585155D03*
X384600Y1595100D03*
X382220Y1591870D03*
X374391Y1648476D03*
X385123Y1639732D03*
X378547D03*
X380170Y1660002D03*
X372640Y1662112D03*
X380077Y1654049D03*
X372009Y1682584D03*
X375430Y1676462D03*
X376610Y1688252D03*
X396380Y62742D03*
X402100Y62632D03*
X399240Y62722D03*
X404910Y62562D03*
X388735Y117322D03*
X395980Y148272D03*
X388965Y215067D03*
X388720Y218362D03*
X394720Y206362D03*
X402700Y234167D03*
X392616Y252162D03*
X396294Y281585D03*
X392083Y290954D03*
X404215Y291140D03*
X398720Y321202D03*
X398661Y323761D03*
X390876Y365640D03*
X390843Y378439D03*
X403875Y365640D03*
X404120Y378439D03*
X404291Y391433D03*
X391149Y404304D03*
X403720Y405552D03*
X388720Y430862D03*
X403220Y436362D03*
X395520Y448362D03*
X400080Y472652D03*
X402500Y495362D03*
X394500Y522862D03*
X400589Y575236D03*
X398796Y1161570D03*
Y1153070D03*
Y1170070D03*
X403738Y1249027D03*
X403618Y1254197D03*
X403498Y1256747D03*
X403678Y1251597D03*
X392538Y1248997D03*
X389928Y1251507D03*
X389988Y1248937D03*
X389868Y1254107D03*
X392298Y1256717D03*
X392418Y1254167D03*
X389627Y1256821D03*
X392478Y1251567D03*
X392238Y1259287D03*
X389627Y1259321D03*
X403438Y1259317D03*
X392220Y1264594D03*
X392228Y1261897D03*
X389627Y1261821D03*
X389639Y1264328D03*
X389635Y1267158D03*
X392185Y1267218D03*
X403385Y1267248D03*
X403378Y1261917D03*
X403390Y1264624D03*
X399935Y1317092D03*
Y1319592D03*
X389161Y1321177D03*
X391491Y1321927D03*
X392131Y1324821D03*
X396397Y1324591D03*
X394197Y1323091D03*
X396397Y1321691D03*
X400073Y1327653D03*
X403051Y1325373D03*
X394297Y1326091D03*
X392131Y1327721D03*
X396397Y1327491D03*
X400888Y1395508D03*
X392947Y1397827D03*
X390934Y1404085D03*
X401079Y1399208D03*
X400924Y1408227D03*
X400926Y1404707D03*
X392517Y1419015D03*
X400991Y1417264D03*
X390934Y1407605D03*
X390914Y1412991D03*
X403125Y1425008D03*
X390687Y1431713D03*
X390777Y1435152D03*
X394067Y1435323D03*
X401244Y1440773D03*
X396822Y1439340D03*
X396946Y1537632D03*
X396768Y1541810D03*
X404920Y1539362D03*
X396946Y1556810D03*
X391330Y1585155D03*
X404030Y1595390D03*
Y1591990D03*
X394360Y1616380D03*
X392550Y1618650D03*
X397406Y1633142D03*
X401740Y1648082D03*
X404240D03*
X404320Y1645452D03*
X401820D03*
X391563Y1640244D03*
X397406Y1636542D03*
X397400Y1641000D03*
X390180Y1668212D03*
X396824Y1673662D03*
X407970Y59612D03*
X407790Y62652D03*
X415800Y62665D03*
Y67465D03*
X419901Y117491D03*
X408284Y163662D03*
X420865Y215067D03*
X410996Y218834D03*
X420752Y239562D03*
X405139Y239908D03*
X417765Y252162D03*
X404985D03*
X417218Y291274D03*
X419920Y338162D03*
X416220Y364062D03*
X418704Y379201D03*
X416762Y367353D03*
X418540Y392163D03*
X416514Y407028D03*
X412720Y439362D03*
X417880Y461942D03*
X418520Y473562D03*
X419460Y1161570D03*
Y1153370D03*
Y1169597D03*
X406248Y1248997D03*
X408798Y1249057D03*
X408511Y1256866D03*
X406001Y1256896D03*
X406128Y1254167D03*
X408678Y1254227D03*
X406188Y1251567D03*
X419638Y1248967D03*
X419295Y1256851D03*
X419518Y1254137D03*
X419578Y1251537D03*
X419295Y1259351D03*
X408738Y1251627D03*
X408523Y1259373D03*
X406013Y1259403D03*
X419295Y1261851D03*
X419307Y1264358D03*
X419285Y1267188D03*
X408523Y1264373D03*
X406013Y1264403D03*
Y1261903D03*
X408523Y1261873D03*
X405895Y1267218D03*
X408445Y1267278D03*
X416629Y1321177D03*
X418959Y1321927D03*
X410225Y1329329D03*
X406225Y1328591D03*
X414435Y1330819D03*
X412963Y1328361D03*
X406225Y1331647D03*
X418320Y1383862D03*
X422320D03*
X414333Y1385292D03*
X410933Y1384648D03*
X414909Y1395658D03*
X408915Y1402606D03*
X411150Y1408163D03*
X410912Y1418177D03*
X408968Y1410427D03*
X411162Y1414126D03*
X416926Y1426471D03*
X412416Y1431645D03*
X419861Y1429718D03*
X419302Y1434700D03*
X422708Y1437560D03*
X410074Y1424993D03*
X416999Y1441908D03*
X413599D03*
X407625Y1552572D03*
X419820Y1555862D03*
X409140Y1566892D03*
X405000Y1566670D03*
X412600Y1601000D03*
X408600Y1607400D03*
X414406Y1624992D03*
Y1628392D03*
X416020Y1620862D03*
X412456Y1649838D03*
X417960Y1650072D03*
X410700Y1655310D03*
X409857Y1682767D03*
X421320Y1671699D03*
X410249Y1673082D03*
X427120Y59862D03*
X428500Y65016D03*
Y70016D03*
X435340Y122196D03*
X428889Y121515D03*
X428883Y131015D03*
X429780Y149373D03*
Y153477D03*
Y157466D03*
Y161466D03*
X433695Y209862D03*
X421200Y232562D03*
X423145Y227862D03*
X426490Y244262D03*
X429702Y290763D03*
X425720Y319492D03*
X432380Y346522D03*
X422420Y338162D03*
X431781Y379201D03*
X434006Y365203D03*
X433596Y391163D03*
X431920Y405288D03*
X428720Y439362D03*
X437720Y435362D03*
X431570Y435512D03*
X437520Y476337D03*
X431220Y496362D03*
X434343Y504233D03*
Y509733D03*
Y498733D03*
X431220Y507143D03*
Y512623D03*
Y501643D03*
X434343Y515233D03*
Y526233D03*
Y520733D03*
X431220Y518133D03*
Y523362D03*
X434620Y535762D03*
X434343Y542733D03*
X434320Y540153D03*
X434343Y547769D03*
Y552769D03*
X421960Y1161570D03*
Y1153370D03*
Y1169597D03*
X422148Y1248937D03*
X424698Y1248997D03*
X422088Y1251507D03*
X421805Y1256821D03*
X422028Y1254107D03*
X424458Y1256717D03*
X424578Y1254167D03*
X424638Y1251567D03*
X421805Y1259321D03*
X424398Y1259287D03*
X436068Y1248967D03*
X435828Y1256687D03*
X435948Y1254137D03*
X436008Y1251537D03*
X435768Y1259257D03*
X421805Y1261821D03*
X421817Y1264328D03*
X421795Y1267158D03*
X424345Y1267218D03*
X424380Y1264594D03*
X424388Y1261897D03*
X435715Y1267188D03*
X435720Y1264564D03*
X435708Y1261857D03*
X432063Y1317092D03*
Y1319592D03*
X421289Y1321177D03*
X423619Y1321927D03*
X428525Y1321691D03*
X426325Y1323091D03*
X424259Y1324821D03*
X428525Y1324591D03*
X432628Y1327845D03*
X435179Y1325373D03*
X424259Y1327721D03*
X426425Y1326091D03*
X428525Y1327491D03*
X426320Y1383862D03*
X430320D03*
X439030Y1383692D03*
X436780Y1387387D03*
X436467Y1391687D03*
X438458Y1402169D03*
X438645Y1426890D03*
X437299Y1436774D03*
X433539Y1430613D03*
X425030Y1434292D03*
X433897Y1434670D03*
X427546Y1443411D03*
X433954Y1439029D03*
X424146Y1443411D03*
X435396Y1551810D03*
X424820Y1552605D03*
X431620Y1541362D03*
X434430Y1567562D03*
X424570Y1579466D03*
X433350Y1579509D03*
X424800Y1616600D03*
X432200Y1607060D03*
X432500Y1613822D03*
X430015Y1626608D03*
X433670Y1639562D03*
X426728Y1636495D03*
X451418Y78782D03*
X446640Y104552D03*
X446746Y152662D03*
X453028Y154864D03*
X452500Y213362D03*
Y222362D03*
X452071Y254862D03*
X442265Y290939D03*
X439120Y314562D03*
X442220Y323362D03*
X448220Y323582D03*
Y319862D03*
X446000Y339362D03*
X455000Y340362D03*
X450500Y358862D03*
X443770Y371042D03*
X451062Y397262D03*
X447490Y409052D03*
X443300Y410962D03*
X447750Y414112D03*
X453020Y414262D03*
X449420Y424162D03*
X451520Y475837D03*
X442520Y476337D03*
X453680Y515072D03*
X451320Y533562D03*
X448276Y1161570D03*
X445776D03*
X443276D03*
X445776Y1153370D03*
X448276D03*
X443276D03*
X448276Y1170069D03*
X445776D03*
X443276D03*
X441128Y1248997D03*
X438578Y1248937D03*
X438518Y1251507D03*
X440858Y1256866D03*
X438348Y1256896D03*
X441008Y1254167D03*
X438458Y1254107D03*
X441068Y1251567D03*
X440870Y1259373D03*
X438360Y1259403D03*
X451642Y1256851D03*
X451878Y1254107D03*
X451642Y1259351D03*
X451938Y1251507D03*
X451998Y1248937D03*
X438360Y1261903D03*
X440870Y1261873D03*
Y1264373D03*
X438360Y1264403D03*
X438225Y1267158D03*
X440775Y1267218D03*
X451642Y1261851D03*
X451654Y1264358D03*
X451645Y1267158D03*
X448757Y1321177D03*
X451087Y1321927D03*
X442353Y1329329D03*
X438353Y1328591D03*
X446563Y1330819D03*
X445091Y1328361D03*
X438353Y1331647D03*
X443842Y1389106D03*
X448020Y1391862D03*
X443424Y1397869D03*
X439391Y1398266D03*
X441369Y1394260D03*
X451048Y1404914D03*
X447110Y1403812D03*
X448114Y1396812D03*
X445339Y1415731D03*
X446230Y1407722D03*
X445230Y1411719D03*
X445723Y1419730D03*
X443850Y1423404D03*
X451080Y1433740D03*
X440164Y1433982D03*
X445294Y1430415D03*
X443715Y1436052D03*
X452520Y1564862D03*
X448328Y1582476D03*
X446020Y1570412D03*
X452020Y1580412D03*
X448740Y1574862D03*
X444458Y1602654D03*
X437383Y1602629D03*
X454661Y1609235D03*
X442974Y1615615D03*
X448181Y1614401D03*
X443800Y1610712D03*
X449940Y1647412D03*
X447090Y1647472D03*
X444940Y1641842D03*
X438340Y1652266D03*
X441740D03*
X462620Y120948D03*
X462320Y115948D03*
X453346Y149864D03*
X461900Y215244D03*
X466300Y217803D03*
X461900Y222921D03*
X466300Y225480D03*
X468323Y254562D03*
X465236Y296973D03*
X461736Y301098D03*
Y306098D03*
X463198Y311587D03*
X465000Y340362D03*
X456660Y359172D03*
X460800Y358962D03*
X467211Y371902D03*
X459220Y393762D03*
X463500Y383562D03*
X455720Y404762D03*
X458600Y414262D03*
X465421Y428078D03*
X456520Y476337D03*
X461520D03*
X453727Y518036D03*
X457456Y522516D03*
X470880Y572692D03*
X467130Y600122D03*
X456818Y1256687D03*
X454388Y1254077D03*
X454152Y1256821D03*
X456998Y1251537D03*
X456758Y1259257D03*
X454152Y1259321D03*
X468258Y1249107D03*
X468018Y1256827D03*
X468138Y1254277D03*
X468198Y1251677D03*
X467958Y1259397D03*
X457058Y1248967D03*
X454508Y1248907D03*
X454448Y1251477D03*
X456938Y1254137D03*
X456705Y1267188D03*
X454155Y1267128D03*
X456748Y1261867D03*
X456740Y1264564D03*
X454152Y1261821D03*
X454164Y1264328D03*
X467905Y1267328D03*
X467910Y1264704D03*
X467898Y1261997D03*
X464191Y1317092D03*
Y1319592D03*
X453417Y1321177D03*
X455747Y1321927D03*
X458453Y1323091D03*
X460653Y1321691D03*
Y1324591D03*
X456387Y1324821D03*
X464191Y1327793D03*
X467307Y1325373D03*
X458553Y1326091D03*
X460653Y1327491D03*
X456387Y1327721D03*
X459550Y1401348D03*
X465947Y1398355D03*
X459321Y1393009D03*
Y1396409D03*
X458441Y1414893D03*
X468880Y1418400D03*
X456619Y1431189D03*
X463140Y1451562D03*
X463207Y1547543D03*
X453595Y1551470D03*
X459520Y1546962D03*
X466905Y1567847D03*
X467400Y1556700D03*
X460020Y1580412D03*
X457220Y1584020D03*
X466520Y1574862D03*
X457220Y1603562D03*
X460200Y1589900D03*
X456510Y1614472D03*
X469488Y1607362D03*
X460910Y1629172D03*
Y1625772D03*
X455681Y1622492D03*
X458978Y1634481D03*
X463344Y1637622D03*
X469580Y1640272D03*
X468040Y1651657D03*
X466460Y1672332D03*
X466180Y1678392D03*
X481880Y147069D03*
X481246Y161364D03*
X476220Y158772D03*
X470900Y234787D03*
X486800Y259162D03*
X478500Y258862D03*
X474736Y302098D03*
X478995Y293787D03*
X479736Y303598D03*
Y308598D03*
X486720Y360862D03*
X482720D03*
X475508Y359266D03*
X476585Y370727D03*
X472720Y391362D03*
X485020Y414162D03*
X471920Y416687D03*
X474169Y476196D03*
X479169D03*
X474044Y503725D03*
X478510Y602942D03*
X472960Y602152D03*
X482780Y607012D03*
X473698Y1161570D03*
X471198D03*
X473698Y1153370D03*
X471198D03*
X473698Y1170070D03*
X471198D03*
X473318Y1249137D03*
X470768Y1249077D03*
X473035Y1256866D03*
X470525Y1256896D03*
X473198Y1254307D03*
X470648Y1254247D03*
X473258Y1251707D03*
X470708Y1251647D03*
X473047Y1259373D03*
X470537Y1259403D03*
X484098Y1248997D03*
X483819Y1256851D03*
X483978Y1254167D03*
X484038Y1251567D03*
X483819Y1259351D03*
X472965Y1267358D03*
X470415Y1267298D03*
X470537Y1261903D03*
X473047Y1261873D03*
Y1264373D03*
X470537Y1264403D03*
X483819Y1261851D03*
X483831Y1264358D03*
X483745Y1267218D03*
X480885Y1321177D03*
X485545D03*
X483215Y1321927D03*
X474481Y1329329D03*
X470481Y1328591D03*
X478691Y1330819D03*
X477219Y1328361D03*
X470481Y1331647D03*
X483560Y1401712D03*
X474983Y1400385D03*
X485141Y1405430D03*
X481997Y1409955D03*
X470987Y1409965D03*
X484921Y1413246D03*
X470890Y1435838D03*
X478449Y1448158D03*
X482633Y1449091D03*
Y1446091D03*
X470111Y1548269D03*
X483348Y1548062D03*
X475110Y1548112D03*
X477968Y1548122D03*
X480848Y1548120D03*
X486210Y1547960D03*
X482400Y1558320D03*
X472220Y1626732D03*
X472210Y1622735D03*
X477905Y1663242D03*
Y1659242D03*
X475150Y1654302D03*
X477835Y1677462D03*
X488748Y72264D03*
X499580Y78442D03*
X489730Y76132D03*
X498330Y96112D03*
X498730Y128592D03*
X498700Y212685D03*
Y220362D03*
X503100Y215244D03*
X500925Y231262D03*
X503100Y222921D03*
X496028Y258590D03*
X499096Y252462D03*
X489091Y293787D03*
X498636Y296273D03*
X495136Y300398D03*
Y305398D03*
X486861D03*
X495036Y310398D03*
X486710Y313582D03*
X492150Y336810D03*
X498720Y360862D03*
X490720D03*
Y368862D03*
X489520Y411862D03*
X494020Y414262D03*
X492970Y409252D03*
X502070Y427937D03*
X488169Y475696D03*
X493169Y476196D03*
X498169D03*
X486500Y556212D03*
X491043Y550447D03*
X486608Y1248967D03*
X489158Y1249027D03*
X486329Y1256821D03*
X486488Y1254137D03*
X488918Y1256747D03*
X489038Y1254197D03*
X486548Y1251537D03*
X489098Y1251597D03*
X486329Y1259321D03*
X488858Y1259317D03*
X500228Y1259237D03*
X486329Y1261821D03*
X486341Y1264328D03*
X488840Y1264624D03*
X488848Y1261927D03*
X488805Y1267248D03*
X486255Y1267188D03*
X500138Y1269637D03*
X500150Y1272344D03*
X500198Y1267037D03*
Y1264467D03*
X500168Y1261807D03*
X500150Y1275224D03*
Y1278104D03*
X487875Y1321927D03*
X492878Y1322618D03*
X490678Y1324018D03*
X496319Y1330493D03*
Y1333043D03*
X499435Y1338799D03*
X488539Y1325772D03*
X492878Y1325518D03*
X488539Y1328672D03*
X490778Y1327018D03*
X492878Y1328418D03*
X496319Y1341264D03*
X491089Y1446091D03*
Y1449091D03*
X499489D03*
Y1446091D03*
X489230Y1643592D03*
X516236Y92948D03*
X513586Y92799D03*
X510600Y92782D03*
X517290Y104252D03*
X513700Y117862D03*
X510900Y111962D03*
X503270Y128592D03*
X507320D03*
X515690Y147852D03*
X519010Y147912D03*
X518186Y139821D03*
X519236Y202404D03*
X518670Y219192D03*
X512500Y209862D03*
Y223362D03*
X508500Y232862D03*
X508000Y241862D03*
X508502Y298813D03*
X503040Y287928D03*
X508500Y303362D03*
X508136Y309398D03*
X502239Y315404D03*
X507160Y332452D03*
X510720Y360862D03*
X514720D03*
X502720D03*
X506720Y368862D03*
X509720Y390362D03*
X513720D03*
X505720Y398362D03*
X502260Y397742D03*
X511320Y437962D03*
X513444Y457522D03*
X516970Y592942D03*
X504135Y615612D03*
X505398Y1259377D03*
X502858Y1259257D03*
X502718Y1271417D03*
X505218Y1271447D03*
X505290Y1267254D03*
X505338Y1261947D03*
X505278Y1264547D03*
X502750Y1267134D03*
X502798Y1261827D03*
X502738Y1264427D03*
X502718Y1274114D03*
X505218Y1274144D03*
X515898Y1271447D03*
X515950Y1274144D03*
X505220Y1280054D03*
X502718Y1276994D03*
X505218Y1277024D03*
X502680Y1280054D03*
X515960D03*
X515950Y1277024D03*
X513013Y1334603D03*
X517673D03*
X515343Y1335353D03*
X506609Y1342755D03*
X502609Y1342017D03*
X510819Y1344245D03*
X509347Y1341787D03*
X502609Y1345073D03*
X509246Y1420002D03*
X505777Y1425579D03*
X507964Y1448979D03*
Y1445979D03*
X529720Y30792D03*
Y43054D03*
X534720Y42922D03*
X533915Y59822D03*
X523978Y59074D03*
X529078Y59282D03*
X527520Y69633D03*
X528590Y72922D03*
X518450Y101602D03*
X527310Y98147D03*
Y94747D03*
X527160Y129243D03*
X523220Y170362D03*
X534765Y161067D03*
X526920Y161362D03*
X529507Y202448D03*
X522337Y202404D03*
X531298Y284280D03*
X536420Y309422D03*
X523682Y307541D03*
Y304541D03*
X526980Y322582D03*
X521820Y336762D03*
X531720Y360862D03*
X527720D03*
X523670Y368892D03*
X525720Y390362D03*
X529720D03*
X521720Y398362D03*
X532650Y446396D03*
Y442376D03*
X521885Y452442D03*
X532650Y450330D03*
Y454270D03*
X533410Y475932D03*
X525820Y473662D03*
X524425Y489112D03*
Y495112D03*
X519520Y484027D03*
X522805Y482155D03*
X531258Y505473D03*
X521561Y505969D03*
Y500469D03*
Y511469D03*
X524220Y505862D03*
Y500362D03*
Y511362D03*
X521561Y516969D03*
Y522469D03*
X536000Y520362D03*
X524220Y516862D03*
X524720Y525293D03*
Y519743D03*
X521561Y527969D03*
Y539819D03*
X524920D03*
X524820Y545319D03*
X523699Y571545D03*
X528500Y566722D03*
X523890Y592387D03*
X531472Y579750D03*
X521118Y1273097D03*
X518488Y1271477D03*
X521058Y1275667D03*
X518490Y1274144D03*
X521058Y1278277D03*
X521020Y1280974D03*
X518500Y1280054D03*
X518490Y1277024D03*
X530398Y1288557D03*
X530548Y1283377D03*
X530428Y1285947D03*
X530410Y1291254D03*
X532558Y1289967D03*
X532618Y1287367D03*
X532678Y1284797D03*
X530450Y1297014D03*
Y1294134D03*
X532570Y1295554D03*
Y1298434D03*
Y1292674D03*
X525008Y1336287D03*
X520643Y1338247D03*
X522809Y1339517D03*
X522783Y1334882D03*
X520643Y1341147D03*
X520003Y1335353D03*
X528447Y1353316D03*
Y1355816D03*
X524892Y1341462D03*
X522818Y1342930D03*
X528929Y1364212D03*
X531563Y1361597D03*
X539720Y30792D03*
X534720D03*
X542050Y47452D03*
X539720Y42862D03*
X550971Y42902D03*
X544720Y42892D03*
X548609Y48082D03*
X537315Y59822D03*
X541002Y71436D03*
X544402D03*
X548070Y79372D03*
X542460Y99172D03*
X539475Y118772D03*
X547395Y147302D03*
X543083Y146338D03*
X540460Y200392D03*
X544390Y236512D03*
X550390Y231742D03*
X548390Y236512D03*
X546390Y231742D03*
X542050Y231722D03*
X539639Y271972D03*
X539830Y274912D03*
X537720Y278212D03*
X547420Y306862D03*
X544920D03*
X549220Y339687D03*
X535720Y360862D03*
X546758Y360502D03*
X547810Y414472D03*
X549670Y419892D03*
X542870Y438320D03*
X548464Y456534D03*
X548780Y475932D03*
X548550Y480382D03*
X546210Y519642D03*
X541820Y575130D03*
X541722Y568054D03*
X537730Y577440D03*
X547020Y590332D03*
X550320Y583362D03*
X536626Y590500D03*
X537560Y598102D03*
X537648Y1290037D03*
X535058Y1290007D03*
X535148Y1287397D03*
X543660Y1302934D03*
X541100D03*
X538560D03*
X535110Y1292704D03*
Y1295584D03*
Y1298464D03*
X537650Y1292704D03*
X540210D03*
X537650Y1298464D03*
Y1295584D03*
X540210Y1298464D03*
Y1295584D03*
X536020Y1302904D03*
X545141Y1357401D03*
X549801D03*
X538737Y1365553D03*
X534737Y1364815D03*
X542947Y1367043D03*
X541475Y1364585D03*
X534737Y1367871D03*
X547471Y1358151D03*
X563482Y40826D03*
X554720Y32862D03*
X565184Y47982D03*
X558058Y46352D03*
X554983Y45312D03*
X553650Y48842D03*
X551470Y79372D03*
X567865Y92656D03*
X559000Y102862D03*
X561000Y98862D03*
X552395Y134340D03*
X566500Y125097D03*
X551231Y122671D03*
X564890Y142173D03*
X555220Y164787D03*
X555545Y156462D03*
X555195Y184862D03*
Y171862D03*
X554872Y196635D03*
X559400Y201162D03*
X557248Y198909D03*
X564600Y202662D03*
X552489Y212022D03*
X553402Y231292D03*
X552089Y253202D03*
Y257202D03*
X562461Y272161D03*
X561324Y301149D03*
X566730Y300992D03*
X555520Y309827D03*
X563790Y331846D03*
X561290D03*
X558790D03*
X562200Y419412D03*
X559300Y414112D03*
X559730Y434772D03*
X557829Y454479D03*
X558220Y459362D03*
X563281Y543113D03*
X563700Y538477D03*
X560640Y540613D03*
X566140Y554972D03*
Y551472D03*
X559927Y548457D03*
X556820Y570462D03*
X557430Y583572D03*
X566510Y1352217D03*
X554837Y1359315D03*
X557037Y1363715D03*
Y1357915D03*
Y1360815D03*
X554937Y1362315D03*
X552771Y1361045D03*
Y1363945D03*
X552131Y1358151D03*
X555057Y1449395D03*
X572500Y32862D03*
X568500D03*
X581500Y41862D03*
X573190Y42912D03*
X567507Y45869D03*
X575330Y47672D03*
X570208Y47982D03*
X579930Y72052D03*
X577300Y66682D03*
X577880Y75442D03*
X570150Y102862D03*
X579080Y119402D03*
X573360Y140532D03*
X573115Y161232D03*
X569470Y171702D03*
X581120Y155062D03*
X568245Y167112D03*
X579481Y198378D03*
X579170Y190092D03*
X579481Y194378D03*
Y206378D03*
X578450Y218562D03*
X579245Y221362D03*
X567730Y225362D03*
X578390D03*
X567730Y221362D03*
X581755Y236978D03*
X575359Y265132D03*
X582510Y296657D03*
X577676Y300268D03*
X577480Y303822D03*
X582510Y304052D03*
Y311571D03*
X570440Y331930D03*
X567630Y331958D03*
X574800Y322462D03*
X571830Y348772D03*
X572360Y351962D03*
X571720Y381862D03*
X575050Y383602D03*
X577720Y381862D03*
X574491Y376549D03*
X580370Y383670D03*
X581090Y426970D03*
X571930Y421232D03*
X571110Y442656D03*
X569490Y437600D03*
X571110Y446706D03*
X567320Y454962D03*
Y459962D03*
Y457462D03*
X577220Y449462D03*
X578920Y466462D03*
X583045Y488212D03*
X583220Y493212D03*
X568840Y501046D03*
X584173Y498422D03*
X568520Y504162D03*
Y506662D03*
X577470Y505592D03*
X578925Y516846D03*
X571627Y548124D03*
X569050Y578292D03*
X572057Y577242D03*
X571555Y1352487D03*
X570645Y1361358D03*
X576220Y1423862D03*
X571620Y1424492D03*
X584950Y54842D03*
X586260Y52222D03*
X599800Y43152D03*
X597955Y48047D03*
X593369Y45682D03*
X586600Y60602D03*
X590680Y83591D03*
X592307Y94262D03*
X597287D03*
X594720Y97220D03*
X588245Y132142D03*
X598410Y124102D03*
X598390Y126802D03*
X589690Y161732D03*
X592220Y173862D03*
X596795Y179287D03*
X590281Y180698D03*
X599720Y184887D03*
X593220D03*
X584795Y233362D03*
X591310Y219582D03*
X592220Y249362D03*
X595415Y246515D03*
X591727Y285862D03*
X593763Y293999D03*
X588850Y291622D03*
X599620Y314762D03*
X595520Y314862D03*
X583820Y314662D03*
X590820Y330962D03*
X590720Y327862D03*
Y324582D03*
X590470Y319192D03*
X593120Y342782D03*
X583685Y363271D03*
X586185D03*
X586070Y352302D03*
X591839Y426112D03*
X595380Y416660D03*
X591720Y433937D03*
X595520Y439762D03*
X597220Y458688D03*
X599080Y448062D03*
X584100Y477952D03*
X592520Y467662D03*
X590210Y484132D03*
X599645Y479862D03*
X598661Y486922D03*
X587100Y493842D03*
X592400Y479162D03*
X591070Y504900D03*
X594090Y501957D03*
X587100Y496342D03*
X591425Y522337D03*
X591500Y516862D03*
X596880Y534812D03*
X592340Y744624D03*
X598693Y742072D03*
X611810Y34400D03*
X612822Y43232D03*
X606880Y44682D03*
X614400Y46012D03*
X603063Y48023D03*
X606020Y84562D03*
X615220Y76862D03*
X615170Y73812D03*
X601220Y73862D03*
Y76862D03*
X603720Y98362D03*
X608620Y94162D03*
X617585Y97257D03*
X613020Y94162D03*
X617409D03*
X603880Y93902D03*
X600220Y96862D03*
X614384Y119342D03*
X606040Y153432D03*
X606190Y144002D03*
X602580Y151052D03*
X603019Y146399D03*
X615573Y179484D03*
X615572Y176442D03*
X611381Y200378D03*
Y209878D03*
X614200Y265792D03*
X605350Y293092D03*
X605870Y298172D03*
X605560Y303372D03*
X607590Y314732D03*
X609040Y317282D03*
X615635Y317637D03*
X614130Y328762D03*
X605305Y331162D03*
X615180Y336812D03*
X605898Y372984D03*
X609690Y402812D03*
X605220Y416362D03*
X610720Y436362D03*
X600800Y430900D03*
X614220Y436362D03*
X610720Y442862D03*
X614220D03*
Y447862D03*
X602910Y461862D03*
X610720Y457862D03*
X614220D03*
X610720Y452862D03*
X604360Y452120D03*
X614220Y467862D03*
Y472862D03*
Y477862D03*
X605469Y467562D03*
X610720Y462862D03*
X614220D03*
X601220Y486922D03*
X600645Y504362D03*
X606200Y510862D03*
X611870Y512560D03*
X606220Y517762D03*
X607328Y537481D03*
X610797Y537528D03*
X607720Y550862D03*
X610720D03*
X613220Y654662D03*
X603276Y741375D03*
X600460Y744912D03*
X613047Y741492D03*
X602768Y758385D03*
X616675Y31777D03*
X624633Y49193D03*
X629820Y42562D03*
Y45062D03*
X619562Y49193D03*
X624140Y46672D03*
X622271Y44782D03*
X629000Y67362D03*
X628590Y58622D03*
X622271Y57952D03*
X623300Y95762D03*
X620540Y100112D03*
X632300Y104472D03*
X626699Y119182D03*
X630951D03*
X631290Y153702D03*
X615970Y161522D03*
X628195Y175914D03*
X628194Y172872D03*
X628730Y216472D03*
X631730D03*
X628730Y220472D03*
Y224472D03*
X631730Y220472D03*
Y224472D03*
X622730Y230362D03*
X630795Y236862D03*
X618470Y265732D03*
X629564Y253127D03*
X621060Y271066D03*
X633150Y301457D03*
X627950Y298897D03*
X627600Y309134D03*
X632143Y306575D03*
X630220Y314362D03*
X623365Y316742D03*
X631146Y317768D03*
X619474Y331162D03*
X619100Y374638D03*
X621720Y373362D03*
X622490Y402162D03*
X628500Y402362D03*
X624220Y411362D03*
X629220D03*
X623220Y426362D03*
X625500Y421362D03*
X629220D03*
Y426362D03*
X628900Y431050D03*
X625620Y447862D03*
X625900Y431050D03*
X625620Y442862D03*
X629220D03*
X622220D03*
X617220Y436362D03*
X622220Y452862D03*
Y447862D03*
X629220Y457862D03*
X626400Y462812D03*
X625620Y457862D03*
X622220D03*
X629220Y452862D03*
X625620D03*
X629220Y447862D03*
X626390Y467882D03*
X626210Y478002D03*
X626310Y472902D03*
X629220Y462862D03*
X622220D03*
X622520Y467862D03*
X629220Y487310D03*
X622860D03*
X626720Y482880D03*
X623670Y507862D03*
X629480Y508862D03*
X633000Y508700D03*
X629920Y516652D03*
X623000Y546900D03*
X629220Y643462D03*
X626720D03*
X617252Y739354D03*
X623497Y748235D03*
X626017Y745083D03*
X620870Y762072D03*
X617940Y763552D03*
X630417Y757135D03*
X628970Y1670880D03*
X637220Y31462D03*
X643880Y42142D03*
X647447Y46322D03*
X641200Y46762D03*
X638500Y57362D03*
X635000D03*
X637000Y68142D03*
X634500Y73422D03*
X645330Y77132D03*
Y72972D03*
X640220Y85542D03*
X634690D03*
X647220Y96929D03*
X639901Y103462D03*
X640000Y108542D03*
X639970Y113892D03*
X640130Y166362D03*
X643170Y171362D03*
X649870Y181942D03*
X645263Y235689D03*
X640295Y234237D03*
X645109Y249202D03*
Y260202D03*
X643800Y294327D03*
Y298297D03*
Y306547D03*
Y302247D03*
X645990Y314482D03*
X643800Y310962D03*
X633350Y314362D03*
X647100Y357372D03*
X636075Y389862D03*
X649075Y389937D03*
X632620Y389862D03*
X645925Y389937D03*
X638700Y400962D03*
X647700Y399162D03*
X643500Y400962D03*
X643940Y411482D03*
X637220Y411362D03*
X644220Y426362D03*
X640720Y418862D03*
X644220Y421362D03*
X637220Y416362D03*
Y426362D03*
X637195Y421362D03*
X647420Y434162D03*
X640720Y431362D03*
X644000Y438862D03*
X644220Y431362D03*
X638250Y439250D03*
X637220Y431362D03*
X644220Y452862D03*
X640820Y457902D03*
X637220Y452862D03*
X640720D03*
X640920Y447862D03*
X644220D03*
X637195Y457862D03*
X637220Y467862D03*
Y472862D03*
Y477862D03*
X644220D03*
Y462862D03*
X641235Y477377D03*
X640798Y472934D03*
X637220Y462862D03*
X640820Y467862D03*
X640620Y483422D03*
X642580Y508172D03*
X645220Y504362D03*
X646815Y517974D03*
X648296Y528255D03*
X637020Y522362D03*
X642630Y517870D03*
X640130D03*
X633147Y758595D03*
X647725Y1643719D03*
X643725Y1643467D03*
X648225Y1658482D03*
X642725Y1658562D03*
X635410Y1664220D03*
X637540Y1669480D03*
X636702Y1677610D03*
X645725Y1691182D03*
X640725Y1691452D03*
X650725Y1690682D03*
X646225Y1708169D03*
X642225Y1708457D03*
X648220Y1716912D03*
X636160Y1710662D03*
X639745Y1722362D03*
Y1718362D03*
X648220Y1722921D03*
X651943Y33535D03*
X663543Y43328D03*
X656950Y59012D03*
X651680Y73812D03*
X656500Y69662D03*
X661587D03*
X661600Y75562D03*
X657165Y79131D03*
X656426Y75431D03*
X652320Y123362D03*
X662498Y124960D03*
X650790Y149871D03*
Y140699D03*
X662880Y149912D03*
Y146912D03*
X651730Y177212D03*
X662560Y214152D03*
X662780Y210362D03*
Y205362D03*
Y207862D03*
X659880Y210762D03*
Y205762D03*
Y208262D03*
X650705Y270947D03*
X662891Y357442D03*
X662680Y354362D03*
X651520Y378662D03*
X658720Y399862D03*
X652000Y402362D03*
X653100Y407862D03*
X655820Y452662D03*
X655800Y461432D03*
X652195Y457862D03*
X655820Y467662D03*
X663000Y489500D03*
X663014Y493860D03*
X655220Y486862D03*
X661865Y505334D03*
X663720Y523806D03*
X665990Y517131D03*
X661220Y526862D03*
X650794Y515039D03*
X652577Y1000775D03*
X653690Y1392362D03*
X653761Y1396300D03*
X663187Y1395170D03*
Y1397720D03*
X666303Y1403476D03*
X663687Y1407279D03*
X654540Y1427605D03*
Y1424205D03*
X661100Y1451012D03*
X662660Y1548120D03*
X663410Y1553982D03*
X664590Y1631620D03*
X663097Y1642667D03*
X651725Y1643397D03*
X656725Y1660769D03*
X663118Y1655557D03*
X663043Y1651557D03*
X663145Y1672862D03*
Y1668862D03*
X653420Y1698662D03*
X663645Y1722862D03*
X680200Y39062D03*
X677560Y40572D03*
X672250Y40812D03*
X666943Y43328D03*
X682290Y46822D03*
X670612Y47264D03*
X674012D03*
X674035Y74522D03*
X678050Y58157D03*
X673987Y87662D03*
X677820Y89462D03*
X680578Y75992D03*
X674540Y80652D03*
X670800Y85932D03*
X667940Y80142D03*
X671320Y91192D03*
X677790Y104880D03*
X673720Y110362D03*
X674145Y113487D03*
X677978Y119668D03*
Y115668D03*
X675560Y117120D03*
X668300Y132400D03*
X665650Y147692D03*
X673713Y237725D03*
X674731Y359924D03*
X680600Y364282D03*
X683100Y369550D03*
X673220Y388362D03*
X675295Y399862D03*
X670720D03*
X668695Y408362D03*
Y404262D03*
X665870Y433942D03*
X675220Y508862D03*
X680220Y495887D03*
X670220Y503837D03*
X680220Y508862D03*
X675220Y521862D03*
X670720D03*
Y516862D03*
X680220Y530362D03*
X673340Y530922D03*
X673617Y744735D03*
X669700Y746626D03*
X677887Y742121D03*
X669778Y759929D03*
X670037Y1336396D03*
X664987D03*
X667487D03*
X664987Y1338896D03*
X667487D03*
X670037D03*
Y1333896D03*
X664987D03*
X667487D03*
X664987Y1348896D03*
X667487D03*
X664987Y1346396D03*
X667487D03*
X664987Y1343896D03*
Y1341396D03*
X667487D03*
Y1343896D03*
X670037Y1341396D03*
Y1343896D03*
Y1346396D03*
Y1348896D03*
X679881Y1399280D03*
X673477Y1409386D03*
X669477Y1406694D03*
X677619Y1408887D03*
X675876Y1406619D03*
X669477Y1409415D03*
X674149Y1434149D03*
X671149D03*
X668649D03*
X674149Y1426149D03*
Y1431149D03*
Y1428649D03*
X671149Y1426149D03*
X668649D03*
X671149Y1431149D03*
X668649Y1428649D03*
Y1431149D03*
X671149Y1428649D03*
X677319Y1428359D03*
Y1433359D03*
Y1430859D03*
X682160Y1548040D03*
X665410Y1548180D03*
X679207Y1560482D03*
X678877Y1566798D03*
X678621Y1571072D03*
X678610Y1582154D03*
X666560Y1581000D03*
X678619Y1579070D03*
X666600Y1584900D03*
X678900Y1595400D03*
X678771Y1585945D03*
X666700Y1595500D03*
X678900Y1589800D03*
X666700Y1591900D03*
X678900Y1592600D03*
X666700Y1588500D03*
X679640Y1617520D03*
Y1614000D03*
X679270Y1604040D03*
X675710Y1620320D03*
X673420Y1650057D03*
X671290Y1646320D03*
X668695Y1662235D03*
X671610Y1673792D03*
X671620Y1668303D03*
X677940Y1670110D03*
X678490Y1695660D03*
X674195Y1712362D03*
X675120Y1716242D03*
X674195Y1728362D03*
X672270Y1721612D03*
X687120Y39632D03*
X692289Y40633D03*
X689940Y38952D03*
X696800Y42108D03*
X696838Y47940D03*
X683440Y42832D03*
X687344Y46940D03*
X692389Y46439D03*
X694751Y70212D03*
X690027Y70142D03*
X685780Y70022D03*
X699475Y69982D03*
X685968Y58157D03*
X694400D03*
X681980D03*
X690510Y59132D03*
X696700Y72462D03*
X692389Y72692D03*
X687664Y73202D03*
X696370Y78512D03*
X696727Y81552D03*
Y84052D03*
X681053Y104668D03*
X695720Y102162D03*
X694220Y104862D03*
X688019Y109845D03*
X687030Y113090D03*
X687034Y115896D03*
X697615Y123697D03*
X687238Y171071D03*
X685600Y364282D03*
X690600D03*
X695600D03*
X683500Y381200D03*
X685210Y388852D03*
X694920Y388797D03*
X687500Y399402D03*
X692330Y388751D03*
X685220Y391652D03*
X692402Y391250D03*
X695220Y399862D03*
X685270Y408362D03*
Y404262D03*
X692400Y404682D03*
X683320Y490662D03*
X685220Y495887D03*
X690580Y482992D03*
X694510Y482942D03*
X686120Y481862D03*
X695220Y495887D03*
X690220D03*
X695220Y508862D03*
X685220D03*
X690220Y506362D03*
X685220Y503837D03*
X690220Y508882D03*
X690330Y503530D03*
X695257Y503847D03*
X695220Y516852D03*
X685220D03*
X690220Y519662D03*
X695220D03*
X689720Y530862D03*
X695220Y530662D03*
X683457Y745175D03*
X696810Y1300162D03*
X692280Y1302532D03*
X684555Y1338896D03*
X689605Y1336396D03*
Y1338896D03*
X687105Y1336396D03*
X684555D03*
X687105Y1338896D03*
X689605Y1333896D03*
X687105D03*
X684555D03*
X689605Y1348896D03*
X687105D03*
X689605Y1346396D03*
X687105D03*
X684555Y1341396D03*
Y1343896D03*
Y1346396D03*
Y1348896D03*
X689605Y1341396D03*
Y1343896D03*
X687105Y1341396D03*
Y1343896D03*
X684541Y1399280D03*
X682211Y1400030D03*
X686871D03*
X691777Y1405594D03*
Y1399794D03*
X689577Y1401194D03*
X687511Y1402924D03*
X691777Y1402694D03*
X689677Y1404194D03*
X687511Y1405824D03*
X694596Y1396198D03*
X694129Y1420283D03*
X696754Y1419809D03*
X691129Y1420283D03*
X681899Y1434049D03*
Y1426049D03*
Y1431049D03*
Y1428549D03*
X694129Y1423303D03*
X691129D03*
X696694Y1427949D03*
Y1425449D03*
Y1430449D03*
X696784Y1422614D03*
X683930Y1552562D03*
Y1555062D03*
Y1557562D03*
X692100Y1567190D03*
X692026Y1580490D03*
X697197Y1640667D03*
X697122Y1636667D03*
X689200Y1648843D03*
X686220Y1640667D03*
X697595Y1666862D03*
X687045Y1673362D03*
X706370Y46782D03*
X701838Y42202D03*
Y47940D03*
X703900Y72112D03*
X701400D03*
X713000Y69662D03*
X697720Y58162D03*
X710200Y69662D03*
X706867Y58197D03*
X703100Y58157D03*
X712500Y79862D03*
X710486Y77695D03*
X700500Y74862D03*
X698710Y86035D03*
X705390Y85792D03*
X703000Y84862D03*
X706720Y100462D03*
X699220Y102162D03*
X702720D03*
X701220Y104862D03*
X697720D03*
X712733Y117488D03*
Y114588D03*
X712290Y106722D03*
X712340Y128093D03*
X700600Y125309D03*
X707008Y125804D03*
X705800Y167788D03*
Y171188D03*
X700600Y364282D03*
X705600D03*
X710600D03*
X709000Y354000D03*
X715600Y363900D03*
X705700Y361400D03*
X709400Y378200D03*
X713220Y378362D03*
X711200Y396500D03*
X707220Y399362D03*
X709160Y386730D03*
X713220Y388362D03*
X707400Y396200D03*
X713220Y399862D03*
X705195Y408362D03*
Y404262D03*
X705780Y411022D03*
X712770Y406822D03*
X705720Y488862D03*
X703220Y490362D03*
X705720Y484862D03*
X711220Y503842D03*
X705220D03*
Y508862D03*
X711220Y508882D03*
X710720Y521362D03*
X705220D03*
X701757Y521324D03*
X705220Y530362D03*
X710940Y591172D03*
X698602Y580536D03*
X705240Y594020D03*
X702740D03*
X712060Y638542D03*
X708680Y638812D03*
X708310Y646032D03*
X704320Y645262D03*
X704000Y740862D03*
X700500Y745862D03*
X703545Y745907D03*
X711720Y1286162D03*
X707720Y1290162D03*
X705720Y1286662D03*
X704795Y1294559D03*
X707320Y1301162D03*
X708137Y1336396D03*
Y1338896D03*
X703087Y1336396D03*
X705587D03*
Y1338896D03*
X703087D03*
X708137Y1333896D03*
X705587D03*
X703087D03*
Y1346396D03*
X705587D03*
X703087Y1348896D03*
X705587D03*
X708137Y1341396D03*
Y1343896D03*
X705587Y1341396D03*
X703087D03*
Y1343896D03*
X705587D03*
X708137Y1348896D03*
Y1346396D03*
X701330Y1395195D03*
Y1397695D03*
X704446Y1403476D03*
X701830Y1407326D03*
X711620Y1409386D03*
X707620Y1406694D03*
Y1409660D03*
X699754Y1419809D03*
X699694Y1427949D03*
Y1425449D03*
Y1430449D03*
X699784Y1422614D03*
X712222Y1570703D03*
X702112Y1571683D03*
Y1575683D03*
Y1579683D03*
X711102Y1575683D03*
X714162Y1574333D03*
X713052Y1579683D03*
X712582Y1584843D03*
X704497Y1598927D03*
X702112Y1587683D03*
Y1591683D03*
X713102Y1601307D03*
X715775Y1599024D03*
X714380Y1589960D03*
X702112Y1595683D03*
X712512Y1596338D03*
X711350Y1590720D03*
X711780Y1614590D03*
X704370Y1604580D03*
X706103Y1617107D03*
X708857Y1613462D03*
X710570Y1629890D03*
X708830Y1623115D03*
X705516Y1620296D03*
X710540Y1636070D03*
X708999Y1646762D03*
X703719Y1646768D03*
X697595Y1662862D03*
X700460Y1660918D03*
X709678Y1658485D03*
X697730Y1677460D03*
X704759Y1677001D03*
X723041Y-19800D03*
Y-23200D03*
X724620Y40062D03*
X728720Y43562D03*
X719820Y45862D03*
X717320Y44062D03*
X729293Y58062D03*
X724644Y58362D03*
X719949Y58862D03*
X715990Y69662D03*
X725740Y69580D03*
X721990Y69762D03*
X718900Y69662D03*
X727700Y60562D03*
X728591Y71960D03*
X722415Y77862D03*
X718425Y77882D03*
X728090Y75132D03*
X719100Y85262D03*
X727518Y90984D03*
X715933Y117488D03*
Y114588D03*
X729933Y108388D03*
X728733Y132088D03*
Y129288D03*
X720433Y135088D03*
X717433D03*
X728733Y126388D03*
X719933Y124488D03*
X723133D03*
X715940Y157362D03*
X718213Y159241D03*
X720633Y160788D03*
X717020Y220862D03*
X719720Y220142D03*
X722500Y365500D03*
X724897Y353887D03*
X721989Y351234D03*
X727000Y365500D03*
X731400D03*
X722500Y374100D03*
X727000D03*
X731400Y375000D03*
X718720Y381892D03*
X728220Y388362D03*
X723195Y408362D03*
Y404262D03*
X725220Y399862D03*
X723220Y508882D03*
X717220D03*
X729220D03*
Y503842D03*
X723220D03*
X717220D03*
X714000Y496132D03*
X723120Y525362D03*
X728220Y521362D03*
X717220D03*
X717296Y525407D03*
X723220Y516852D03*
X729220D03*
X717220D03*
X729212Y531700D03*
X729328Y583076D03*
X729295Y586113D03*
X725207Y579371D03*
X722707D03*
X715860Y585540D03*
X714320Y597462D03*
X723450Y597072D03*
X720240Y598292D03*
X715420Y639162D03*
X719190Y646642D03*
X717720Y643262D03*
X715220D03*
X723340Y642922D03*
X714087Y745865D03*
X720697Y765862D03*
X723460Y1245632D03*
X714720Y1286162D03*
X723054Y1333896D03*
X725604D03*
X728104D03*
X725604Y1338896D03*
X723054Y1336396D03*
X725604D03*
X728104Y1338896D03*
Y1336396D03*
X723054Y1338896D03*
X725604Y1346396D03*
X728104D03*
X725604Y1348896D03*
X728104D03*
X725604Y1343896D03*
Y1341396D03*
X728104Y1343896D03*
Y1341396D03*
X723054Y1348896D03*
Y1346396D03*
Y1343896D03*
Y1341396D03*
X725654Y1405824D03*
Y1402924D03*
X727720Y1401194D03*
X727820Y1404194D03*
X718024Y1399280D03*
X722684D03*
X720354Y1400030D03*
X725014D03*
X715762Y1408887D03*
X714019Y1406619D03*
X717300Y1547370D03*
X715792Y1567461D03*
X720370Y1566910D03*
X723520Y1561604D03*
X724712Y1566820D03*
X716612Y1584635D03*
X717152Y1570093D03*
X728977Y1574453D03*
X717402Y1574433D03*
X724465Y1580092D03*
X722465Y1582092D03*
X726465D03*
X723942Y1574123D03*
X724465Y1590950D03*
X722465Y1588950D03*
X726465D03*
X729052Y1602518D03*
X726092Y1598483D03*
X720987Y1599568D03*
X723542Y1612702D03*
X721488Y1610945D03*
X725910Y1611900D03*
X716688Y1610055D03*
X719168Y1612016D03*
X718195Y1647300D03*
X714203Y1642926D03*
X729150Y1641690D03*
X726810Y1652430D03*
X714071Y1663842D03*
X722630Y1655740D03*
X724500Y1680400D03*
X718758Y1673800D03*
X745900Y40362D03*
X733314Y40862D03*
X740100Y41162D03*
X746100Y46262D03*
X736620Y45262D03*
X745474Y57932D03*
X733642Y58062D03*
X741377Y57932D03*
X737595D03*
X732793Y71436D03*
X736193D03*
X742620Y71762D03*
X735880Y60662D03*
X740819Y82362D03*
X736720Y101662D03*
X745035Y94632D03*
X735770Y94988D03*
X739823Y91052D03*
X741308Y108742D03*
X738600Y136600D03*
X736060Y145532D03*
X740220Y145362D03*
X745725Y167537D03*
X732720Y231362D03*
X734220Y238362D03*
X744247Y312598D03*
X741800Y363200D03*
X742090Y356082D03*
X735600Y351400D03*
X735800Y365500D03*
X732700Y351500D03*
X740200Y375100D03*
X736220Y380787D03*
X742720Y380262D03*
X735800Y375000D03*
X738220Y388362D03*
X742160Y396452D03*
X738220Y383862D03*
X745720Y399862D03*
X735220Y410842D03*
X735745Y408362D03*
Y404262D03*
X733720Y399862D03*
X743980Y443482D03*
X740740Y473822D03*
X741420Y494162D03*
X747600Y506592D03*
X735220Y508862D03*
X745220Y503842D03*
X735220D03*
X735430Y516862D03*
X745220Y522362D03*
Y516852D03*
X730220Y523362D03*
X740840Y521982D03*
X735173Y521362D03*
X736480Y531722D03*
X738980D03*
X733922Y531712D03*
X733117Y580071D03*
Y582571D03*
X733134Y585672D03*
X736710Y603842D03*
Y607242D03*
X735620Y613862D03*
X730690Y655532D03*
X744538Y746524D03*
X737609Y744282D03*
X730889Y746834D03*
X740820Y741762D03*
X729920Y1405594D03*
X732226Y1396212D03*
X729920Y1399794D03*
Y1402694D03*
X733336Y1568341D03*
Y1565341D03*
Y1559341D03*
Y1562341D03*
X730336Y1559341D03*
Y1562341D03*
X745336D03*
Y1559341D03*
Y1565341D03*
Y1568341D03*
X742336Y1562341D03*
Y1559341D03*
Y1565341D03*
Y1568341D03*
X739336Y1562341D03*
Y1559341D03*
Y1565341D03*
Y1568341D03*
X736336D03*
Y1565341D03*
Y1559341D03*
Y1562341D03*
X733336Y1574341D03*
Y1571341D03*
X745336Y1574341D03*
Y1571341D03*
X742336Y1574341D03*
Y1571341D03*
X739336Y1574341D03*
Y1571341D03*
X736336D03*
Y1574341D03*
X735300Y1648760D03*
X737080Y1655820D03*
X735080Y1662980D03*
X740840Y1655590D03*
X732705Y1669450D03*
X754620Y51602D03*
X758620D03*
X749477Y57932D03*
X755700Y59942D03*
Y62442D03*
X758200Y59942D03*
Y62442D03*
X760700Y59942D03*
Y62442D03*
X747487Y71429D03*
X757693Y100653D03*
Y96423D03*
X750700Y106642D03*
X754800Y97082D03*
X750033Y92888D03*
Y89988D03*
X757340Y92562D03*
X748033Y116288D03*
X747230Y108572D03*
X760390Y111810D03*
X751220Y137864D03*
X747200Y251500D03*
X757150Y280592D03*
X758720Y283262D03*
X759920Y280562D03*
X758412Y298790D03*
X755305Y298847D03*
X748820Y284562D03*
X758390Y295450D03*
X748498Y309640D03*
X759637Y311585D03*
X757936Y303908D03*
X760670Y317432D03*
X747554Y384962D03*
X757430Y408212D03*
X760469Y442647D03*
X750290Y462162D03*
X757365Y459862D03*
X752500Y495762D03*
X757238Y483862D03*
X756642Y496522D03*
Y501744D03*
X751220Y522362D03*
Y516852D03*
X759790Y525522D03*
X755940Y516862D03*
X756650Y526072D03*
X761710Y517651D03*
X757020Y530462D03*
X759820D03*
X754220D03*
X762345Y1284542D03*
Y1287542D03*
Y1290542D03*
X762205Y1293272D03*
X757720Y1375462D03*
Y1384062D03*
X758020Y1397862D03*
X758420Y1406862D03*
X758120Y1414762D03*
X755420Y1426262D03*
Y1422862D03*
X748336Y1562341D03*
Y1559341D03*
Y1565341D03*
Y1568341D03*
X751336D03*
Y1565341D03*
Y1559341D03*
Y1562341D03*
X748336Y1574341D03*
Y1571341D03*
X760112Y1579183D03*
X749612Y1579023D03*
X749652Y1586407D03*
X760152Y1583183D03*
X749612Y1583023D03*
X760112Y1592183D03*
Y1587183D03*
X749662Y1590733D03*
X749612Y1594683D03*
X758360Y1589661D03*
X761716Y1661194D03*
X751620Y1674312D03*
X759859Y1686090D03*
X759359Y1729520D03*
X752875Y1726670D03*
X774059Y68912D03*
X773420Y143462D03*
X772328Y153728D03*
X771426Y158026D03*
X766320Y264892D03*
X763320D03*
X771630Y258102D03*
X762420Y280562D03*
X777420Y277962D03*
X769789Y296231D03*
X777467Y296315D03*
X769860Y302462D03*
X771377Y314139D03*
X771490Y354942D03*
X768490D03*
X777420Y354962D03*
X774490Y354942D03*
X765000Y354862D03*
X771960Y375162D03*
X767960Y369662D03*
X776000D03*
X764000D03*
X766195Y393212D03*
X773245Y398212D03*
X766195Y403212D03*
Y413212D03*
X773245Y403212D03*
Y408212D03*
X768910Y403260D03*
X771050Y416940D03*
X766195Y423212D03*
Y428212D03*
X768701Y418662D03*
X774982Y446908D03*
X772365Y454862D03*
X768720Y459862D03*
X765315Y454862D03*
Y459862D03*
X772365D03*
X765360Y475412D03*
X765335Y469552D03*
X772364Y475062D03*
X772365Y469862D03*
X765315Y479862D03*
X772365Y488862D03*
X776170Y493422D03*
X766510Y493452D03*
X765386Y483572D03*
X773530Y507062D03*
X765810Y506342D03*
X769745Y502600D03*
X775378Y502502D03*
X765521Y525364D03*
X769220Y530362D03*
X765720D03*
X777020D03*
X772020Y746562D03*
X774384Y744088D03*
X762562Y746444D03*
X769921Y742095D03*
X767421D03*
X764921D03*
X769337Y760775D03*
X762617Y758885D03*
X765345Y1284542D03*
X768335Y1284612D03*
X765345Y1287542D03*
Y1290542D03*
X768335Y1287612D03*
Y1290612D03*
X765205Y1293272D03*
X768195Y1293342D03*
X778005Y1294092D03*
X768520Y1384062D03*
Y1375462D03*
X768620Y1397262D03*
X775375Y1403561D03*
X767820Y1414762D03*
X763152Y1581893D03*
Y1577893D03*
Y1573793D03*
X773952Y1580493D03*
X768714Y1571203D03*
X769452Y1584393D03*
X770252Y1587268D03*
X763152Y1590893D03*
Y1594893D03*
X774052Y1590293D03*
X776922Y1590444D03*
X764920Y1695347D03*
X766880Y1689020D03*
X766603Y1721797D03*
X785180Y120947D03*
X792680D03*
X790180D03*
X787680D03*
X783940Y118637D03*
X786440D03*
X788940D03*
X781440D03*
X782553Y150031D03*
Y152531D03*
X779893Y147521D03*
Y150021D03*
X780820Y278262D03*
X785135Y274822D03*
X785200Y271400D03*
X794057Y301569D03*
X794220Y296062D03*
X785220Y284762D03*
X792943Y312642D03*
X784415Y313734D03*
X793896Y309026D03*
X793820Y304962D03*
X779120Y303410D03*
Y308755D03*
X785000Y355000D03*
X779920Y354962D03*
X782420D03*
X790120Y354862D03*
X792620D03*
X787600Y354900D03*
X795520Y393462D03*
X791075Y388000D03*
X781195Y393212D03*
X781320Y398212D03*
X787720Y408362D03*
X781195Y413212D03*
Y423212D03*
X785560Y417902D03*
X788120Y422942D03*
X791040Y422892D03*
X793660Y422842D03*
X785720Y427862D03*
X789230Y414942D03*
X780020Y441437D03*
Y445287D03*
X784730Y432682D03*
X787320Y444862D03*
Y439862D03*
X791582Y435352D03*
X781205Y454402D03*
X780315Y459862D03*
X787320Y454862D03*
Y449862D03*
Y459862D03*
X787360Y469862D03*
X786220Y464862D03*
X796315Y469290D03*
X780315Y464862D03*
X783340Y474802D03*
X782690Y488862D03*
X793220Y493362D03*
X781170Y493422D03*
X785800Y482762D03*
X793875Y483262D03*
X778670Y493422D03*
X783600Y502462D03*
X783450Y522462D03*
X783400Y511902D03*
X789720Y589862D03*
X785220Y581362D03*
X789720Y587362D03*
X791720Y593862D03*
X793720Y595862D03*
X791969Y618384D03*
X794720Y617862D03*
X783507Y761875D03*
X794157Y761295D03*
X782515Y766702D03*
X791140Y761693D03*
X792045Y1284542D03*
Y1290542D03*
Y1287542D03*
X791905Y1293272D03*
X791260Y1388662D03*
X790380Y1432132D03*
X784352Y1568293D03*
Y1565293D03*
Y1559293D03*
Y1562293D03*
X781352Y1568293D03*
Y1565293D03*
Y1559293D03*
Y1562293D03*
X793352D03*
Y1559293D03*
Y1565293D03*
Y1568293D03*
X790352Y1562293D03*
Y1559293D03*
Y1565293D03*
Y1568293D03*
X787352D03*
Y1565293D03*
Y1559293D03*
Y1562293D03*
X784352Y1574293D03*
Y1571293D03*
X781352Y1574293D03*
Y1571293D03*
X793352Y1574293D03*
Y1571293D03*
X790352Y1574293D03*
Y1571293D03*
X787352D03*
Y1574293D03*
X808800Y267900D03*
X810920Y280062D03*
X798204Y279146D03*
X797924Y298358D03*
X806450Y310362D03*
X803620Y302962D03*
X805870Y304812D03*
X799720Y300462D03*
X795920Y312662D03*
X803280Y354982D03*
X800646Y354921D03*
X795220Y354862D03*
X806000Y360600D03*
X798400D03*
X805910Y355012D03*
X797900Y354800D03*
X795520Y398212D03*
X800352Y408389D03*
X803120Y428762D03*
X797720Y428412D03*
X798370Y439932D03*
X802010Y439940D03*
X802790Y433832D03*
X795320Y439862D03*
X805720Y432902D03*
X801750Y444330D03*
X795320Y444862D03*
X810860Y454862D03*
X802810D03*
X795320D03*
Y449862D03*
X802810Y464862D03*
Y449862D03*
X810860Y459862D03*
X802810D03*
X795320D03*
X810860Y449862D03*
X798990Y474862D03*
X802865D03*
X795320Y464862D03*
X810815Y474862D03*
X810860Y464862D03*
X810815Y469862D03*
X807220Y493362D03*
X801940Y485932D03*
X804510Y486122D03*
X809510D03*
X799230Y485922D03*
X812510Y486422D03*
X802790Y495652D03*
X805470Y510522D03*
X807640Y506672D03*
X808100Y509900D03*
X797420Y512503D03*
X805445Y587582D03*
X810720Y586862D03*
X811143Y605265D03*
X807945Y594362D03*
X803220D03*
X797200Y599883D03*
X795720Y614862D03*
X796702Y761195D03*
X810850Y770272D03*
X799577Y760985D03*
X807000Y757562D03*
X798035Y1284612D03*
X795045Y1284542D03*
X798035Y1290612D03*
Y1287612D03*
X795045Y1290542D03*
Y1287542D03*
X797895Y1293342D03*
X794905Y1293272D03*
X806323Y1343076D03*
X812130Y1343022D03*
X809210Y1343062D03*
X804100Y1435010D03*
X800000Y1431100D03*
X799352Y1562293D03*
Y1559293D03*
Y1565293D03*
Y1568293D03*
X796352Y1562293D03*
Y1559293D03*
Y1565293D03*
Y1568293D03*
X799352Y1574293D03*
Y1571293D03*
X796352Y1574293D03*
Y1571293D03*
X804652Y1581793D03*
Y1573793D03*
X812652Y1577793D03*
X801652Y1584539D03*
X812698Y1587047D03*
X804652Y1597793D03*
Y1585993D03*
X799152Y1586507D03*
X804652Y1589793D03*
Y1609793D03*
X827114Y115223D03*
X823114D03*
X814570Y145952D03*
X814531Y139851D03*
X820900Y147112D03*
X815060Y280072D03*
X813490Y273862D03*
X816220Y277162D03*
X813293Y287062D03*
X826300Y311962D03*
X823800D03*
X818000Y378800D03*
X813210Y374292D03*
X815710D03*
X825003Y389012D03*
Y397276D03*
X819220Y397664D03*
X824980Y413260D03*
X819220Y412264D03*
X823600Y421194D03*
X815310Y440100D03*
X816810Y464862D03*
X825100Y468900D03*
X824860Y464862D03*
X816400Y472900D03*
X820720Y493862D03*
X822415Y479600D03*
X821720Y511082D03*
X814305Y499503D03*
X819320Y502347D03*
X821720Y527082D03*
X815650Y516807D03*
X821720Y515082D03*
Y523082D03*
X820220Y586862D03*
X814220Y582530D03*
X823720Y594862D03*
X820470Y595112D03*
X815120Y593582D03*
X820613Y744641D03*
X823589Y746924D03*
X822374Y757039D03*
X814770Y763874D03*
X815789Y1008845D03*
X826090Y1334362D03*
Y1339362D03*
Y1329362D03*
Y1344362D03*
X820920Y1344342D03*
X818420D03*
X823352Y1565293D03*
Y1562293D03*
Y1559293D03*
Y1568293D03*
X826352Y1565293D03*
Y1562293D03*
Y1559293D03*
Y1568293D03*
X823352Y1571293D03*
Y1574293D03*
X826352Y1571293D03*
Y1574293D03*
X815652Y1582570D03*
Y1573793D03*
X813352Y1590893D03*
X812652Y1593793D03*
X815551D03*
X818652Y1590444D03*
X812652Y1605793D03*
Y1601793D03*
X840001Y6800D03*
Y10200D03*
X836779Y68008D03*
X828600Y61752D03*
X839898Y87248D03*
X841584Y94181D03*
X837250Y93221D03*
X839360Y114862D03*
X835114Y115223D03*
X845220Y135862D03*
Y129362D03*
X829114Y147123D03*
X828145Y160362D03*
X838220Y163862D03*
X835220D03*
X837320Y175112D03*
X842720Y181360D03*
X837160Y218212D03*
Y213207D03*
X844526Y204968D03*
X838820Y206872D03*
X837500Y229642D03*
X840063Y285022D03*
X839450Y272662D03*
X835400Y268800D03*
X829620Y280345D03*
X829820Y275045D03*
X840850Y278948D03*
X829720Y292762D03*
X839860Y294702D03*
X827620Y302962D03*
X830417Y311865D03*
X836300Y418800D03*
X832400Y427100D03*
X840400Y418900D03*
X831720Y457700D03*
X839640Y449612D03*
X832700Y446800D03*
X830600Y449200D03*
X838220Y459562D03*
X841200Y456500D03*
X832720Y494862D03*
X829720D03*
X838645Y492862D03*
X830870Y480010D03*
X832590Y512888D03*
X829745Y502082D03*
X832370Y525849D03*
X843287Y527817D03*
X841461Y525849D03*
X840990Y529786D03*
X828009Y587913D03*
X831705Y593877D03*
X829230Y582772D03*
X831530Y651932D03*
X830587Y741205D03*
X833120Y743392D03*
X838587Y766825D03*
X841827Y766795D03*
X837127Y758976D03*
X829420Y758422D03*
X841997Y773085D03*
X838020Y1232432D03*
X832090Y1326862D03*
Y1331862D03*
Y1336862D03*
Y1341862D03*
X829352Y1565293D03*
Y1562293D03*
Y1559293D03*
Y1568293D03*
X832352D03*
Y1565293D03*
Y1559293D03*
Y1562293D03*
X835352Y1568293D03*
Y1565293D03*
Y1559293D03*
Y1562293D03*
X838352Y1568293D03*
Y1565293D03*
Y1559293D03*
Y1562293D03*
X841352Y1568293D03*
Y1565293D03*
Y1559293D03*
Y1562293D03*
X829352Y1574293D03*
Y1571293D03*
X832352D03*
Y1574293D03*
X835352Y1571293D03*
Y1574293D03*
X838352Y1571293D03*
Y1574293D03*
X841352Y1571293D03*
Y1574293D03*
X843652Y1584539D03*
X841152Y1586507D03*
X858629Y60293D03*
X850015Y87341D03*
X843855Y87711D03*
X847472Y94754D03*
X847660Y113962D03*
X853100Y113762D03*
X854100Y132972D03*
X854220Y135862D03*
Y129362D03*
X854200Y138562D03*
X848745Y160187D03*
X848709Y156752D03*
X848360Y182872D03*
X845720Y181362D03*
X855858Y212425D03*
X855933Y215375D03*
X860050Y215310D03*
X847580Y232222D03*
X853828Y269043D03*
X850133Y271049D03*
X861865Y273730D03*
X850093Y286625D03*
X855480Y299692D03*
X856243Y286447D03*
X859920Y308852D03*
X859740Y399081D03*
X846040Y399210D03*
X846490Y422131D03*
X850610Y444352D03*
X851606Y447927D03*
X844210Y455902D03*
X846700Y476900D03*
X855200D03*
X857620Y492862D03*
X858600Y511130D03*
X848620Y509752D03*
X853070Y515447D03*
X857195Y522162D03*
X859888Y593970D03*
X859054Y583752D03*
X845523Y582126D03*
X856520Y751262D03*
X859450Y750462D03*
X844957Y763065D03*
X854620Y1242125D03*
X854237Y1250358D03*
X846652Y1581793D03*
Y1573793D03*
X854652Y1577793D03*
X857652Y1582570D03*
Y1573793D03*
X854777Y1586968D03*
X846652Y1597793D03*
X855352Y1590893D03*
X854652Y1593793D03*
X846652Y1585993D03*
X857551Y1593793D03*
X846652Y1589793D03*
X854652Y1605793D03*
Y1601793D03*
X846652Y1609793D03*
X862930Y70072D03*
X866330D03*
X862452Y151590D03*
X867620Y154362D03*
X871145Y163862D03*
X871580Y183370D03*
X875169Y185113D03*
X864859Y187110D03*
X873200Y194262D03*
X871890Y196740D03*
X877971Y196652D03*
X867528Y231788D03*
X875543Y266447D03*
X867700Y268262D03*
X875543Y269347D03*
X863747Y280870D03*
X867237Y273325D03*
X868552Y285537D03*
X874243Y287047D03*
X877322Y296051D03*
X872320Y304936D03*
X869820D03*
X867320D03*
X864820D03*
X860531Y375826D03*
X870700Y386476D03*
Y398620D03*
Y402581D03*
X868113Y409372D03*
X870513Y414276D03*
X862320Y431462D03*
X863415Y445829D03*
X860574Y445404D03*
X861080Y459742D03*
X870360Y493042D03*
X862620Y507162D03*
X868110Y499142D03*
X865290Y499032D03*
X865810Y521862D03*
X866820Y736562D03*
X863925Y737697D03*
X864680Y751582D03*
X874155Y756993D03*
X864700Y778300D03*
X868352Y1568293D03*
Y1565293D03*
Y1559293D03*
Y1562293D03*
X865352Y1568293D03*
Y1565293D03*
Y1559293D03*
Y1562293D03*
X874352D03*
Y1559293D03*
Y1565293D03*
Y1568293D03*
X871352D03*
Y1565293D03*
Y1559293D03*
Y1562293D03*
X868352Y1574293D03*
Y1571293D03*
X865352Y1574293D03*
Y1571293D03*
X874352Y1574293D03*
Y1571293D03*
X871352D03*
Y1574293D03*
X860652Y1590444D03*
X878327Y183169D03*
X876695Y171362D03*
Y176862D03*
X887520Y171362D03*
Y176862D03*
X877724Y200837D03*
X878220Y187449D03*
X888929Y209223D03*
X891620Y209662D03*
X888929Y206723D03*
X891620Y207162D03*
X884003Y278712D03*
X883870Y275802D03*
X883909Y281862D03*
X879587Y270004D03*
X883870Y272652D03*
X887338Y296760D03*
X882520Y327562D03*
X885020D03*
X887520D03*
X890422Y333879D03*
X893440Y336232D03*
X890820Y389362D03*
X890920Y386352D03*
X889453Y458926D03*
X887590Y471552D03*
X889439Y489599D03*
Y492999D03*
X881680Y504742D03*
Y508142D03*
X884512Y523800D03*
X882410Y526132D03*
X888130Y532612D03*
X891530D03*
X887810Y582442D03*
X889000Y737562D03*
X885310Y736442D03*
X886720Y741902D03*
X878192Y879910D03*
X884747Y871745D03*
X879100Y912608D03*
X884619Y916477D03*
X892317Y915872D03*
X880102Y923235D03*
X891560Y1435510D03*
X883352Y1562293D03*
Y1559293D03*
Y1565293D03*
Y1568293D03*
X880352Y1562293D03*
Y1559293D03*
Y1565293D03*
Y1568293D03*
X877352Y1562293D03*
Y1559293D03*
Y1565293D03*
Y1568293D03*
X883352Y1574293D03*
Y1571293D03*
X880352Y1574293D03*
Y1571293D03*
X877352Y1574293D03*
Y1571293D03*
X888652Y1581793D03*
Y1573793D03*
X885652Y1584539D03*
X888652Y1597793D03*
Y1585993D03*
X883152Y1586507D03*
X888652Y1589793D03*
Y1609793D03*
X908620Y188899D03*
X896620Y209662D03*
X894120D03*
Y207162D03*
X896620D03*
X906120Y261252D03*
X894770Y283062D03*
X896540Y341132D03*
X902260Y473153D03*
Y475653D03*
X903124Y470797D03*
X900020Y470672D03*
X896060Y481222D03*
Y484622D03*
X907678Y488177D03*
X895340Y497882D03*
Y501282D03*
X901829Y512730D03*
Y516130D03*
X893450Y516862D03*
X901230Y531612D03*
X904630D03*
X894897Y871745D03*
X894965Y917422D03*
X899830Y971484D03*
Y974884D03*
X907770Y1045242D03*
X894830Y1435970D03*
X907352Y1568293D03*
Y1565293D03*
Y1559293D03*
Y1562293D03*
Y1574293D03*
Y1571293D03*
X896652Y1577793D03*
X899652Y1582570D03*
Y1573793D03*
X896672Y1587073D03*
X897352Y1590893D03*
X896652Y1593793D03*
X899551D03*
X902652Y1590444D03*
X896652Y1605793D03*
Y1601793D03*
X922726Y176302D03*
X922100Y181791D03*
X917386Y184114D03*
X924920Y196199D03*
X923836Y193563D03*
X923897Y445545D03*
X927034Y445594D03*
X912984Y458135D03*
X909584D03*
X924447Y463012D03*
X921047D03*
X909190Y473392D03*
X912288Y472430D03*
X918532Y492445D03*
X927154Y492103D03*
X924623Y492097D03*
X918078Y495177D03*
X921189Y492086D03*
X918212Y497677D03*
X918131Y503330D03*
X921060Y506086D03*
X923783Y506076D03*
X918212Y500777D03*
X909984Y496330D03*
X926173Y512391D03*
X913394Y521662D03*
X916794D03*
X909600Y521162D03*
X922879Y531976D03*
Y528576D03*
X918420Y804062D03*
X909720Y798861D03*
Y794862D03*
X913720Y799362D03*
X914152Y803294D03*
X921757Y962082D03*
X916974Y962108D03*
X923930Y976652D03*
X917980Y974952D03*
X924440Y996852D03*
X914838Y985989D03*
X918720Y1009937D03*
X910352Y1568293D03*
Y1565293D03*
Y1559293D03*
Y1562293D03*
X922352D03*
Y1559293D03*
Y1565293D03*
Y1568293D03*
X919352Y1562293D03*
Y1559293D03*
Y1565293D03*
Y1568293D03*
X916352Y1562293D03*
Y1559293D03*
Y1565293D03*
Y1568293D03*
X913352D03*
Y1565293D03*
Y1559293D03*
Y1562293D03*
X910352Y1574293D03*
Y1571293D03*
X922352Y1574293D03*
Y1571293D03*
X919352Y1574293D03*
Y1571293D03*
X916352Y1574293D03*
Y1571293D03*
X913352D03*
Y1574293D03*
X919488Y1660733D03*
X918020Y1672860D03*
X914500Y1671400D03*
X938160Y173389D03*
X935550Y173329D03*
X940720Y173389D03*
X938160Y176389D03*
X935550Y176329D03*
X940720Y176389D03*
X940424Y184190D03*
X936424D03*
X935770Y191419D03*
X939270D03*
X940410Y188852D03*
X930472Y246093D03*
X938603Y240063D03*
X933122Y246115D03*
X933686Y242922D03*
X935454Y241154D03*
X933217Y380693D03*
Y384693D03*
X941059Y427911D03*
Y424511D03*
X937447Y457862D03*
X934047D03*
X928394Y472201D03*
Y474701D03*
X932373Y495175D03*
X932089Y492691D03*
X929654Y492103D03*
X932218Y499314D03*
X939872Y495813D03*
X932089Y505986D03*
X932289Y502986D03*
X926637Y506069D03*
X929281Y506086D03*
X931720Y524862D03*
X940550Y517400D03*
X940140Y514925D03*
X933773Y530479D03*
X930731D03*
X941050Y532252D03*
Y528852D03*
X938742Y803831D03*
X931573Y816109D03*
X927470Y815112D03*
X935052Y812630D03*
X934260Y808312D03*
X938371Y809311D03*
X930786Y811785D03*
X925220Y817862D03*
X928237Y824844D03*
X926469Y826612D03*
X926823Y962082D03*
X940170Y962842D03*
X939740Y987762D03*
X936998Y985750D03*
X932310Y996812D03*
X927220Y1012362D03*
X931220D03*
X925352Y1562293D03*
Y1559293D03*
Y1565293D03*
Y1568293D03*
Y1574293D03*
Y1571293D03*
X938652Y1581393D03*
X928152Y1584539D03*
X938652Y1593393D03*
Y1585393D03*
X925152Y1586507D03*
X938652Y1589393D03*
X933979Y1661327D03*
X929979Y1661352D03*
X942100Y1671100D03*
X945720Y173389D03*
X943220D03*
X945720Y176389D03*
X943220D03*
X948400Y176499D03*
X949120Y184912D03*
X944250Y194489D03*
Y197889D03*
X957020Y193299D03*
X949550Y192819D03*
X957020Y264862D03*
X953046Y390103D03*
X951181Y391916D03*
X950660Y399472D03*
X956487Y394831D03*
X949920Y404602D03*
X944032Y437631D03*
Y434231D03*
X945447Y463012D03*
X942047D03*
X946727Y507952D03*
Y504552D03*
X954420Y511252D03*
Y500552D03*
Y497152D03*
Y514652D03*
X954390Y527596D03*
X945524Y515483D03*
X944261Y517871D03*
X941740Y512922D03*
X942610Y515350D03*
X945100Y534464D03*
X955123Y533642D03*
X948415Y534313D03*
X956518Y531567D03*
X957220Y582862D03*
X953594Y787477D03*
X954447Y791735D03*
X951043Y796140D03*
X950190Y791382D03*
X944272Y803410D03*
X943366Y798707D03*
X946786Y795287D03*
X947921Y799761D03*
X944170Y962842D03*
X949560Y981392D03*
X951560Y997422D03*
X956980Y1536260D03*
X953980D03*
X950980D03*
X947980D03*
X944980D03*
Y1551260D03*
X947980D03*
X950980D03*
X953980D03*
X956980D03*
X944980Y1548260D03*
X947980D03*
X950980D03*
X953980D03*
X956980D03*
X944980Y1545260D03*
X947980D03*
X950980D03*
X953980D03*
X956980D03*
X944980Y1542260D03*
X947980D03*
X950980D03*
X953980D03*
X956980D03*
Y1539260D03*
X953980D03*
X950980D03*
X947980D03*
X944980D03*
Y1554260D03*
X947980D03*
X950980D03*
X953980D03*
X956980D03*
X956800Y1663725D03*
X956600Y1666875D03*
X962604Y165313D03*
X962458Y162398D03*
X965150Y193412D03*
X966720Y198099D03*
X970720D03*
X961120Y193299D03*
X968384Y242051D03*
X965884D03*
X960020Y264862D03*
X963020D03*
X962570Y282812D03*
X962882Y314512D03*
X967239Y320073D03*
X963854Y320113D03*
X963300Y347962D03*
X962623Y350642D03*
X970730Y377872D03*
X972220Y386251D03*
Y390239D03*
X975670Y392063D03*
X963856Y398302D03*
X965890Y405967D03*
X963720Y439862D03*
X961320Y476242D03*
X968286Y483941D03*
Y480541D03*
X964347Y509462D03*
X970788Y501230D03*
X964347Y501262D03*
X969351Y512416D03*
X957790Y527596D03*
X963930Y533362D03*
X967330D03*
X959351Y533566D03*
X960920Y644762D03*
Y649762D03*
Y654762D03*
X963720Y647262D03*
Y657262D03*
Y652262D03*
X960820Y665062D03*
X960920Y659762D03*
X963720Y662262D03*
X967750Y1376460D03*
X969000Y1536262D03*
X971700D03*
X969000Y1548262D03*
X971700D03*
X969000Y1545262D03*
X971700D03*
X969000Y1551262D03*
X971700D03*
Y1542262D03*
X969000D03*
X971700Y1539262D03*
X969000D03*
X965904Y1554364D03*
X960904D03*
X969000Y1554262D03*
X971700D03*
X965086Y1603984D03*
X962086D03*
X980899Y-19800D03*
Y-23200D03*
Y6800D03*
Y10200D03*
X990501Y152397D03*
X986369Y155358D03*
X975690Y157220D03*
X983811Y156694D03*
X985499Y168753D03*
X985431Y181058D03*
X990115Y173039D03*
X987320Y194599D03*
Y198099D03*
Y201599D03*
X977220Y201399D03*
X986020Y191099D03*
X981795Y216623D03*
X978012Y276436D03*
X975512Y282096D03*
X978012D03*
X975512Y279266D03*
X978012D03*
X981470Y268532D03*
X979940Y292262D03*
Y289762D03*
X975512Y294996D03*
X978012D03*
X979940Y284762D03*
Y287262D03*
X988818Y346372D03*
X978000Y362462D03*
X988723Y369650D03*
X991934Y368443D03*
X988908Y373392D03*
X986400Y383123D03*
X983770Y373962D03*
X979766Y377507D03*
X977949Y384205D03*
X980916Y384286D03*
X980856Y392502D03*
X986955Y391939D03*
X983629Y397628D03*
X979559Y399362D03*
X983970Y392562D03*
X991369Y408252D03*
X979240Y425212D03*
X984254Y418379D03*
X987440Y431193D03*
X980720Y512362D03*
X986400Y503200D03*
X986273Y532996D03*
X980535Y532643D03*
X986418Y530019D03*
X975900Y1265062D03*
X987920Y1290662D03*
X985320Y1288762D03*
X992306Y1295049D03*
X979373Y1342724D03*
X974700Y1536262D03*
X980400D03*
X977700D03*
X974700Y1548262D03*
Y1545262D03*
Y1551262D03*
X980400Y1548262D03*
X977700D03*
X980400Y1545262D03*
X977700D03*
X980400Y1551262D03*
X977700D03*
Y1542262D03*
X980400D03*
X974700D03*
X977700Y1539262D03*
X980400D03*
X974700D03*
X984270Y1554364D03*
X974700Y1554262D03*
X980400D03*
X977700D03*
X989270Y1554364D03*
X995000Y150883D03*
X1001500D03*
X995180Y153689D03*
X1006220Y160799D03*
X1002720D03*
X1001101Y165510D03*
X999220Y185299D03*
X1002720D03*
X1006220D03*
X996415Y172579D03*
X1002920Y174799D03*
X990220Y195699D03*
Y199199D03*
X1008120Y198293D03*
X990195Y216823D03*
X990220Y202699D03*
X1000610Y211039D03*
X1005640Y210969D03*
X1001195Y219898D03*
X1005120Y230399D03*
X994743Y289843D03*
X1006232Y343983D03*
X1001440Y359702D03*
X994689Y379348D03*
X1006201Y370004D03*
X999440Y371782D03*
X996922Y367764D03*
X994322Y404090D03*
X1005123Y414662D03*
X997617Y412383D03*
X997394Y415578D03*
X993012Y421570D03*
X997225Y419162D03*
X990840Y431193D03*
X1005720Y498862D03*
X1003220Y512862D03*
X1005520Y510932D03*
X991237Y533043D03*
X1008560Y589682D03*
X1005960Y594682D03*
X1005373Y748826D03*
X995120Y773122D03*
X994942Y777055D03*
X996320Y1280683D03*
Y1284062D03*
X997920Y1278762D03*
X994574Y1297318D03*
X995066Y1536262D03*
X992466D03*
X1001066D03*
X1003766D03*
X998066D03*
X995066Y1551262D03*
X992466D03*
X995066Y1545262D03*
X992466D03*
X995066Y1548262D03*
X992466D03*
X1001066Y1551262D03*
X1003766D03*
X1001066Y1545262D03*
X1003766D03*
X1001066Y1548262D03*
X1003766D03*
X998066Y1551262D03*
Y1545262D03*
Y1548262D03*
Y1542262D03*
X1003766D03*
X1001066D03*
X992466D03*
X995066D03*
X998066Y1539262D03*
X1003766D03*
X1001066D03*
X992466D03*
X995066D03*
X1007636Y1554364D03*
X995066Y1554262D03*
X992466D03*
X1001066D03*
X1003766D03*
X998066D03*
X996698Y1604000D03*
X993698D03*
X1008129Y150948D03*
X1009720Y160799D03*
X1013220D03*
X1012791Y157596D03*
X1012000Y185299D03*
X1014900D03*
X1017800D03*
X1017200Y175699D03*
X1014300D03*
X1019900Y175799D03*
X1020645Y190499D03*
X1011320Y202169D03*
X1019355Y218423D03*
X1019802Y214099D03*
X1010005Y208424D03*
X1011720Y229699D03*
X1019355Y222423D03*
X1019530Y226423D03*
X1007820Y229999D03*
X1021118Y294290D03*
X1020720Y310937D03*
X1015520Y302862D03*
X1009800Y343800D03*
X1021695Y364518D03*
X1006710Y372931D03*
X1015096Y373758D03*
X1017163Y367963D03*
X1009883Y367955D03*
X1010420Y416062D03*
X1015420Y410862D03*
X1009009Y419948D03*
X1021239Y416974D03*
X1016261Y432888D03*
X1012861D03*
X1024200Y510362D03*
X1018092Y520212D03*
X1020392Y521826D03*
X1016360Y594682D03*
X1016220Y590862D03*
X1019000Y601042D03*
X1021654Y606302D03*
X1011160Y594682D03*
X1007873Y748826D03*
X1007600Y1298250D03*
X1007610Y1295040D03*
X1021612Y1536262D03*
X1016012D03*
X1018612D03*
Y1551262D03*
X1016012D03*
X1018612Y1545262D03*
X1016012D03*
X1018612Y1548262D03*
X1016012D03*
X1021612Y1551262D03*
Y1545262D03*
Y1548262D03*
X1018612Y1542262D03*
X1016012D03*
X1021612D03*
Y1539262D03*
X1016012D03*
X1018612D03*
Y1554262D03*
X1016012D03*
X1021612D03*
X1012636Y1554364D03*
X1032433Y-29811D03*
Y-33211D03*
Y-13211D03*
Y-9811D03*
X1026620Y125662D03*
X1034229Y128953D03*
X1032894Y155185D03*
X1022800Y175799D03*
X1037618Y261200D03*
X1031702Y264130D03*
X1025862Y291727D03*
X1032317Y291284D03*
X1036278Y303993D03*
Y307393D03*
X1033285Y353627D03*
X1029395Y375844D03*
X1025004Y374662D03*
X1031950Y383771D03*
Y387171D03*
X1031153Y390152D03*
X1026820Y394362D03*
X1038320Y407062D03*
Y404462D03*
X1026548Y400571D03*
X1035920Y420062D03*
Y417462D03*
X1026370Y503562D03*
X1032155Y509737D03*
X1025530Y519627D03*
X1033040Y519852D03*
X1038130Y518417D03*
X1040720Y591862D03*
X1024154Y601152D03*
X1029630Y601252D03*
X1026654Y596152D03*
X1035760Y592952D03*
X1033260Y601272D03*
X1038260D03*
X1033817Y735612D03*
X1036954Y734669D03*
X1030660Y735082D03*
X1027212Y1536262D03*
X1024612D03*
Y1551262D03*
X1027212D03*
X1024612Y1545262D03*
X1027212D03*
X1024612Y1548262D03*
X1027212D03*
X1024612Y1542262D03*
X1027212D03*
Y1539262D03*
X1024612D03*
X1031002Y1554364D03*
X1024612Y1554262D03*
X1027212D03*
X1036002Y1554364D03*
X1028298Y1604000D03*
X1025298D03*
X1040970Y128332D03*
X1043720Y363462D03*
X1054820Y370162D03*
X1044120Y366362D03*
X1040120Y393962D03*
X1042720D03*
X1041420Y443962D03*
X1043920D03*
X1050470Y447062D03*
X1041444Y506504D03*
X1053690Y520760D03*
X1045720Y591672D03*
X1043260Y601272D03*
X1045760Y596272D03*
X1048260Y601272D03*
X1051680Y614772D03*
X1053745Y742341D03*
X1053354Y1286714D03*
Y1291714D03*
X1039510Y1296655D03*
X1049510D03*
X1044510D03*
X1039510Y1293155D03*
X1049510D03*
X1044510D03*
X1053354Y1296714D03*
X1041798Y1536262D03*
X1047798D03*
X1050498D03*
X1044798D03*
X1039298D03*
X1041798Y1551262D03*
X1039298D03*
X1041798Y1545262D03*
X1039298D03*
X1041798Y1548262D03*
X1039298D03*
X1047798Y1551262D03*
X1050498D03*
X1047798Y1545262D03*
X1050498D03*
X1047798Y1548262D03*
X1050498D03*
X1044798Y1551262D03*
Y1545262D03*
Y1548262D03*
X1039298Y1542262D03*
X1044798D03*
X1050498D03*
X1047798D03*
X1041798D03*
X1044798Y1539262D03*
X1050498D03*
X1047798D03*
X1039298D03*
X1041798D03*
X1054368Y1554364D03*
X1041798Y1554262D03*
X1039298D03*
X1047798D03*
X1050498D03*
X1044798D03*
X1056898Y1604000D03*
X1067220Y145362D03*
Y142862D03*
Y148362D03*
X1059943Y435314D03*
X1062120Y477462D03*
X1056190Y520760D03*
X1058220Y585862D03*
X1061470D03*
X1056220Y605052D03*
X1055205Y744853D03*
X1063354Y1286714D03*
X1058354D03*
X1063354Y1291714D03*
X1058354D03*
X1063354Y1296714D03*
X1058290Y1296302D03*
X1071179Y1294669D03*
X1066462Y1520088D03*
X1065164Y1536262D03*
X1062464D03*
X1071164D03*
X1068164D03*
X1065164Y1551262D03*
X1062464D03*
X1065164Y1545262D03*
X1062464D03*
X1065164Y1548262D03*
X1062464D03*
X1071164Y1551262D03*
Y1545262D03*
Y1548262D03*
X1068164Y1551262D03*
Y1545262D03*
Y1548262D03*
Y1542262D03*
X1071164D03*
X1062464D03*
X1065164D03*
X1068164Y1539262D03*
X1071164D03*
X1062464D03*
X1065164D03*
Y1554262D03*
X1062464D03*
X1071164D03*
X1068164D03*
X1059368Y1554364D03*
X1059898Y1604000D03*
X1071920Y53862D03*
X1079114Y75775D03*
X1080168Y90721D03*
X1081282Y180937D03*
X1086756Y187540D03*
X1077973Y246362D03*
X1083973D03*
X1080973D03*
X1077883Y260842D03*
X1076823Y265438D03*
X1083823D03*
X1083883Y260842D03*
X1080883D03*
X1080323Y265438D03*
X1082853Y269492D03*
X1079853D03*
X1075400Y273762D03*
X1078400D03*
X1081400D03*
X1084400D03*
X1087400D03*
X1076018Y289400D03*
X1079018D03*
X1082018D03*
X1085018D03*
X1084130Y298342D03*
X1086630D03*
X1076353Y363966D03*
X1078853D03*
X1087330Y369061D03*
Y374131D03*
Y379251D03*
X1075462Y386723D03*
X1078151Y413911D03*
X1078120Y411262D03*
X1084245Y435437D03*
X1078545Y435637D03*
X1081045D03*
X1087280Y435437D03*
X1076598Y477087D03*
X1081930Y477132D03*
X1079320Y473892D03*
X1076820D03*
X1073589Y506461D03*
X1082220Y522362D03*
X1085720Y522422D03*
X1073250Y582332D03*
X1084637Y744635D03*
X1083714Y1285144D03*
Y1288144D03*
Y1291144D03*
X1077634Y1294869D03*
X1074387Y1294652D03*
X1074010Y1510650D03*
X1073864Y1536262D03*
X1085830D03*
X1073864Y1551262D03*
Y1545262D03*
Y1548262D03*
X1085830Y1551262D03*
Y1545262D03*
Y1548262D03*
Y1542262D03*
X1073864D03*
X1085830Y1539262D03*
X1073864D03*
X1077734Y1554364D03*
X1073864Y1554262D03*
X1085830D03*
X1082734Y1554364D03*
X1084000Y1647110D03*
X1094644Y67992D03*
X1090279Y126524D03*
X1105580Y132822D03*
X1100630Y130376D03*
X1099030Y245140D03*
X1088018Y289400D03*
X1089130Y298342D03*
X1091630D03*
X1094130D03*
X1089660Y408560D03*
X1095820Y420762D03*
X1090245Y435437D03*
X1093497Y744655D03*
X1089714Y1285144D03*
X1105480Y1517982D03*
X1088530Y1536262D03*
X1091530D03*
X1088530Y1551262D03*
Y1545262D03*
Y1548262D03*
X1094530Y1551262D03*
X1097230D03*
X1094530Y1545262D03*
X1097230D03*
X1094530Y1548262D03*
X1097230D03*
X1091530Y1551262D03*
Y1545262D03*
Y1548262D03*
Y1542262D03*
X1097230D03*
X1094530D03*
X1088530D03*
X1091530Y1539262D03*
X1094530D03*
X1088530D03*
X1101600Y1554364D03*
X1104750Y1549346D03*
X1088530Y1554262D03*
X1094530D03*
X1097230D03*
X1091530D03*
X1095436Y1603944D03*
X1092436D03*
X1088790Y1641830D03*
X1094225Y1671710D03*
X1091880Y1673720D03*
X1110977Y55505D03*
X1110754Y60028D03*
X1113594Y69862D03*
X1109020Y80592D03*
X1118309Y111687D03*
X1115860Y113883D03*
X1118486Y208942D03*
X1111918Y234718D03*
X1109088Y234668D03*
X1111918Y237718D03*
Y240718D03*
X1109088Y237668D03*
Y240668D03*
X1120190Y255652D03*
X1117820Y456132D03*
X1113207Y744455D03*
X1115853Y1426342D03*
Y1435532D03*
X1114400Y1518237D03*
X1110725Y1518046D03*
X1113725Y1530935D03*
X1115802Y1615010D03*
X1117407Y1628495D03*
X1113990Y1631370D03*
X1113325Y1627975D03*
X1117182Y1625460D03*
X1106480Y1641275D03*
X1113110Y1666460D03*
X1108320Y1680200D03*
X1112130Y1711600D03*
X1112252Y1706170D03*
X1112200Y1709000D03*
X1114150Y1715726D03*
X1110663Y1719189D03*
X1119200Y1730300D03*
Y1727200D03*
X1114300Y1722700D03*
X1119300Y1724100D03*
X1132547Y64864D03*
X1129997Y69864D03*
X1122278Y107549D03*
X1120420Y109829D03*
X1124858Y197309D03*
X1128485Y198159D03*
X1133041Y194137D03*
X1124360Y259712D03*
X1125409Y305797D03*
X1122059Y305673D03*
X1124985Y302578D03*
X1127402Y456174D03*
X1136051Y503324D03*
X1124120Y643762D03*
X1136720Y641362D03*
X1133720Y642862D03*
X1129420Y644062D03*
X1122980Y741312D03*
X1127972Y747250D03*
X1135750Y1255672D03*
X1127179Y1372700D03*
X1124679D03*
Y1370200D03*
X1127179D03*
X1129729Y1372700D03*
Y1370200D03*
Y1375200D03*
X1127179D03*
X1124679D03*
X1129729Y1377700D03*
Y1380200D03*
Y1385200D03*
Y1382700D03*
X1127179D03*
X1124679D03*
X1127179Y1380200D03*
Y1377700D03*
X1124679D03*
Y1380200D03*
Y1385200D03*
X1127179D03*
X1122879Y1431474D03*
Y1434024D03*
X1125995Y1439780D03*
X1123379Y1443583D03*
X1133169Y1445690D03*
X1129169Y1442998D03*
X1135568Y1442923D03*
X1129169Y1445719D03*
X1130841Y1462953D03*
X1128341Y1465453D03*
Y1462953D03*
X1130841Y1465453D03*
X1133841Y1462953D03*
Y1465453D03*
X1128341Y1468453D03*
X1130841D03*
X1133841D03*
X1128341Y1460453D03*
X1130841D03*
X1133841D03*
Y1471453D03*
X1130841D03*
X1128341D03*
X1132187Y1582738D03*
X1135187D03*
X1132187Y1590738D03*
X1135187D03*
X1124862Y1615010D03*
X1140242Y101135D03*
X1152720Y180862D03*
X1148795Y213731D03*
X1141957Y227277D03*
X1144457D03*
X1139457D03*
X1146670Y230110D03*
X1147700Y362731D03*
X1137315Y379592D03*
X1147700Y368041D03*
X1138551Y503324D03*
X1144720Y501362D03*
Y498662D03*
X1142967Y592097D03*
X1138500Y586362D03*
X1142127Y586452D03*
X1140697Y608762D03*
X1150140Y610362D03*
X1144810Y613762D03*
X1142674Y1287608D03*
X1144247Y1372700D03*
Y1370200D03*
X1146797Y1372700D03*
X1149297D03*
X1146797Y1370200D03*
X1149297D03*
X1144247Y1375200D03*
X1146797D03*
X1149297D03*
X1144247Y1377700D03*
Y1380200D03*
Y1385200D03*
Y1382700D03*
X1146797D03*
X1149297D03*
X1146797Y1380200D03*
Y1377700D03*
X1149297Y1380200D03*
Y1377700D03*
Y1385200D03*
X1146797D03*
X1146563Y1436334D03*
X1141903D03*
X1144233Y1435584D03*
X1139573D03*
X1149469Y1437098D03*
X1151669Y1435698D03*
Y1438598D03*
X1137311Y1445191D03*
X1147203Y1441968D03*
X1149569Y1440098D03*
X1151669Y1441498D03*
X1147203Y1439068D03*
X1141591Y1462853D03*
Y1465353D03*
Y1468353D03*
Y1471353D03*
Y1460353D03*
X1150821Y1459607D03*
Y1456587D03*
X1138430Y1524150D03*
X1151497Y1524187D03*
X1153465Y1550301D03*
X1149528D03*
X1145410Y1540640D03*
X1143060Y1538380D03*
X1141654Y1550301D03*
X1137717Y1558020D03*
X1141690Y1552920D03*
X1152187Y1574738D03*
X1142187D03*
X1145187D03*
X1142187Y1582738D03*
X1145187D03*
X1152187D03*
X1141525Y1597630D03*
X1152187Y1590738D03*
X1142187D03*
X1145187D03*
X1140750Y1604330D03*
X1150380Y1602590D03*
X1146960Y1618960D03*
X1152257Y1628910D03*
X1155703Y73679D03*
X1165440Y176450D03*
X1168710Y176590D03*
X1159460Y194090D03*
X1160630Y213870D03*
X1159753Y361281D03*
X1159460Y366025D03*
X1156790Y363231D03*
X1161690Y374110D03*
X1164320Y451062D03*
X1156100Y456342D03*
X1167190Y526922D03*
X1158300Y585862D03*
X1170740Y602132D03*
X1155962Y746193D03*
X1156609Y1286685D03*
X1165279Y1372700D03*
X1162779D03*
X1167829D03*
X1162779Y1370200D03*
X1165279D03*
X1167829D03*
X1162779Y1375200D03*
X1165279D03*
X1167829D03*
Y1377700D03*
Y1380200D03*
Y1385200D03*
Y1382700D03*
X1165279D03*
X1162779D03*
X1165279Y1380200D03*
X1162779D03*
Y1377700D03*
X1165279D03*
X1162779Y1385200D03*
X1165279D03*
X1161022Y1431499D03*
Y1433999D03*
X1164138Y1439780D03*
X1154288Y1432502D03*
X1161522Y1443630D03*
X1167312Y1442998D03*
Y1445964D03*
X1159386Y1464253D03*
Y1466753D03*
X1156386Y1464253D03*
Y1466753D03*
X1159386Y1469253D03*
X1156386D03*
X1153821Y1459607D03*
Y1456587D03*
X1159386Y1461753D03*
X1159476Y1458918D03*
X1156386Y1461753D03*
X1156476Y1458918D03*
X1159446Y1456113D03*
X1156446D03*
X1167245Y1524187D03*
X1159371D03*
X1163308D03*
X1155433D03*
X1165276Y1550301D03*
X1169213D03*
X1157402D03*
X1161339D03*
X1161595Y1574738D03*
X1164595D03*
X1155187D03*
X1161595Y1582738D03*
X1164595D03*
X1155187D03*
X1163079Y1601479D03*
X1161595Y1590738D03*
X1164595D03*
X1155187D03*
X1169460Y1606630D03*
Y1616630D03*
Y1611630D03*
X1158030Y1619250D03*
X1164830Y1628830D03*
X1163970Y1620600D03*
X1169325Y1642600D03*
X1158325D03*
X1162383Y1652505D03*
X1164830Y1654632D03*
X1159930D03*
X1161076Y1680624D03*
X1157700Y1681100D03*
X1174120Y57111D03*
X1175926Y69151D03*
X1180676Y106858D03*
X1187413Y143132D03*
X1181420Y157962D03*
X1181700Y186962D03*
X1173314Y176452D03*
X1170595Y170056D03*
X1181476Y172247D03*
X1184510Y188962D03*
X1173100Y186962D03*
X1172925Y202174D03*
X1181369Y199234D03*
X1183460Y205342D03*
X1181470Y208802D03*
X1172835Y218174D03*
X1181500Y211962D03*
Y218462D03*
Y215962D03*
Y222162D03*
X1186653Y302242D03*
X1181450Y306052D03*
X1174120Y355362D03*
X1169690Y526922D03*
X1172310Y584562D03*
X1181300Y584762D03*
X1177570Y602052D03*
X1175217Y595762D03*
X1173020Y745972D03*
X1175573Y1286765D03*
X1172573D03*
X1182747Y1372700D03*
X1185297D03*
X1182747Y1370200D03*
X1185297D03*
X1182747Y1375200D03*
X1185297D03*
X1182747Y1380200D03*
Y1377700D03*
Y1385200D03*
Y1382700D03*
X1185297D03*
Y1377700D03*
Y1380200D03*
Y1385200D03*
X1184706Y1436334D03*
X1180046D03*
X1182376Y1435584D03*
X1177716D03*
X1171342Y1445650D03*
X1175454Y1445191D03*
X1173711Y1442923D03*
X1171182Y1524187D03*
X1184330Y1573260D03*
X1184290Y1570080D03*
X1171595Y1574738D03*
X1174595D03*
X1171595Y1582738D03*
X1174595D03*
X1183410Y1594450D03*
X1183440Y1591640D03*
X1171595Y1590738D03*
X1174595D03*
X1178140Y1601100D03*
X1184200Y1599900D03*
X1183320Y1597080D03*
X1169968Y1602370D03*
X1174550Y1615630D03*
X1178250Y1609100D03*
X1184200Y1602700D03*
X1185030Y1624660D03*
X1180325Y1642600D03*
X1173383Y1652505D03*
X1184383D03*
X1181930Y1654632D03*
X1175830D03*
X1170930D03*
X1183076Y1680624D03*
X1172076D03*
X1194478Y56986D03*
X1197520Y56962D03*
X1201158Y57130D03*
X1189393Y60183D03*
X1188700Y100700D03*
X1185400Y104000D03*
X1193532Y132644D03*
X1194800Y143112D03*
X1197414Y161592D03*
X1191020Y170862D03*
X1185420Y153762D03*
X1200720Y184862D03*
X1188300Y189062D03*
X1200720Y187862D03*
X1200963Y212648D03*
X1200830Y206002D03*
X1186340Y204492D03*
X1187300Y217862D03*
X1188500Y205772D03*
X1188600Y225962D03*
X1187013Y238972D03*
X1194840Y236592D03*
X1199720Y252362D03*
X1196720D03*
X1188810Y296088D03*
X1186280Y298972D03*
X1193198Y586172D03*
X1195698D03*
X1198198D03*
X1200698D03*
X1185687Y744475D03*
X1187797Y1372700D03*
Y1370200D03*
Y1375200D03*
Y1382700D03*
Y1377700D03*
Y1380200D03*
Y1385200D03*
X1187412Y1437498D03*
X1189612Y1436098D03*
X1191918Y1432516D03*
X1185346Y1442128D03*
X1187512Y1440498D03*
X1189612Y1441898D03*
X1185346Y1439228D03*
X1189612Y1438998D03*
X1187720Y1517688D03*
X1187830Y1522188D03*
X1198546Y1520188D03*
X1187830Y1526688D03*
X1198546Y1524688D03*
X1187720Y1536362D03*
X1198485Y1534313D03*
X1198436Y1529362D03*
X1187720Y1531862D03*
Y1553692D03*
X1198497Y1539667D03*
X1187720Y1548772D03*
X1198436Y1546492D03*
X1187720Y1544292D03*
X1198436Y1551192D03*
Y1556192D03*
Y1561062D03*
X1187720Y1558682D03*
Y1563182D03*
X1194510Y1563076D03*
X1187600Y1622064D03*
X1201600Y1633790D03*
X1199400Y1627800D03*
X1190895Y1642910D03*
X1186000Y1640000D03*
X1197400Y1654942D03*
X1192500D03*
X1186830Y1654632D03*
X1193646Y1680934D03*
X1201106Y1677873D03*
X1190735Y1688390D03*
X1194793Y1698295D03*
X1201505Y1688435D03*
X1192340Y1700422D03*
X1197240D03*
X1193174Y1726414D03*
X1216176Y56742D03*
X1202860Y120392D03*
X1215763Y114363D03*
X1215800Y111300D03*
X1201700Y110000D03*
X1202920Y117162D03*
X1210910Y129502D03*
X1206114Y132962D03*
X1206434Y129492D03*
X1206694Y139512D03*
X1214415Y153962D03*
X1206664Y158952D03*
X1214091Y164962D03*
X1214534Y157462D03*
X1214054Y186092D03*
X1214693Y174962D03*
X1214134Y180972D03*
X1213720Y200309D03*
Y189362D03*
X1204220D03*
X1213720Y195362D03*
X1215720Y204862D03*
X1203200Y202514D03*
X1219060Y213312D03*
X1206660Y224742D03*
X1213540Y224792D03*
X1207220Y243998D03*
X1210900Y265300D03*
X1204475Y350684D03*
X1205165Y380962D03*
X1218870Y418082D03*
X1214000Y599262D03*
X1208980Y598462D03*
X1207100Y600882D03*
X1211277Y744265D03*
X1206757Y744455D03*
X1210288Y754081D03*
X1202300Y753962D03*
X1207607Y754095D03*
X1215896Y756942D03*
X1206432Y758995D03*
X1202307Y757082D03*
X1205820Y1652910D03*
X1210830Y1676500D03*
X1217210Y1684520D03*
X1212305Y1688700D03*
X1216363Y1698605D03*
X1205563Y1698340D03*
X1207180Y1685680D03*
X1208010Y1700467D03*
X1213910Y1700732D03*
X1203110Y1700467D03*
X1203939Y1726459D03*
X1214834Y1726724D03*
X1228425Y91500D03*
X1222100Y91600D03*
X1225100Y91500D03*
X1225700Y108962D03*
X1232182Y110659D03*
X1224614Y116962D03*
X1219534Y116492D03*
X1223500Y111162D03*
X1226400Y125200D03*
X1226093Y134262D03*
X1229500Y125100D03*
X1223100Y130700D03*
X1234093Y144962D03*
X1226093Y140962D03*
X1222593D03*
X1222920Y144909D03*
Y148909D03*
X1222593Y168962D03*
X1222890Y157002D03*
X1226093Y156962D03*
X1222594Y154242D03*
X1226093Y168162D03*
X1225874Y163462D03*
X1222720Y163362D03*
X1226093Y177962D03*
X1222724Y176102D03*
X1226093Y172962D03*
X1223134Y190802D03*
X1225574Y188662D03*
X1228520Y202162D03*
X1229720Y197302D03*
X1226093Y193462D03*
X1225320Y200162D03*
X1233282Y201875D03*
X1223180Y210552D03*
X1233780Y214572D03*
X1231720Y217862D03*
Y209862D03*
X1219220Y243862D03*
Y247148D03*
X1230720Y380362D03*
X1221220D03*
X1232720Y377862D03*
X1224300Y380400D03*
X1223650Y520672D03*
X1230650D03*
X1227150D03*
X1219060Y757272D03*
X1223327Y757615D03*
X1228320Y758598D03*
X1218810Y1700732D03*
X1236620Y58862D03*
X1241010Y110782D03*
X1250010Y117121D03*
X1244200Y112862D03*
X1249362Y111600D03*
X1241035Y114399D03*
X1234746Y136040D03*
X1240728Y136198D03*
X1240904Y151592D03*
X1238604Y150062D03*
X1241100Y145842D03*
X1244120Y167462D03*
X1246272Y164889D03*
X1243100Y160181D03*
X1243184Y182422D03*
X1239874Y182322D03*
X1236410Y201462D03*
X1236220Y189362D03*
X1236593Y197462D03*
X1236584Y205762D03*
X1245486Y203000D03*
X1245593Y211762D03*
X1236620Y221562D03*
X1244720Y230362D03*
X1245514Y224302D03*
X1245593Y219662D03*
X1239045Y224062D03*
X1246878Y248615D03*
X1240500Y248332D03*
Y244332D03*
X1236720Y257362D03*
X1243589Y379595D03*
X1236720Y377862D03*
X1234720Y380362D03*
X1248150Y520672D03*
X1244650D03*
X1241150D03*
X1237650D03*
X1234150D03*
X1242260Y757602D03*
X1261227Y52061D03*
X1258727D03*
X1263454Y83060D03*
X1266464Y83090D03*
X1264098Y88787D03*
X1262320Y96012D03*
X1258539Y100900D03*
X1252520Y92022D03*
X1258539Y109263D03*
X1260641Y114399D03*
X1264220Y110462D03*
X1250424Y108943D03*
X1257581Y114579D03*
X1256093Y149462D03*
X1264663Y158946D03*
X1254994Y157382D03*
X1265010Y162222D03*
X1261899Y174648D03*
X1253624Y201362D03*
X1267315Y220701D03*
X1264874Y217462D03*
X1256504D03*
X1255613Y209568D03*
X1265207Y208442D03*
X1259703Y209808D03*
X1253440Y230552D03*
X1253860Y235622D03*
X1256070Y229512D03*
X1264584Y226592D03*
X1256593Y221462D03*
Y233972D03*
Y225972D03*
X1253950Y246692D03*
X1266715Y244692D03*
X1254370Y241302D03*
X1265065Y249982D03*
X1256494Y243177D03*
X1256574Y238662D03*
X1266518Y237042D03*
X1256584Y248002D03*
X1256454Y252122D03*
X1264854Y253996D03*
Y256496D03*
X1258883Y280558D03*
X1258250Y292986D03*
X1263150Y294726D03*
X1255150Y306211D03*
X1256220Y434362D03*
X1261220Y454362D03*
X1253220Y451362D03*
X1267220D03*
X1260220Y477362D03*
X1255920Y511362D03*
X1251650Y520672D03*
X1255150D03*
X1258667Y751405D03*
X1255520Y747362D03*
X1263486Y739949D03*
X1257672Y1351008D03*
X1276820Y58142D03*
X1282360Y58132D03*
X1279580D03*
X1279390Y87697D03*
X1275820Y87962D03*
X1270329Y101011D03*
X1266722Y101005D03*
X1278456Y96187D03*
X1279415Y90847D03*
X1281704Y95402D03*
X1282824Y108872D03*
X1271284Y108971D03*
X1282764Y135398D03*
X1277820Y140682D03*
X1281093Y144516D03*
X1271954Y159143D03*
X1271593Y165962D03*
X1278093Y184462D03*
X1278993Y193262D03*
X1273093Y200038D03*
X1278183Y201262D03*
X1275493Y193962D03*
X1267289Y192167D03*
X1269904Y192692D03*
X1272893Y191262D03*
X1271315Y220701D03*
X1267773Y208373D03*
X1273093Y213962D03*
X1275727Y209597D03*
X1267618Y225382D03*
X1277661Y225685D03*
X1267593Y229462D03*
X1278783Y221386D03*
X1282176Y221436D03*
X1282654Y226309D03*
X1278320Y239292D03*
X1279493Y248662D03*
X1282645Y255671D03*
Y252271D03*
X1277771Y255173D03*
X1273754Y256504D03*
X1276800Y276562D03*
X1269960Y294536D03*
X1271150Y305792D03*
X1272530Y429362D03*
X1284220D03*
X1280270Y434362D03*
X1272220D03*
X1278380Y463362D03*
X1276220Y477362D03*
X1283220D03*
X1269220D03*
X1274420Y463362D03*
X1275576Y730879D03*
X1266727Y752955D03*
X1279788Y1304042D03*
X1279812Y1353552D03*
X1279334Y1356089D03*
X1275856Y1358098D03*
X1271990Y1358079D03*
X1276891Y1362891D03*
X1282928Y1361833D03*
X1269012Y1371693D03*
Y1368293D03*
X1290291Y-29811D03*
Y-33211D03*
Y-13211D03*
Y-9811D03*
X1285201Y58121D03*
X1293454Y81232D03*
X1289210D03*
X1298640Y93062D03*
X1292880Y93162D03*
X1292899Y98519D03*
X1294354Y103166D03*
X1291704Y109427D03*
X1288093Y125962D03*
X1291478Y137745D03*
X1286150Y131092D03*
X1297605Y145824D03*
X1285710Y249182D03*
X1290293Y247562D03*
X1288637Y240448D03*
X1292630Y240462D03*
X1291071Y275543D03*
Y278543D03*
X1290005Y293768D03*
Y290268D03*
X1294500Y299692D03*
X1291100D03*
X1291500Y312862D03*
Y315362D03*
X1291420Y320662D03*
Y318162D03*
X1295540Y440902D03*
X1301310Y440862D03*
X1291220Y463362D03*
X1294440Y477267D03*
X1296630Y463462D03*
X1300220Y477362D03*
X1284220Y463362D03*
X1289936Y732539D03*
X1290520Y746562D03*
X1292572Y785575D03*
X1297298Y790982D03*
X1296719Y1290197D03*
X1299169Y1295467D03*
Y1297967D03*
X1296569D03*
Y1295467D03*
Y1292967D03*
X1299169D03*
X1296581Y1300474D03*
X1299181D03*
X1296576Y1303298D03*
X1299176D03*
X1290102Y1365789D03*
X1286102Y1365051D03*
X1294312Y1367279D03*
X1292840Y1364821D03*
X1286102Y1368107D03*
X1298836Y1358387D03*
X1296506Y1357637D03*
X1301820Y58672D03*
X1311424Y68652D03*
X1308174D03*
X1311960Y58152D03*
X1311260Y83032D03*
X1310857Y78542D03*
X1307120Y78562D03*
X1310906Y97807D03*
X1314406Y97756D03*
X1308274Y104162D03*
X1314059Y93877D03*
X1307244Y118452D03*
X1306836Y108242D03*
X1302080Y117032D03*
X1302060Y113852D03*
X1300990Y121812D03*
X1315156Y130656D03*
X1314920Y135361D03*
X1313117Y250605D03*
X1314685Y248651D03*
X1307431Y256099D03*
X1309283Y254162D03*
X1311275Y252297D03*
X1305552Y257974D03*
X1308736Y284948D03*
X1312136D03*
X1307042Y292636D03*
X1303642D03*
X1307442Y306998D03*
X1304042D03*
X1307677Y322996D03*
X1311077D03*
X1317100Y553900D03*
X1308600Y653500D03*
X1303576Y659671D03*
X1311420Y738262D03*
X1305187Y735630D03*
X1315020Y739862D03*
X1307469Y787772D03*
X1301034Y784165D03*
X1304260Y788265D03*
X1309930Y789852D03*
X1306701Y794779D03*
X1305117Y797125D03*
X1309210Y792802D03*
X1315169Y1274887D03*
X1315289Y1269717D03*
X1315229Y1272287D03*
X1304149Y1291317D03*
X1301889Y1284987D03*
X1301829Y1290167D03*
X1301859Y1287587D03*
X1304299Y1280967D03*
X1304269Y1283567D03*
X1304239Y1286147D03*
X1304209Y1288747D03*
X1315176Y1280218D03*
X1315181Y1277594D03*
X1299319Y1290197D03*
X1299349Y1287617D03*
X1301686Y1303268D03*
X1304196Y1299248D03*
X1304189Y1293917D03*
X1304201Y1296624D03*
X1301679Y1292937D03*
Y1295437D03*
Y1297937D03*
X1301691Y1300444D03*
X1311820Y1330518D03*
Y1333018D03*
X1314936Y1338799D03*
X1312650Y1342572D03*
X1308616Y1363345D03*
Y1360445D03*
X1306082Y1359315D03*
X1306182Y1362315D03*
X1304016Y1363945D03*
Y1361045D03*
X1308616Y1357945D03*
X1303496Y1358387D03*
X1301166Y1357637D03*
X1316459Y58697D03*
X1322248Y68487D03*
X1321279Y58767D03*
X1317831Y68652D03*
X1322415Y75480D03*
X1322906Y94212D03*
X1319968Y98266D03*
X1329891Y99455D03*
X1329646Y104954D03*
X1322906Y109733D03*
X1323912Y245111D03*
X1320387Y258901D03*
X1325769Y259001D03*
X1325414Y293556D03*
X1328814D03*
X1319903Y299176D03*
X1323303D03*
X1319618Y318073D03*
X1325080Y323902D03*
X1316218Y318073D03*
X1328480Y323902D03*
X1330101Y540049D03*
X1328530Y747702D03*
X1325210Y744322D03*
X1331519Y1262027D03*
X1331459Y1264597D03*
X1331399Y1267197D03*
X1317889Y1267147D03*
X1320399Y1267117D03*
X1317883Y1269978D03*
X1317895Y1272485D03*
X1320393Y1269948D03*
X1320405Y1272455D03*
X1331177Y1269933D03*
Y1272433D03*
X1317895Y1274985D03*
X1320405Y1274955D03*
X1331177Y1274933D03*
X1331166Y1280248D03*
X1317746D03*
X1320256Y1280218D03*
X1317895Y1277485D03*
X1320405Y1277455D03*
X1331189Y1277440D03*
X1328514Y1334603D03*
X1330844Y1335353D03*
X1322110Y1342755D03*
X1318110Y1342017D03*
X1326320Y1344245D03*
X1324848Y1341787D03*
X1318110Y1345073D03*
X1331288Y1372440D03*
X1327491Y1372358D03*
X1324491Y1372658D03*
X1327491Y1375858D03*
X1331288Y1375940D03*
X1324491Y1375858D03*
X1327491Y1381478D03*
Y1378478D03*
X1331288Y1378560D03*
X1324491Y1381478D03*
Y1378478D03*
X1331304Y1401986D03*
Y1404986D03*
X1327926D03*
X1322228Y1419890D03*
X1322186Y1411326D03*
Y1414326D03*
Y1417326D03*
X1322270Y1422454D03*
X1325084Y1420066D03*
X1325042Y1408502D03*
Y1411502D03*
Y1417502D03*
Y1414502D03*
X1331344Y1414456D03*
X1330804Y1411536D03*
Y1408536D03*
X1331386Y1420020D03*
X1328008D03*
X1331344Y1417456D03*
X1327966Y1408456D03*
Y1411456D03*
Y1417456D03*
Y1414456D03*
X1331428Y1422584D03*
X1328050D03*
X1322312Y1425018D03*
X1325126Y1422630D03*
X1325168Y1425194D03*
X1328092Y1425148D03*
X1331470D03*
X1341752Y-29811D03*
Y-33211D03*
Y-9811D03*
Y-13211D03*
X1333190Y58825D03*
X1347640Y101950D03*
X1345583Y91307D03*
X1336549Y105970D03*
X1344631Y127244D03*
X1332497Y133931D03*
X1343034Y141698D03*
X1336761Y293404D03*
X1340161D03*
X1335145Y332616D03*
X1341431Y322693D03*
X1331745Y332616D03*
X1338031Y322693D03*
X1345424Y328981D03*
X1344720Y423162D03*
X1337220D03*
X1342220D03*
X1339720D03*
X1333143Y540049D03*
X1340420Y538422D03*
Y541822D03*
X1347419Y1259257D03*
X1347379Y1256687D03*
X1336269Y1274957D03*
X1333969Y1264567D03*
X1334029Y1261997D03*
X1333909Y1267167D03*
X1336339Y1269777D03*
X1336279Y1272347D03*
X1347359Y1261857D03*
X1347371Y1264564D03*
X1336519Y1264627D03*
X1336579Y1262057D03*
X1347366Y1267188D03*
X1336459Y1267227D03*
X1333687Y1269903D03*
Y1272403D03*
Y1274903D03*
X1333676Y1280218D03*
X1336261Y1277654D03*
X1333699Y1277410D03*
X1343948Y1317092D03*
Y1319592D03*
X1344532Y1328161D03*
X1347397Y1325320D03*
X1336144Y1341147D03*
X1338288Y1339653D03*
X1340488Y1340853D03*
X1336144Y1338247D03*
X1340214Y1334853D03*
X1340410Y1338017D03*
X1338288Y1336553D03*
X1333174Y1334603D03*
X1335504Y1335353D03*
X1334288Y1372440D03*
X1340288D03*
X1346193Y1372523D03*
X1343193D03*
X1337288Y1372440D03*
Y1375940D03*
X1334288D03*
X1343193Y1376023D03*
X1346193D03*
X1340288Y1375940D03*
X1346304Y1401986D03*
X1343304D03*
X1340304D03*
X1337304D03*
X1334304D03*
Y1404986D03*
X1346304D03*
X1343304D03*
X1340304D03*
X1337304D03*
X1337344Y1414456D03*
X1346344D03*
X1343344D03*
X1340344D03*
X1346534Y1411496D03*
Y1408496D03*
X1334344Y1414456D03*
X1346344Y1417456D03*
X1340344D03*
X1337344D03*
X1334386Y1420020D03*
X1334344Y1417456D03*
X1346386Y1420020D03*
X1343386D03*
X1340386D03*
X1337386D03*
X1343344Y1417456D03*
X1337428Y1422584D03*
X1340428D03*
X1343428D03*
X1334428D03*
X1337328Y1425164D03*
X1340328D03*
X1343328D03*
X1346178Y1425254D03*
X1346278Y1422674D03*
X1334470Y1425148D03*
X1348610Y84712D03*
X1349480Y77072D03*
X1366369Y83820D03*
X1349570Y104147D03*
X1353394Y131812D03*
X1348620Y136162D03*
X1349220Y140362D03*
X1348824Y328981D03*
X1358371Y332275D03*
X1361771D03*
X1355200Y337843D03*
X1351800D03*
X1356220Y581862D03*
X1356047Y680000D03*
X1358907Y681262D03*
X1361727Y680665D03*
X1352474Y1256866D03*
X1349964Y1256896D03*
X1352486Y1259373D03*
X1349976Y1259403D03*
X1363258Y1256851D03*
Y1259351D03*
X1349876Y1267158D03*
X1352426Y1267218D03*
X1363266Y1267188D03*
X1349976Y1261903D03*
X1352486Y1261873D03*
Y1264373D03*
X1349976Y1264403D03*
X1363258Y1261851D03*
X1363270Y1264358D03*
X1360593Y1321872D03*
X1363098Y1320951D03*
X1354238Y1329329D03*
X1350238Y1328591D03*
X1358448Y1330819D03*
X1356976Y1328361D03*
X1350238Y1331647D03*
X1352666Y1378560D03*
X1349666D03*
X1352666Y1381560D03*
X1349666D03*
X1352666Y1375940D03*
X1349666D03*
X1352126Y1401986D03*
X1349426D03*
X1352126Y1404986D03*
X1349426D03*
X1349508Y1420020D03*
X1352166Y1420456D03*
Y1414456D03*
Y1411456D03*
Y1408456D03*
Y1417456D03*
X1349466Y1411456D03*
Y1408456D03*
Y1417456D03*
Y1414456D03*
X1349278Y1422674D03*
X1364860Y1455172D03*
X1362410Y1445272D03*
X1378839Y87626D03*
X1366369Y92450D03*
X1366714Y109506D03*
X1376991Y176430D03*
X1373591D03*
X1375619Y236261D03*
X1375257Y229756D03*
X1373493Y227762D03*
X1370207Y682245D03*
X1374938Y1161569D03*
Y1170069D03*
X1379579Y1259317D03*
X1368379Y1259287D03*
X1379639Y1256747D03*
X1368439Y1256717D03*
X1365768Y1256821D03*
Y1259321D03*
X1365776Y1267158D03*
X1368326Y1267218D03*
X1379519Y1261917D03*
X1379531Y1264624D03*
X1379526Y1267248D03*
X1368361Y1264594D03*
X1368369Y1261897D03*
X1365768Y1261821D03*
X1365780Y1264328D03*
X1376076Y1317092D03*
Y1319592D03*
X1379192Y1325373D03*
X1368272Y1324821D03*
X1372538Y1324591D03*
X1370338Y1323091D03*
X1372538Y1321691D03*
X1365376Y1321938D03*
X1367635Y1320904D03*
X1377214Y1327653D03*
X1368272Y1327721D03*
X1370438Y1326091D03*
X1372538Y1327491D03*
X1377054Y1394028D03*
X1367316Y1399053D03*
Y1403458D03*
X1370577Y1421899D03*
X1367436Y1414778D03*
X1370891Y1410306D03*
X1378417Y1415292D03*
X1367316Y1407458D03*
X1367889Y1419235D03*
X1377075Y1425014D03*
X1365235Y1428637D03*
X1370250Y1433715D03*
X1367620Y1431472D03*
X1367170Y1453142D03*
X1368842Y1449261D03*
X1364800Y1449231D03*
X1368980Y1457122D03*
X1370041Y1460374D03*
X1393250Y93802D03*
X1386684Y145017D03*
X1386404Y149008D03*
X1394182Y171470D03*
X1398182D03*
X1395960Y226422D03*
X1393460D03*
X1386868Y222937D03*
X1384017Y223697D03*
X1386138Y225411D03*
X1384895Y221346D03*
X1381951Y221420D03*
X1381235Y236020D03*
X1390600Y248262D03*
X1392685Y498992D03*
X1387550Y502922D03*
X1387600Y499182D03*
X1391260Y507082D03*
X1396081Y1161569D03*
Y1153369D03*
Y1170069D03*
X1384652Y1256866D03*
X1382142Y1256896D03*
X1384664Y1259373D03*
X1382154Y1259403D03*
X1395436Y1256851D03*
Y1259351D03*
X1384586Y1267278D03*
X1395426Y1267188D03*
X1382036Y1267218D03*
X1382154Y1261903D03*
X1384664Y1261873D03*
Y1264373D03*
X1382154Y1264403D03*
X1395436Y1261851D03*
X1395448Y1264358D03*
X1392770Y1321177D03*
X1395100Y1321927D03*
X1386366Y1329329D03*
X1382366Y1328591D03*
X1390576Y1330819D03*
X1389104Y1328361D03*
X1382366Y1331647D03*
X1396311Y1385712D03*
X1398680Y1380582D03*
X1390474Y1385142D03*
X1387074Y1384272D03*
X1390513Y1395452D03*
X1387066Y1401734D03*
X1387291Y1408163D03*
X1387470Y1418302D03*
X1385109Y1410427D03*
X1390170Y1423942D03*
X1387068Y1413991D03*
X1381066Y1425008D03*
X1393630Y1426562D03*
X1388557Y1431645D03*
X1395907Y1430227D03*
X1395443Y1434700D03*
X1398569Y1437860D03*
X1383429Y1427652D03*
X1392620Y1446708D03*
X1389220D03*
X1382600Y1563480D03*
X1391655Y1570037D03*
X1391055Y1565037D03*
X1384840Y1565640D03*
X1386790Y1563610D03*
X1396600Y1590200D03*
Y1586400D03*
X1393000Y1590300D03*
X1395325Y1606862D03*
X1386200Y1645700D03*
X1386600Y1641400D03*
X1407029Y152732D03*
X1410370Y138742D03*
X1406970D03*
X1407029Y156132D03*
X1407178Y171684D03*
X1403778D03*
X1413900Y225212D03*
X1396900Y228932D03*
X1398831Y1161569D03*
Y1153369D03*
Y1170069D03*
X1411909Y1259257D03*
X1400599Y1256717D03*
X1411969Y1256687D03*
X1397946Y1256821D03*
Y1259321D03*
X1400539Y1259287D03*
X1400521Y1264594D03*
X1400529Y1261897D03*
X1397936Y1267158D03*
X1400486Y1267218D03*
X1411849Y1261857D03*
X1411861Y1264564D03*
X1411856Y1267188D03*
X1397946Y1261821D03*
X1397958Y1264328D03*
X1408204Y1317092D03*
Y1319592D03*
X1411320Y1325373D03*
X1400400Y1324821D03*
X1404666Y1324591D03*
X1402466Y1323091D03*
X1404666Y1321691D03*
X1397430Y1321177D03*
X1399760Y1321927D03*
X1408969Y1327645D03*
X1402566Y1326091D03*
X1400400Y1327721D03*
X1404666Y1327491D03*
X1401655Y1384676D03*
X1406461Y1383862D03*
X1415171Y1383692D03*
X1412961Y1387387D03*
X1412608Y1391687D03*
X1414362Y1402191D03*
X1414786Y1426890D03*
X1413440Y1436774D03*
X1409680Y1430613D03*
X1401371Y1434592D03*
X1410477Y1440117D03*
X1410038Y1434670D03*
X1403687Y1444711D03*
X1400287D03*
X1400220Y1518862D03*
X1409248Y1528862D03*
X1400160Y1543342D03*
X1404433Y1565037D03*
X1400695Y1570037D03*
X1400715Y1565037D03*
X1407440Y1557552D03*
X1404433Y1570037D03*
X1402536Y1576097D03*
X1402680Y1597700D03*
X1401300Y1619917D03*
X1410900Y1624800D03*
X1400000Y1626362D03*
Y1634362D03*
Y1638362D03*
X1410500Y1638862D03*
X1396900Y1642100D03*
X1428336Y232762D03*
X1415340Y231812D03*
X1418630Y220018D03*
X1422030D03*
X1413847Y239528D03*
X1426020Y261501D03*
X1431430Y256383D03*
Y264060D03*
X1426647Y329050D03*
X1417022Y621419D03*
X1424119Y1161520D03*
X1426619D03*
X1424119Y1153369D03*
X1426619D03*
Y1169570D03*
X1424119D03*
X1416999Y1256866D03*
X1414489Y1256896D03*
X1417011Y1259373D03*
X1414501Y1259403D03*
X1427783Y1256851D03*
Y1259351D03*
X1414366Y1267158D03*
X1416916Y1267218D03*
X1427786Y1267158D03*
X1414501Y1261903D03*
X1417011Y1261873D03*
Y1264373D03*
X1414501Y1264403D03*
X1427783Y1261851D03*
X1427795Y1264358D03*
X1424898Y1321177D03*
X1427228Y1321927D03*
X1418494Y1329329D03*
X1414494Y1328591D03*
X1422704Y1330819D03*
X1421232Y1328361D03*
X1414494Y1331647D03*
X1418990Y1387452D03*
X1422594Y1383301D03*
X1419995Y1397492D03*
X1415620Y1396652D03*
X1419055Y1392497D03*
X1426872Y1405811D03*
X1423256Y1403728D03*
X1424255Y1396612D03*
X1421480Y1415731D03*
X1422371Y1407722D03*
X1421371Y1411719D03*
X1421864Y1419730D03*
X1419991Y1423404D03*
X1424930Y1433850D03*
X1416272Y1433949D03*
X1421435Y1430415D03*
X1419746Y1435932D03*
X1414350Y1516435D03*
X1426020Y1521535D03*
X1414590Y1532255D03*
X1414350Y1521335D03*
X1427120Y1537355D03*
X1414590Y1537155D03*
X1414740Y1543475D03*
Y1548375D03*
X1427320Y1548575D03*
X1425620Y1556662D03*
X1416060Y1574922D03*
X1422680Y1582100D03*
X1419450Y1596150D03*
X1423700Y1600400D03*
X1434600Y59262D03*
X1444275Y57262D03*
X1432220Y61862D03*
X1440800Y66862D03*
X1447340Y157402D03*
X1442434Y210757D03*
X1430120Y225182D03*
X1431636Y230448D03*
X1444570Y238372D03*
X1431933Y238125D03*
X1431431Y267378D03*
X1436120Y315772D03*
X1436270Y312592D03*
X1436335Y309407D03*
X1436320Y305862D03*
Y303362D03*
X1436050Y321352D03*
X1436120Y318272D03*
X1436232Y344176D03*
X1433418Y729104D03*
X1444099Y1259397D03*
X1432899Y1259257D03*
X1444159Y1256827D03*
X1432959Y1256687D03*
X1430293Y1256821D03*
Y1259321D03*
X1444051Y1264704D03*
X1444039Y1261997D03*
X1444046Y1267328D03*
X1432889Y1261867D03*
X1432881Y1264564D03*
X1432846Y1267188D03*
X1430296Y1267128D03*
X1430293Y1261821D03*
X1430305Y1264328D03*
X1440332Y1317092D03*
Y1319592D03*
X1443448Y1325373D03*
X1432528Y1324821D03*
X1436794Y1324591D03*
X1434594Y1323091D03*
X1436794Y1321691D03*
X1429558Y1321177D03*
X1431888Y1321927D03*
X1441332Y1327793D03*
X1434694Y1326091D03*
X1432528Y1327721D03*
X1436794Y1327491D03*
X1437443Y1406289D03*
X1444997Y1392885D03*
X1435462Y1393009D03*
Y1396409D03*
X1434312Y1415197D03*
X1443112Y1417929D03*
X1445020Y1412672D03*
X1443676Y1432624D03*
X1433750Y1429208D03*
X1439742Y1436924D03*
X1434720Y1454862D03*
X1440440Y1454892D03*
X1444468Y1570610D03*
X1433720Y1569762D03*
X1440105Y1593352D03*
X1446700Y1598400D03*
X1438300Y1606800D03*
Y1602600D03*
X1430250Y1612812D03*
X1441800Y1628700D03*
Y1624500D03*
X1438547Y1638212D03*
X1443617D03*
X1431575Y1634842D03*
X1442573Y1649862D03*
X1442587Y1659242D03*
X1438320Y1668292D03*
X1438220Y1673955D03*
X1446715Y1679957D03*
X1446000Y67802D03*
X1458720Y145362D03*
X1450270Y143022D03*
X1450720Y153362D03*
X1448820Y148092D03*
X1450720Y169862D03*
Y161862D03*
X1449740Y166912D03*
X1450720Y181862D03*
Y177862D03*
Y173862D03*
X1462561Y205982D03*
X1457361D03*
X1459961Y210432D03*
X1456150Y214382D03*
X1449110Y233742D03*
X1455600Y297200D03*
X1456770Y342942D03*
X1460849Y343327D03*
X1462790Y359042D03*
X1462870Y355012D03*
X1449777Y362021D03*
X1459900Y370823D03*
X1455920Y373941D03*
X1463600Y374462D03*
X1449777Y371039D03*
X1455642Y409646D03*
X1449296Y407347D03*
X1449600Y402322D03*
X1456777Y418596D03*
Y426546D03*
X1456237Y726945D03*
X1457620Y736195D03*
X1460187Y729805D03*
X1455692Y731401D03*
X1457714Y741622D03*
X1447149Y1161569D03*
X1449649D03*
X1447299Y1153369D03*
X1449799D03*
X1447149Y1170069D03*
X1449649D03*
X1449176Y1256866D03*
X1446666Y1256896D03*
X1449188Y1259373D03*
X1446678Y1259403D03*
X1459960Y1259351D03*
Y1256851D03*
X1449106Y1267358D03*
X1459886Y1267218D03*
X1446556Y1267298D03*
X1446678Y1261903D03*
X1449188Y1261873D03*
Y1264373D03*
X1446678Y1264403D03*
X1459960Y1261851D03*
X1459972Y1264358D03*
X1457026Y1321177D03*
X1461686D03*
X1459356Y1321927D03*
X1450622Y1329329D03*
X1446622Y1328591D03*
X1454832Y1330819D03*
X1453360Y1328361D03*
X1446622Y1331647D03*
X1459968Y1402765D03*
X1451176Y1399026D03*
X1451198Y1403047D03*
X1460224Y1407545D03*
X1458138Y1409955D03*
X1461062Y1413246D03*
X1455006Y1447938D03*
X1459111Y1445669D03*
Y1448669D03*
X1457577Y1526689D03*
X1457817Y1542509D03*
X1457967Y1553729D03*
X1458200Y1565037D03*
Y1560037D03*
X1448620Y1556162D03*
X1456030Y1590302D03*
X1456120Y1586262D03*
X1453600Y1595662D03*
X1451500Y1612800D03*
X1454167Y1638302D03*
X1459127D03*
X1448507Y1638212D03*
X1448920Y1675062D03*
X1474142Y61767D03*
X1462000Y153362D03*
X1470220Y169862D03*
X1473090Y204502D03*
X1472335Y209362D03*
X1467761Y205982D03*
X1471308Y230640D03*
X1463833Y230448D03*
X1474660Y252878D03*
X1463808Y244948D03*
X1463833Y235566D03*
X1473820Y265962D03*
X1471510Y252878D03*
X1471690Y259862D03*
X1463950Y258172D03*
X1463330Y264060D03*
X1463510Y273878D03*
X1475452Y289708D03*
X1475352Y306308D03*
X1476826Y312177D03*
X1467700Y370953D03*
X1472758Y370817D03*
X1465836Y408668D03*
X1470942Y409718D03*
X1475250Y401812D03*
X1469777Y418396D03*
X1469951Y429251D03*
X1469720Y434542D03*
X1469760Y452622D03*
X1471460Y633402D03*
X1468060D03*
X1465171Y647132D03*
X1469020Y647102D03*
X1470841Y721493D03*
X1464999Y1259317D03*
X1476369Y1259237D03*
X1465059Y1256747D03*
X1462470Y1259321D03*
Y1256821D03*
X1476291Y1275224D03*
X1464946Y1267248D03*
X1464989Y1261927D03*
X1464981Y1264624D03*
X1476339Y1264467D03*
Y1267037D03*
X1476309Y1261807D03*
X1476279Y1269637D03*
X1476291Y1272344D03*
X1462396Y1267188D03*
X1462470Y1261821D03*
X1462482Y1264328D03*
X1476291Y1278104D03*
X1464016Y1321927D03*
X1466819Y1324018D03*
X1469019Y1322618D03*
X1473956Y1341068D03*
X1472460Y1330493D03*
Y1333043D03*
X1475576Y1338799D03*
X1469019Y1325518D03*
X1464680Y1325772D03*
X1469019Y1328418D03*
X1466919Y1327018D03*
X1464680Y1328672D03*
X1467567Y1445669D03*
Y1448669D03*
X1475967Y1445669D03*
Y1448669D03*
X1478320Y1522962D03*
X1472565Y1623635D03*
X1478061Y1633864D03*
X1463767Y1638302D03*
X1476570Y1661124D03*
X1482650Y-29811D03*
Y-33211D03*
Y-9811D03*
Y-13211D03*
X1493120Y240412D03*
X1487958Y236062D03*
X1490060Y255378D03*
X1485320Y260362D03*
X1478745Y281508D03*
X1493289Y280027D03*
X1478526Y289677D03*
X1481445Y289708D03*
X1479745Y312208D03*
X1478426Y306277D03*
X1481345Y306308D03*
X1481484Y361688D03*
X1481766Y372288D03*
X1489443D03*
X1494784Y374188D03*
X1486040Y368392D03*
X1481766Y406238D03*
X1490384Y407292D03*
X1493384Y411313D03*
X1482650Y411190D03*
X1495527Y406215D03*
X1486880Y416863D03*
X1484805Y427577D03*
X1489310Y426822D03*
X1481539Y1259377D03*
X1478999Y1259257D03*
X1481479Y1261947D03*
X1481419Y1264547D03*
X1481431Y1267254D03*
X1478939Y1261827D03*
X1478879Y1264427D03*
X1478891Y1267134D03*
X1481359Y1271447D03*
X1492039D03*
X1481359Y1274144D03*
X1492091D03*
X1478859Y1271417D03*
Y1274114D03*
X1481361Y1280054D03*
X1492101D03*
X1478821D03*
X1481359Y1277024D03*
X1492091D03*
X1478859Y1276994D03*
X1489154Y1334603D03*
X1493814D03*
X1491484Y1335353D03*
X1482750Y1342755D03*
X1478750Y1342017D03*
X1486960Y1344245D03*
X1485488Y1341787D03*
X1478750Y1345073D03*
X1485387Y1420002D03*
X1481918Y1425579D03*
X1484442Y1445557D03*
Y1448557D03*
X1482830Y1525162D03*
X1480800Y1663600D03*
X1510500Y125992D03*
X1508959Y215802D03*
X1503020D03*
X1499922Y211240D03*
X1496720Y225292D03*
X1504484Y234562D03*
X1508410Y230842D03*
X1510017Y225516D03*
X1501840Y225502D03*
X1512420Y239116D03*
X1510810Y249742D03*
X1509040Y243362D03*
X1504890Y249862D03*
X1506600Y239092D03*
X1504650Y254392D03*
X1508049Y280056D03*
X1498984Y282797D03*
X1508558Y291175D03*
X1512244Y311522D03*
X1505922Y304583D03*
X1509539Y308467D03*
X1498184Y361723D03*
Y369798D03*
X1495150Y369842D03*
X1503450Y385843D03*
X1509638Y738627D03*
X1509350Y741315D03*
X1504747Y747293D03*
X1503514Y801361D03*
Y797961D03*
X1497199Y1275667D03*
X1497259Y1273097D03*
X1494629Y1271477D03*
X1494631Y1274144D03*
X1506569Y1285947D03*
X1508819Y1284797D03*
X1506539Y1288557D03*
X1508759Y1287367D03*
X1508699Y1289967D03*
X1494641Y1280054D03*
X1494631Y1277024D03*
X1506551Y1291254D03*
X1497199Y1278277D03*
X1497161Y1280974D03*
X1506689Y1283377D03*
X1506591Y1297014D03*
Y1294134D03*
X1508711Y1295554D03*
Y1298434D03*
Y1292674D03*
X1496784Y1341147D03*
X1498924Y1334882D03*
X1498950Y1339517D03*
X1501149Y1336287D03*
X1496784Y1338247D03*
X1496144Y1335353D03*
X1504588Y1353316D03*
Y1355816D03*
X1501033Y1341462D03*
X1498959Y1342930D03*
X1505570Y1364212D03*
X1507704Y1361597D03*
X1510027Y1425825D03*
X1507617Y1424045D03*
X1522920Y116180D03*
X1513900Y117762D03*
X1518575Y138662D03*
X1521115Y193262D03*
X1524539Y215551D03*
X1522009Y210825D03*
X1518110Y215551D03*
X1526998Y209645D03*
X1527732Y219488D03*
X1514520Y231116D03*
X1526152Y225114D03*
X1514593Y249698D03*
Y235116D03*
X1519758Y265161D03*
X1522786Y262558D03*
X1522258Y265161D03*
X1519833Y277297D03*
X1522258Y288956D03*
X1517669Y291516D03*
X1515940Y795815D03*
Y799215D03*
X1513789Y1290037D03*
X1511289Y1287397D03*
X1511199Y1290007D03*
X1513791Y1292704D03*
X1516351D03*
X1513791Y1298464D03*
Y1295584D03*
X1516351D03*
Y1298464D03*
X1511251Y1292704D03*
Y1298464D03*
Y1295584D03*
X1521282Y1357401D03*
X1525942D03*
X1514878Y1365553D03*
X1510878Y1364815D03*
X1519088Y1367043D03*
X1517616Y1364585D03*
X1510878Y1367871D03*
X1523612Y1358151D03*
X1512177Y1427795D03*
X1516137Y1432135D03*
X1513657Y1429985D03*
X1544010Y27552D03*
X1536310Y47492D03*
X1534060Y100162D03*
X1530660D03*
X1533520Y110662D03*
X1529500Y122122D03*
X1535575Y118862D03*
X1540090Y122782D03*
X1536925Y129937D03*
X1529500Y125862D03*
X1535520Y151562D03*
X1529233Y153162D03*
X1535450Y155262D03*
X1542401Y141561D03*
X1534720Y199803D03*
X1528720Y199862D03*
X1533385Y193108D03*
X1533148Y211614D03*
X1531824Y207677D03*
X1534194Y217519D03*
X1529670Y225522D03*
X1535561Y225393D03*
X1531110Y264862D03*
X1539150Y267132D03*
X1540958Y307756D03*
X1539720Y589862D03*
Y581862D03*
X1540377Y634165D03*
X1541211Y646178D03*
X1533178Y1360815D03*
X1530978Y1359315D03*
X1528912Y1361045D03*
X1531078Y1362315D03*
X1533178Y1363715D03*
X1528912Y1363945D03*
X1533178Y1357915D03*
X1528272Y1358151D03*
X1552960Y124359D03*
X1553189Y127781D03*
X1556049Y147711D03*
X1545763Y159305D03*
X1551160Y189342D03*
X1557900Y220362D03*
X1557760Y214792D03*
X1550353Y217352D03*
X1557320Y203297D03*
X1559400Y229832D03*
X1545668Y305266D03*
X1545768Y302766D03*
X1543958Y307556D03*
X1546458Y307856D03*
X1543858Y310056D03*
X1543720Y581862D03*
X1548720D03*
X1552720Y589862D03*
Y581862D03*
X1554753Y628860D03*
X1553312Y636815D03*
X1559354Y655716D03*
Y659116D03*
X1550487Y681565D03*
X1550320Y696562D03*
X1550917Y704332D03*
X1550390Y709885D03*
X1573560Y245078D03*
X1574760Y251032D03*
X1559722Y243110D03*
X1570675Y267857D03*
X1573246Y306650D03*
X1572396Y309450D03*
X1563714Y572792D03*
X1567114D03*
X1559557Y593290D03*
X1564768Y708159D03*
X1562871Y732316D03*
Y735716D03*
X1571577Y747145D03*
X1567547Y755485D03*
X1571920Y762662D03*
X1568490Y758162D03*
X1570374Y760093D03*
X1576589Y300927D03*
X1588314Y592553D03*
X1585714D03*
X1583114D03*
X1590914D03*
X1588254Y595103D03*
X1588284Y597613D03*
X1585654Y595103D03*
X1585684Y597613D03*
X1583084D03*
X1583054Y595103D03*
X1588284Y608655D03*
X1585684D03*
X1583084D03*
X1590854Y595103D03*
X1590884Y597613D03*
Y608655D03*
X1588254Y613715D03*
X1588224Y611205D03*
X1585654Y613715D03*
X1585624Y611205D03*
X1583024D03*
X1583054Y613715D03*
X1590854D03*
X1590824Y611205D03*
X1591368Y628727D03*
X1591428Y626177D03*
X1588928D03*
X1588868Y628727D03*
X1591398Y631237D03*
X1588898D03*
X1591368Y650877D03*
X1591338Y648367D03*
X1591398Y645817D03*
X1588868Y650877D03*
X1588838Y648367D03*
X1588898Y645817D03*
X1591368Y653377D03*
X1588868D03*
X1591448Y657677D03*
X1588948D03*
Y660177D03*
X1591448D03*
X1588968Y665237D03*
X1591468D03*
X1588938Y662727D03*
X1591438D03*
X1588938Y679807D03*
X1588878Y682357D03*
X1588908Y684867D03*
X1591438Y679807D03*
X1591378Y682357D03*
X1591408Y684867D03*
X1591328Y696727D03*
X1591388Y694177D03*
X1588888D03*
X1588828Y696727D03*
X1591358Y699277D03*
X1588858D03*
X1591358Y718837D03*
X1591328Y716327D03*
X1591388Y713777D03*
X1588858Y718837D03*
X1588828Y716327D03*
X1588888Y713777D03*
X1590915Y755793D03*
X1603747Y192951D03*
X1603530Y202402D03*
X1603706Y211526D03*
X1603580Y206902D03*
X1604200Y234642D03*
X1604240Y227892D03*
X1603920Y222922D03*
X1604270Y231490D03*
X1604240Y238242D03*
X1602980Y560002D03*
X1593514Y592553D03*
X1601830Y590685D03*
X1604430D03*
X1607200Y583962D03*
X1593484Y597613D03*
X1593454Y595103D03*
X1593484Y608655D03*
X1593424Y611205D03*
X1593454Y613715D03*
X1601830Y615201D03*
X1604430D03*
X1598868Y628727D03*
X1598928Y626177D03*
X1593868Y628727D03*
X1593928Y626177D03*
X1596428D03*
X1596368Y628727D03*
X1598898Y631237D03*
X1593898D03*
X1596398D03*
X1598868Y650877D03*
X1598838Y648367D03*
X1596368Y650877D03*
X1593868D03*
X1596338Y648367D03*
X1593838D03*
X1598898Y645817D03*
X1596398D03*
X1593898D03*
X1598868Y653377D03*
X1596368D03*
X1593868D03*
X1598948Y657677D03*
X1593948D03*
X1596448D03*
Y660177D03*
X1593948D03*
X1598948D03*
X1596468Y665237D03*
X1593968D03*
X1598968D03*
X1596438Y662727D03*
X1593938D03*
X1598938D03*
X1593938Y679807D03*
X1596438D03*
X1593878Y682357D03*
X1596378D03*
X1593908Y684867D03*
X1596408D03*
X1598878Y682357D03*
X1598908Y684867D03*
X1598938Y679807D03*
X1596288Y688902D03*
X1598888D03*
X1598828Y696727D03*
X1593828D03*
X1593888Y694177D03*
X1596388D03*
X1596328Y696727D03*
X1593858Y699277D03*
X1596358D03*
X1598888Y694177D03*
X1596288Y691502D03*
X1598858Y699277D03*
X1598888Y691502D03*
X1598858Y718837D03*
X1598828Y716327D03*
X1596358Y718837D03*
X1593858D03*
X1596328Y716327D03*
X1593828D03*
X1596388Y713777D03*
X1593888D03*
X1598888D03*
X1596250Y721452D03*
X1598850D03*
X1599010Y724002D03*
X1598440Y736692D03*
X1592760Y736652D03*
X1595600D03*
X1606788Y756199D03*
X1602788D03*
X1621920Y25962D03*
X1622220Y49862D03*
X1623881Y129627D03*
X1610788Y756199D03*
X1614788D03*
X1618788D03*
X1615062Y1421241D03*
X1613047Y1415669D03*
X1614927Y1426076D03*
Y1429896D03*
X1624353Y1428766D03*
Y1431316D03*
X1617215Y1440822D03*
X1633111Y206693D03*
X1632342Y216015D03*
X1635835Y343002D03*
X1636800Y429982D03*
X1639800D03*
X1636800Y426982D03*
X1639800D03*
X1636800Y438982D03*
X1639800D03*
X1636800Y435982D03*
X1639800D03*
X1636800Y432982D03*
X1639800D03*
X1638928Y756199D03*
X1630928D03*
X1634928D03*
X1638277Y1269065D03*
X1640812Y1270020D03*
X1631203Y1367492D03*
X1628653D03*
X1626153D03*
X1628653Y1372492D03*
X1631203D03*
X1626153D03*
X1631203Y1369992D03*
X1628653D03*
X1626153D03*
X1628653Y1379992D03*
Y1382492D03*
Y1377492D03*
Y1374992D03*
X1631203Y1377492D03*
Y1374992D03*
Y1379992D03*
Y1382492D03*
X1626153Y1379992D03*
Y1382492D03*
Y1374992D03*
Y1377492D03*
X1630643Y1440290D03*
X1627469Y1437072D03*
X1624853Y1440875D03*
X1634643Y1442982D03*
X1638785Y1442483D03*
X1637042Y1440215D03*
X1630643Y1443090D03*
X1635315Y1465745D03*
Y1462745D03*
X1632315Y1468745D03*
X1629815D03*
X1632315Y1465745D03*
X1629815D03*
X1632315Y1462745D03*
X1629815D03*
X1635315Y1468745D03*
Y1460245D03*
X1629815D03*
X1632315D03*
X1629815Y1457745D03*
X1632315D03*
X1635315D03*
X1639645Y1473645D03*
X1650020Y408952D03*
X1647310Y408922D03*
X1650020Y411452D03*
X1647310Y411422D03*
X1654110Y434177D03*
X1657755Y517910D03*
X1651851Y532057D03*
X1651112Y545572D03*
X1645530Y549160D03*
X1653230Y549322D03*
X1642720Y560862D03*
X1656238Y592113D03*
X1649833Y594946D03*
X1653794Y594956D03*
X1653774Y598576D03*
X1649844Y598555D03*
X1656955Y611090D03*
X1645300Y612202D03*
X1653220Y620662D03*
X1645681Y624011D03*
X1648581D03*
X1651481D03*
X1654809Y638101D03*
X1653319Y642311D03*
X1652351Y639573D03*
X1648811Y628277D03*
X1647081Y626211D03*
X1645917Y628917D03*
Y633577D03*
X1645167Y631247D03*
Y635907D03*
X1650081Y626111D03*
X1651711Y628277D03*
X1651635Y651836D03*
X1652581Y646311D03*
X1643582Y652601D03*
X1655637Y646311D03*
X1641082Y652601D03*
X1649363Y649485D03*
X1654809Y672101D03*
X1652351Y673573D03*
X1645681Y658011D03*
X1648581D03*
X1648811Y662277D03*
X1647081Y660211D03*
X1645917Y662917D03*
Y667577D03*
X1645167Y665247D03*
Y669907D03*
X1650081Y660111D03*
X1651481Y658011D03*
X1651711Y662277D03*
X1641082Y686601D03*
X1651635Y685836D03*
X1652581Y680311D03*
X1653319Y676311D03*
X1643582Y686601D03*
X1655113Y680835D03*
X1649363Y683485D03*
X1654809Y706101D03*
X1648811Y696277D03*
X1645167Y703907D03*
X1645917Y701577D03*
X1645167Y699247D03*
X1645917Y696917D03*
X1650081Y694111D03*
X1645681Y692011D03*
X1647081Y694211D03*
X1648581Y692011D03*
X1651711Y696277D03*
X1651481Y692011D03*
X1641082Y720601D03*
X1651635Y719836D03*
X1652581Y714311D03*
X1653319Y710311D03*
X1652351Y707573D03*
X1643582Y720601D03*
X1655637Y714311D03*
X1649363Y717485D03*
X1651509Y756492D03*
X1650771Y1367492D03*
X1648271D03*
X1645721D03*
X1648271Y1372492D03*
X1650771D03*
X1645721D03*
X1650771Y1369992D03*
X1648271D03*
X1645721D03*
X1648271Y1379992D03*
Y1382492D03*
X1650771Y1379992D03*
Y1382492D03*
X1648271Y1377492D03*
Y1374992D03*
X1650771Y1377492D03*
Y1374992D03*
X1645721Y1377492D03*
Y1374992D03*
Y1379992D03*
Y1382492D03*
X1641047Y1432876D03*
X1645707D03*
X1643377Y1433626D03*
X1648037D03*
X1655762Y1429794D03*
X1648677Y1436220D03*
X1653243Y1435690D03*
X1651043Y1434190D03*
X1653243Y1432790D03*
X1651143Y1437190D03*
X1653243Y1438590D03*
X1648677Y1439120D03*
X1655295Y1453879D03*
X1652295D03*
X1643065Y1462645D03*
Y1465645D03*
Y1468645D03*
Y1460145D03*
Y1457645D03*
X1655295Y1456899D03*
X1652295D03*
X1642645Y1473645D03*
X1646958Y1501553D03*
X1668100Y180852D03*
X1667739Y187187D03*
X1666690Y193290D03*
X1674432Y216981D03*
X1672596Y220541D03*
X1668426Y222432D03*
X1664866Y225162D03*
X1660861Y227548D03*
X1664970Y472112D03*
X1662447Y480619D03*
X1665790Y523417D03*
X1662262Y537334D03*
X1659740Y542222D03*
X1661872Y534703D03*
X1660243Y532071D03*
X1668917Y549992D03*
X1666902Y555115D03*
X1663502D03*
X1658738Y592113D03*
X1661238D03*
X1664197Y602191D03*
X1669222Y604490D03*
X1670700Y594562D03*
X1672500Y596462D03*
X1660660Y602273D03*
X1664410Y617953D03*
X1668920Y617637D03*
X1660754Y609837D03*
X1669397Y614064D03*
X1663471Y609837D03*
X1666686Y757162D03*
X1669303Y1372492D03*
X1664253D03*
X1666753D03*
X1669303Y1367492D03*
Y1369992D03*
X1666753Y1367492D03*
X1664253D03*
Y1369992D03*
X1666753D03*
X1669303Y1379992D03*
Y1382492D03*
Y1377492D03*
Y1374992D03*
X1666753Y1379992D03*
X1664253D03*
X1666753Y1382492D03*
X1664253D03*
X1666753Y1377492D03*
X1664253D03*
Y1374992D03*
X1666753D03*
X1662496Y1428791D03*
Y1431291D03*
X1665612Y1437072D03*
X1662996Y1440922D03*
X1672786Y1442982D03*
X1668786Y1440290D03*
Y1443256D03*
X1657920Y1453405D03*
X1660920D03*
X1657860Y1466545D03*
Y1464045D03*
X1657950Y1456210D03*
X1657860Y1459045D03*
Y1461545D03*
X1660950Y1456210D03*
X1660860Y1466545D03*
Y1464045D03*
Y1459045D03*
Y1461545D03*
X1666123Y1493362D03*
Y1501362D03*
Y1533862D03*
Y1520862D03*
Y1545862D03*
X1671673Y1550815D03*
X1666123Y1557557D03*
X1666198Y1561557D03*
X1671660Y1569412D03*
X1666198Y1581321D03*
X1678994Y217231D03*
X1690208Y421855D03*
X1689095Y462640D03*
X1684940Y463030D03*
X1685779Y491230D03*
X1690229Y481845D03*
X1687238Y485496D03*
X1681817Y495290D03*
X1675664Y513802D03*
X1690999Y513107D03*
X1683702Y514687D03*
X1676600Y523902D03*
X1688768Y518107D03*
X1689544Y543874D03*
X1689506Y539882D03*
X1679941Y552222D03*
X1678860Y556752D03*
X1683369Y562698D03*
Y566098D03*
X1676644Y655345D03*
Y652745D03*
X1679244Y655345D03*
X1681864Y655286D03*
X1679244Y652745D03*
X1676624Y642404D03*
X1676644Y644945D03*
Y647545D03*
Y650145D03*
X1679244Y642345D03*
X1681864Y642286D03*
X1679244Y644945D03*
Y647545D03*
X1681864Y644886D03*
Y647486D03*
Y650086D03*
Y652686D03*
X1679244Y650145D03*
X1673860Y726522D03*
X1681810Y752955D03*
X1688912Y1372492D03*
X1686362D03*
Y1367492D03*
Y1369992D03*
X1688912Y1367492D03*
Y1369992D03*
Y1377492D03*
Y1374992D03*
Y1382492D03*
Y1379992D03*
X1686362D03*
Y1382492D03*
Y1374992D03*
Y1377492D03*
X1679190Y1432876D03*
X1683850D03*
X1681520Y1433626D03*
X1686180D03*
X1686820Y1436520D03*
X1688886Y1434790D03*
X1688986Y1437790D03*
X1676928Y1442483D03*
X1675185Y1440215D03*
X1686820Y1439420D03*
X1680720Y1487062D03*
X1679508Y1498303D03*
X1678340Y1500862D03*
X1679508Y1517803D03*
X1677930Y1520362D03*
X1679508Y1538803D03*
X1678340Y1541362D03*
X1678230Y1590542D03*
X1674220Y1585321D03*
X1703617Y26459D03*
X1700217D03*
X1703570Y50649D03*
X1700170D03*
X1702490Y204780D03*
X1704223Y209707D03*
Y212207D03*
X1701164Y209758D03*
X1698566Y214904D03*
X1696066D03*
X1693725Y217409D03*
X1698566Y212404D03*
X1696066D03*
X1698725Y217409D03*
X1696225D03*
X1701164Y212258D03*
X1704264Y217458D03*
X1701264D03*
X1704264Y214958D03*
X1701264D03*
X1698566Y209704D03*
X1696066D03*
X1693466Y209504D03*
Y214704D03*
Y212204D03*
X1693725Y219909D03*
X1698725D03*
X1696225D03*
X1704264Y219958D03*
X1701264D03*
X1704185Y222710D03*
X1698220Y369652D03*
X1699809Y403985D03*
X1695579D03*
X1702959Y404243D03*
X1707780Y410738D03*
X1697161Y406602D03*
X1692429Y403985D03*
X1701124Y423802D03*
X1694050Y416643D03*
X1695455Y422287D03*
X1707544Y431745D03*
X1707568Y420370D03*
X1690140Y434160D03*
X1693720Y455862D03*
X1697220D03*
X1702127Y468719D03*
X1693236Y472650D03*
X1691151Y493678D03*
X1689943Y479304D03*
X1701811Y501318D03*
X1701635Y497177D03*
X1699300Y498632D03*
X1697210Y500802D03*
X1694050Y501422D03*
X1693711Y498527D03*
X1691129Y501697D03*
X1707200Y498962D03*
X1699553Y513107D03*
X1707552Y506731D03*
X1707716Y513562D03*
X1702930Y526102D03*
X1699265Y521507D03*
X1690999Y525507D03*
X1701726Y518107D03*
X1699666Y541507D03*
X1699251Y533642D03*
X1691104Y530503D03*
X1691445Y535011D03*
X1704886Y534564D03*
X1689769Y537339D03*
X1699107Y555783D03*
X1703306Y550064D03*
X1703452Y639381D03*
X1700852D03*
X1698232Y639440D03*
X1700852Y655141D03*
X1703452Y647341D03*
Y649941D03*
Y652541D03*
Y644741D03*
X1700852Y647341D03*
Y649941D03*
Y652541D03*
Y644741D03*
X1698232Y655200D03*
Y644800D03*
Y647400D03*
Y650000D03*
Y652600D03*
X1703452Y641981D03*
X1700852D03*
X1698232Y642040D03*
X1700922Y657781D03*
X1698302Y657840D03*
X1698048Y705662D03*
X1701320Y705678D03*
X1698020Y702962D03*
X1696402Y709533D03*
X1699110Y727452D03*
X1705035Y729210D03*
X1704973Y753019D03*
X1703310Y749455D03*
X1690620Y760702D03*
X1691412Y1372492D03*
Y1367492D03*
Y1369992D03*
Y1377492D03*
Y1374992D03*
Y1382492D03*
Y1379992D03*
X1691086Y1436290D03*
Y1433390D03*
X1693392Y1429808D03*
X1691086Y1439190D03*
X1704723Y1500862D03*
Y1520362D03*
Y1541362D03*
X1705003Y1564057D03*
X1707220Y15662D03*
X1715210Y18282D03*
X1714589Y21562D03*
X1709589Y26062D03*
X1719589Y25862D03*
X1717089D03*
X1710106Y48720D03*
Y40020D03*
X1720895Y68062D03*
X1716875D03*
X1712520Y117862D03*
X1712720Y111862D03*
X1719943Y112667D03*
Y116667D03*
X1713418Y130862D03*
X1721418Y135327D03*
X1717418D03*
X1714490Y142920D03*
X1717140Y148910D03*
X1711700Y140200D03*
X1717619Y165909D03*
X1718110Y159040D03*
X1719530Y162950D03*
X1722078Y189483D03*
X1720310Y191252D03*
X1707159Y217580D03*
Y215080D03*
Y210080D03*
Y222580D03*
Y225080D03*
Y220080D03*
X1713720Y381152D03*
X1717220D03*
X1719200Y371162D03*
X1713720Y391652D03*
Y384652D03*
Y388152D03*
X1717220Y391652D03*
Y388152D03*
Y384652D03*
X1709000Y413362D03*
X1706500D03*
X1709000Y415862D03*
X1706500D03*
X1721220Y458362D03*
X1713977Y457137D03*
X1708977Y458542D03*
X1721936Y469263D03*
X1716134Y478443D03*
X1715711Y474399D03*
X1713977Y470804D03*
X1708977D03*
X1716148Y483720D03*
X1716087Y495665D03*
X1716156Y487685D03*
X1716278Y491676D03*
X1707552Y503331D03*
X1709844Y516106D03*
X1707610Y534113D03*
X1709356Y541144D03*
X1709680Y545432D03*
X1716110Y532632D03*
X1707346Y547504D03*
X1717987Y569705D03*
X1716480Y691410D03*
X1710550Y691327D03*
X1712824Y696476D03*
X1710122Y703509D03*
X1713920Y700962D03*
X1709828Y719283D03*
X1713450Y728222D03*
X1719727Y1472088D03*
X1726720Y49862D03*
X1733720D03*
X1730220D03*
X1736040Y41792D03*
X1732810Y52482D03*
X1736040Y44292D03*
X1730140Y52552D03*
X1727600Y52582D03*
X1725320Y67962D03*
X1723018Y101667D03*
X1723218Y93267D03*
X1738220Y98862D03*
X1736720Y101862D03*
X1729080Y118132D03*
X1739720Y120892D03*
X1728999Y112895D03*
X1730765Y151362D03*
X1733920D03*
X1723670Y149102D03*
X1728320Y169862D03*
X1723090Y173072D03*
Y177072D03*
X1734857Y184865D03*
X1737470Y177147D03*
X1737500Y217962D03*
Y214962D03*
Y211962D03*
Y208962D03*
Y226962D03*
Y223962D03*
Y220962D03*
X1725344Y359334D03*
X1728300Y377787D03*
X1733780Y390620D03*
X1729810D03*
X1737660D03*
X1734290Y423820D03*
X1727700Y417265D03*
X1739316Y480939D03*
X1730954Y478062D03*
X1725522Y482869D03*
X1733354Y490869D03*
Y486869D03*
X1738014Y1287344D03*
X1724431Y1336311D03*
X1734717Y1404340D03*
X1729700Y1462932D03*
X1733200D03*
X1736700D03*
X1736400Y1458942D03*
Y1455442D03*
X1731600Y1457230D03*
X1726120Y1490262D03*
X1726149Y1496270D03*
X1724649Y1513945D03*
X1727674D03*
X1729310Y1520951D03*
X1735310D03*
X1724649Y1505895D03*
X1727674D03*
X1726310Y1530445D03*
X1732310D03*
X1729310D03*
X1735310D03*
X1726310Y1520951D03*
X1732310D03*
X1751065Y39017D03*
X1754620Y39062D03*
X1747720Y31862D03*
Y34362D03*
X1740858Y72330D03*
Y79830D03*
Y74830D03*
Y82330D03*
X1745220Y98862D03*
X1741720D03*
X1743720Y101862D03*
X1740220D03*
X1748720Y97362D03*
X1745010Y122952D03*
X1750820Y119972D03*
X1738520Y151362D03*
X1751220Y147562D03*
X1748465D03*
X1754120Y171562D03*
X1750920Y171662D03*
X1754234Y190836D03*
X1752078Y216728D03*
X1740500Y217962D03*
Y214962D03*
Y211962D03*
Y208962D03*
X1747600Y209062D03*
X1744600D03*
X1751800Y206762D03*
X1752078Y226728D03*
Y224228D03*
Y221728D03*
Y219228D03*
X1740500Y226962D03*
Y223962D03*
Y220962D03*
X1746484Y279682D03*
X1749450Y293862D03*
X1756204Y301695D03*
X1752000Y306562D03*
X1756933Y372452D03*
X1744380Y382892D03*
X1744510Y377452D03*
X1747080Y435870D03*
X1746720Y464862D03*
X1752316Y703969D03*
Y695669D03*
X1752217Y692988D03*
X1752276Y720529D03*
X1752316Y712269D03*
X1747814Y1287344D03*
X1742714Y1287244D03*
X1754165Y1304422D03*
Y1307422D03*
Y1301422D03*
Y1295422D03*
Y1298422D03*
Y1310422D03*
X1738740Y1451742D03*
X1740200Y1462932D03*
X1745111Y1463262D03*
X1747677Y1507388D03*
X1744677D03*
X1747304Y1524976D03*
X1744304D03*
X1762420Y21562D03*
X1765238Y22062D03*
X1768026Y24165D03*
X1769669Y15244D03*
X1761998Y15187D03*
X1765260Y18262D03*
X1757320Y15872D03*
X1758672Y26431D03*
X1755272D03*
X1767220Y26962D03*
X1758669Y50649D03*
X1755269D03*
X1762738Y53262D03*
X1767220Y53342D03*
X1767185Y48817D03*
X1767400Y39915D03*
X1769274Y50742D03*
X1771774Y53682D03*
X1758063Y72623D03*
X1767170Y83607D03*
X1767990Y76797D03*
X1760478Y90027D03*
X1770368Y72691D03*
X1757978Y116727D03*
X1760978D03*
X1763678Y106127D03*
X1769278Y108027D03*
Y110927D03*
Y113727D03*
X1755978Y108427D03*
Y111027D03*
X1760478Y106127D03*
X1758300Y128242D03*
X1763435Y166862D03*
X1765820Y182282D03*
X1767300Y174587D03*
X1755078Y216928D03*
X1761500Y214062D03*
X1765000D03*
X1768500D03*
X1755078Y219428D03*
Y221928D03*
Y224428D03*
X1760104Y301648D03*
X1761936Y310709D03*
X1769230Y310478D03*
X1756800Y364048D03*
Y368048D03*
X1770280Y372452D03*
X1770220Y377452D03*
Y382952D03*
X1757066Y435721D03*
X1757650Y461393D03*
X1768560Y539042D03*
X1766060D03*
X1768317Y686375D03*
X1755112Y703948D03*
Y695648D03*
X1755013Y692967D03*
X1757612Y703948D03*
Y695648D03*
X1755072Y720508D03*
X1755112Y712248D03*
X1757572Y720508D03*
X1757612Y712248D03*
X1757165Y1304422D03*
X1760165D03*
Y1307422D03*
X1757165D03*
X1769165Y1301422D03*
X1766165D03*
X1763165D03*
X1757165D03*
X1760165D03*
X1769165Y1295422D03*
X1766165D03*
X1763165D03*
X1760165D03*
X1757165D03*
X1760165Y1298422D03*
X1757165D03*
X1763165D03*
X1766165D03*
X1769165D03*
X1758352Y1317368D03*
Y1322168D03*
X1757165Y1310422D03*
X1760165D03*
X1759987Y1325375D03*
Y1328275D03*
X1763829Y1337548D03*
X1766829D03*
Y1340448D03*
X1769829Y1337548D03*
Y1340448D03*
X1766829Y1343348D03*
X1769829Y1346248D03*
Y1343348D03*
Y1349148D03*
Y1351858D03*
X1782305Y13647D03*
X1775556Y21471D03*
X1775830Y26522D03*
X1777754Y37746D03*
X1781774Y54462D03*
X1774274Y50742D03*
X1776710Y53562D03*
X1779411Y50692D03*
X1774328Y60087D03*
X1779778Y70027D03*
X1774328Y62987D03*
X1775580Y73330D03*
X1779778Y72927D03*
X1787790Y85132D03*
X1781485Y88192D03*
X1785142Y76032D03*
X1773611Y88293D03*
X1778578Y97927D03*
X1778478Y90627D03*
X1784178Y108227D03*
Y111127D03*
Y113927D03*
X1780320Y153162D03*
X1774950Y167392D03*
X1779500Y171692D03*
X1777520Y178403D03*
Y173903D03*
X1782600Y175932D03*
X1778778Y216928D03*
X1783878D03*
X1772000Y214062D03*
X1778778Y219428D03*
Y221928D03*
X1783878Y224428D03*
Y226928D03*
Y219428D03*
Y221928D03*
X1786089Y287641D03*
X1783563D03*
X1777354Y295489D03*
X1783018Y301729D03*
X1782324Y410432D03*
Y403932D03*
Y425432D03*
Y418932D03*
X1782420Y447137D03*
X1781470Y452065D03*
X1778310Y591152D03*
X1781720Y592742D03*
X1778165Y1307422D03*
Y1304422D03*
Y1301422D03*
X1775165D03*
X1772165D03*
X1778165Y1295422D03*
X1775165D03*
X1772165D03*
Y1298422D03*
X1775165D03*
X1778165D03*
X1784165Y1307422D03*
Y1304422D03*
X1781165Y1307422D03*
Y1304422D03*
X1784165Y1301422D03*
Y1295422D03*
Y1298422D03*
X1781165Y1301422D03*
Y1295422D03*
Y1298422D03*
X1781829Y1324448D03*
X1784829D03*
X1778829D03*
X1778165Y1310422D03*
Y1312922D03*
X1784165Y1310422D03*
Y1312922D03*
X1781165Y1310422D03*
Y1312922D03*
X1781829Y1333148D03*
Y1330248D03*
Y1327348D03*
X1784829Y1333148D03*
Y1330248D03*
Y1327348D03*
X1781829Y1337548D03*
Y1340448D03*
X1784829Y1337548D03*
Y1340448D03*
X1778829Y1333148D03*
Y1330248D03*
Y1327348D03*
Y1337548D03*
X1772829D03*
X1775829D03*
X1778829Y1340448D03*
X1775829D03*
X1772829D03*
X1781829Y1346248D03*
Y1343348D03*
Y1349148D03*
Y1351858D03*
Y1354758D03*
X1772829Y1346248D03*
X1775829D03*
X1778829D03*
X1772829Y1343348D03*
X1775829D03*
X1778829D03*
X1772829Y1349148D03*
X1775829D03*
X1778829D03*
X1772829Y1351858D03*
X1775829D03*
X1778829D03*
X1772829Y1354758D03*
X1775829D03*
X1778829D03*
X1799920Y52594D03*
X1788238Y82292D03*
Y78062D03*
Y74912D03*
X1803215Y154032D03*
X1793269Y287641D03*
X1790743D03*
X1791619Y294441D03*
X1789093D03*
X1800160Y362542D03*
X1800340Y387062D03*
X1791494Y386536D03*
X1792450Y410615D03*
X1792507Y403932D03*
X1792220Y425432D03*
X1792335Y418775D03*
X1796020Y451162D03*
X1791888Y683805D03*
X1800450Y1505230D03*
X1795561Y1524729D03*
X1806920Y150862D03*
X1808910Y143902D03*
X1813335Y155435D03*
X1813325Y177257D03*
X1807220Y179897D03*
X1817157Y373829D03*
X1816224Y410432D03*
X1816994Y398052D03*
X1815724Y423932D03*
X1810792Y417432D03*
X1812161Y472521D03*
X1814537Y1322105D03*
X1813700Y1494762D03*
X1807150Y1505675D03*
X1818289Y1501591D03*
X1811494Y1505349D03*
X1813994Y1507891D03*
X1825762Y167662D03*
X1835760Y185772D03*
X1829695Y226333D03*
X1832295D03*
X1827095D03*
X1824095D03*
X1834895D03*
Y223733D03*
X1824095D03*
X1827095D03*
X1832295D03*
X1829695D03*
X1832295Y233933D03*
X1829695D03*
X1827095D03*
X1824095D03*
X1829695Y231433D03*
X1832295D03*
X1829695Y228933D03*
X1832295D03*
X1827095Y231433D03*
X1824095D03*
X1827095Y228933D03*
X1824095D03*
X1834895Y233933D03*
Y231433D03*
Y228933D03*
X1828204Y328654D03*
X1829189Y363731D03*
X1829434Y406348D03*
X1834005Y401421D03*
X1821280Y413432D03*
X1834600Y406442D03*
X1826914Y431718D03*
X1829514Y1498198D03*
Y1500807D03*
X1832114Y1498198D03*
Y1500807D03*
X1824995Y1502201D03*
X1846691Y166450D03*
X1844157Y182210D03*
X1848435Y172187D03*
X1838880Y195162D03*
X1837895Y226333D03*
Y223733D03*
Y233933D03*
Y231433D03*
Y228933D03*
X1836294Y383592D03*
X1838379Y453921D03*
G54D31*
X174685Y647210D03*
X174393Y678354D03*
X195316Y1430034D03*
X383224Y1354446D03*
X412990D03*
X443326D03*
X458600Y1379662D03*
X472700Y1353962D03*
X526478Y1449795D03*
X708795Y1429579D03*
X1131715Y1532913D03*
X1168627Y1466363D03*
X1175215Y1532913D03*
X1359365Y1353946D03*
X1389131D03*
X1419467D03*
X1434200Y1379362D03*
X1449233Y1353946D03*
X1502956Y1449373D03*
X1670101Y1463655D03*
X1682882Y628017D03*
Y678952D03*
X1769790Y204632D03*
X1799350D03*
X1826405Y269763D03*
Y299056D03*
G54D27*
X70472Y173228D03*
Y236220D03*
G54D46*
X450000Y278543D03*
X470000D03*
X483500Y246362D03*
X473500D03*
X480000Y278543D03*
X490000D03*
X500000D03*
X498563Y607067D03*
X510000Y278543D03*
X520000D03*
X518563Y607067D03*
X508563D03*
X549236Y1441207D03*
X569236D03*
X688500Y1611900D03*
Y1621900D03*
X1041435Y143357D03*
X1056225Y143131D03*
X1041435Y163357D03*
X1056225Y163131D03*
X1099970Y1712570D03*
Y1722570D03*
X1689646Y115669D03*
X1679646D03*
X1689646Y125669D03*
Y135669D03*
X1679646Y125669D03*
Y135669D03*
X1689646Y145669D03*
Y155669D03*
X1679646Y145669D03*
Y155669D03*
X1689646Y165669D03*
X1679646D03*
X1689646Y175669D03*
X1679646D03*
X1771457Y1624646D03*
Y1644646D03*
G54D17*
X27699Y1258727D03*
Y1255381D03*
Y1265420D03*
Y1262074D03*
X43841Y994357D03*
Y1255381D03*
Y1258727D03*
Y1252034D03*
Y1262074D03*
Y1265420D03*
X57299Y766798D03*
X52541Y957546D03*
Y954200D03*
X57399Y1258727D03*
X52820Y1253862D03*
X57399Y1265420D03*
Y1262074D03*
X66099Y1061286D03*
X73541Y1255381D03*
Y1258727D03*
Y1252034D03*
Y1265420D03*
Y1262074D03*
X86999Y766798D03*
X82241Y957546D03*
Y954200D03*
Y994357D03*
X87099Y1258727D03*
X82241Y1248688D03*
X84334Y1254263D03*
X87099Y1265420D03*
Y1262074D03*
X103241Y994357D03*
Y1255381D03*
Y1258727D03*
Y1252034D03*
Y1265420D03*
Y1262074D03*
X116567Y766775D03*
X111941Y957546D03*
Y954200D03*
X125499Y1061286D03*
X116799Y1258727D03*
X111941Y1248688D03*
X114191Y1254604D03*
X116799Y1265420D03*
Y1262074D03*
X141641Y957546D03*
Y954200D03*
Y994357D03*
Y1057940D03*
X129933Y1238461D03*
X132941Y1255381D03*
Y1258727D03*
Y1252034D03*
X141641Y1248688D03*
X143675Y1255567D03*
X132941Y1265420D03*
Y1262074D03*
X146367Y766775D03*
X160130Y1251847D03*
X146499Y1258727D03*
Y1265420D03*
Y1262074D03*
X176099Y766798D03*
X171341Y957546D03*
Y954200D03*
X162641Y994357D03*
X176199Y1258727D03*
X162641Y1255381D03*
Y1258727D03*
Y1252034D03*
X171341Y1248688D03*
X171947Y1255837D03*
X176199Y1265420D03*
X162641D03*
Y1262074D03*
X176199D03*
X184899Y1061286D03*
X192341Y1255381D03*
Y1258727D03*
Y1252034D03*
Y1265420D03*
Y1262074D03*
X205799Y766798D03*
X201041Y957546D03*
Y954200D03*
Y994357D03*
X205899Y1258727D03*
X201041Y1248688D03*
X201193Y1257900D03*
X205899Y1265420D03*
Y1262074D03*
X222041Y957546D03*
Y954200D03*
Y994357D03*
Y1255381D03*
X219660Y1260492D03*
X222041Y1252034D03*
Y1265420D03*
Y1262074D03*
X235499Y766798D03*
X236391Y1002557D03*
X240521Y1000395D03*
X237841Y1000437D03*
X233891Y1002557D03*
X231391D03*
X228891D03*
X235599Y1258727D03*
X230741Y1248688D03*
X235480Y1265406D03*
X235599Y1262074D03*
X251741Y957546D03*
Y954200D03*
Y994357D03*
X254881Y999650D03*
X257561Y999608D03*
X244299Y1061286D03*
X248047Y1259155D03*
X250467Y1259175D03*
X251707Y1252034D03*
X249603Y1266204D03*
X251699Y1265254D03*
X272529Y111053D03*
X265442D03*
X261899D03*
Y108553D03*
X265442D03*
X268985Y111053D03*
Y108553D03*
X272529D03*
X260441Y1057940D03*
Y1248688D03*
X629658Y766478D03*
X623347Y999665D03*
X625780Y1000198D03*
X620899Y1061286D03*
X629931Y1258727D03*
X632080Y1262074D03*
X629699Y1255381D03*
X631270Y1264942D03*
X636941Y957546D03*
Y954200D03*
X644347Y1003135D03*
X640327D03*
X640467Y1000735D03*
X647447Y1002865D03*
X647397Y1000135D03*
X644257Y1000325D03*
X636946Y1258414D03*
X647690Y1260812D03*
X637041Y1252034D03*
X645897Y1248785D03*
X647877Y1254076D03*
X636877Y1261235D03*
X667677Y441636D03*
X650107Y1002825D03*
X650599Y1258727D03*
X666741Y1255381D03*
X664630Y1259442D03*
X649587Y1266766D03*
X661400Y1263522D03*
X674628Y424313D03*
X671479Y421163D03*
X667660Y429037D03*
X674628Y427462D03*
X677778Y414864D03*
Y424313D03*
X671479Y414864D03*
X674628Y421163D03*
Y418013D03*
X677778D03*
Y421163D03*
X668329D03*
X677778Y427462D03*
Y430612D03*
X674628Y436911D03*
X671479D03*
X677778Y433761D03*
X668329Y436911D03*
X677778Y440061D03*
X674628D03*
X677778Y436911D03*
Y443210D03*
X680928Y440061D03*
X674628Y430612D03*
X671479Y443211D03*
X677778Y449510D03*
X668329Y452659D03*
X674628D03*
X671479D03*
X677778D03*
X668329Y455809D03*
X671479Y458959D03*
X674628D03*
X668329D03*
X677778D03*
Y455809D03*
X674628D03*
X668067Y462090D03*
X677778Y462108D03*
X671479Y455809D03*
X680928Y458959D03*
X674628Y449510D03*
Y462108D03*
X677778Y477856D03*
Y471557D03*
Y474707D03*
X671479Y465258D03*
X674628D03*
X668329D03*
X677778D03*
Y468407D03*
X671479Y481006D03*
X667350Y470680D03*
X671479Y474707D03*
X674628Y484006D03*
X680299Y766798D03*
X666641Y957546D03*
Y954200D03*
X672063Y998632D03*
X680299Y1061286D03*
Y1258727D03*
X666741Y1252034D03*
X675537Y1248885D03*
X677980Y1262074D03*
X666741D03*
X666646Y1264464D03*
X680046Y1264964D03*
X695055Y112678D03*
Y115178D03*
X687227Y414864D03*
X690376Y421163D03*
Y418013D03*
Y414864D03*
X693526Y427462D03*
X687227Y424313D03*
X690376Y427462D03*
X680928Y414864D03*
Y418013D03*
X684077Y421163D03*
X680928Y427462D03*
X684077Y418013D03*
Y427462D03*
X680928Y421163D03*
X684077Y424313D03*
X687227Y427462D03*
X696676D03*
X693526Y421163D03*
Y424313D03*
X690376D03*
X696676Y421163D03*
Y424313D03*
Y418013D03*
X680928Y436911D03*
Y433761D03*
X693526Y430612D03*
X696676Y440061D03*
Y443210D03*
X684077Y430612D03*
Y440061D03*
X687227Y436911D03*
Y443210D03*
X684077D03*
Y436911D03*
X680928Y443210D03*
X690376Y436911D03*
Y443210D03*
X687227Y440061D03*
X693526Y433761D03*
X696676D03*
X684077D03*
X687227Y430612D03*
X690376D03*
X696676D03*
X687227Y433761D03*
X680928Y430612D03*
X687227Y462108D03*
X680928Y455809D03*
X693526Y462108D03*
X680928Y449510D03*
X687227D03*
X690376Y462108D03*
X684077Y449510D03*
X680928Y452659D03*
X684077D03*
X687227Y455809D03*
X684077D03*
X680928Y462108D03*
X696676Y449510D03*
Y452659D03*
X690376Y449510D03*
Y455809D03*
X687227Y452659D03*
X693526Y458959D03*
X696676D03*
Y462108D03*
X687227Y458959D03*
X684077D03*
Y468407D03*
X687227Y471557D03*
Y474707D03*
Y477856D03*
X684077Y471557D03*
X690376Y465258D03*
X684077D03*
X680928Y471557D03*
Y474707D03*
Y477856D03*
X693526Y465258D03*
Y471557D03*
X690376Y468407D03*
Y477856D03*
Y471557D03*
X687227Y465258D03*
X690376Y474707D03*
X687227Y468407D03*
X693526D03*
X684077Y474707D03*
X696676Y465258D03*
Y474707D03*
Y468407D03*
X693526Y474707D03*
X696676Y471557D03*
X693526Y477856D03*
X696441Y957546D03*
Y954200D03*
Y994357D03*
Y1255381D03*
X694100Y1261562D03*
X696441Y1248688D03*
X692233Y1252480D03*
X696046Y1263764D03*
X698598Y115178D03*
X705685D03*
X702141D03*
X698598Y112678D03*
X705685D03*
X702141D03*
X706125Y418013D03*
X712424Y424313D03*
X699825Y427462D03*
X699826Y414864D03*
X699825Y424313D03*
X712424Y430612D03*
X709274Y440061D03*
Y443210D03*
X706125D03*
X699825D03*
X709274Y433761D03*
X712424D03*
X699825D03*
X706125D03*
X699825Y430612D03*
X706125Y462108D03*
X709274D03*
X712424D03*
X709274Y449510D03*
X699825D03*
X706125D03*
X709274Y452659D03*
X699825Y458959D03*
X706125D03*
X709274D03*
X712424D03*
X699825Y462108D03*
X709274Y474707D03*
Y471557D03*
Y465258D03*
Y468407D03*
X712424Y474707D03*
Y468407D03*
Y465258D03*
X706125Y471557D03*
Y468407D03*
X699825Y471557D03*
Y474707D03*
X706125Y477856D03*
X699825Y465258D03*
X712424Y471557D03*
X706125Y481006D03*
X709899Y766798D03*
X709999Y1258727D03*
X708090Y1262074D03*
X705037Y1252034D03*
X706493Y1256563D03*
X705167Y1262074D03*
X709977Y1264985D03*
X721873Y427462D03*
X725022D03*
X728172Y418013D03*
X718723D03*
X715574Y427462D03*
X728172Y421163D03*
X718723Y414864D03*
X725022Y424313D03*
X721873D03*
X725022Y421163D03*
X728172Y427462D03*
X731322Y421163D03*
X725022Y418013D03*
X718723Y427462D03*
Y424313D03*
Y421163D03*
X715574Y424313D03*
Y421163D03*
Y418013D03*
X728172Y424313D03*
X718723Y436911D03*
X721873Y433761D03*
Y436911D03*
Y440061D03*
Y430612D03*
X718723Y433761D03*
Y440061D03*
X725022Y436911D03*
Y433761D03*
X728172D03*
X718723Y430612D03*
X715574D03*
X725022D03*
X728172Y436911D03*
X715574D03*
Y440061D03*
Y443210D03*
X728172D03*
Y430612D03*
X725022Y440061D03*
X718723Y443210D03*
X721873D03*
X725022D03*
X728172Y440061D03*
X731322D03*
X728172Y455809D03*
Y458959D03*
X718723Y455809D03*
X721873Y458959D03*
Y452659D03*
X725022D03*
X728172D03*
X715574Y462108D03*
X725022Y458959D03*
X721873Y455809D03*
X725022Y462108D03*
X718723Y452659D03*
X715574Y449510D03*
Y452659D03*
Y455809D03*
X728172Y462108D03*
X718723Y449510D03*
X721873D03*
X725022D03*
X718723Y458959D03*
X721873Y462108D03*
X718723D03*
X725022Y468407D03*
X721873Y465258D03*
Y477856D03*
X718723Y468407D03*
X715574Y474707D03*
Y471557D03*
Y468407D03*
Y465258D03*
X718723Y474707D03*
Y471557D03*
X728172Y477856D03*
X721873Y471557D03*
X725022D03*
X718723Y465258D03*
X728172D03*
X725022Y474707D03*
X728172Y468407D03*
X721873Y474707D03*
Y468407D03*
X728172Y474707D03*
Y471557D03*
X725022Y465258D03*
X718723Y477856D03*
X725132Y481116D03*
X728272Y481006D03*
X726041Y957546D03*
Y954200D03*
Y994357D03*
X726141Y1057940D03*
Y1255381D03*
X723700Y1258727D03*
X726141Y1248688D03*
Y1262074D03*
X726107Y1265420D03*
X734471Y418013D03*
X731322Y427462D03*
Y418013D03*
X734471Y421163D03*
X731322Y424313D03*
X734471D03*
X737621D03*
X731322Y414864D03*
Y433761D03*
X734471Y436911D03*
X731322D03*
X734471Y443210D03*
X737621D03*
X731322D03*
Y455809D03*
X737621Y458959D03*
X731322D03*
X734471Y452659D03*
X731322D03*
Y449510D03*
X734471Y458959D03*
X731322Y465258D03*
Y477856D03*
X737621Y471557D03*
X734471Y468407D03*
X731322D03*
X731321Y474707D03*
X731322Y471557D03*
X734471Y481006D03*
X739699Y766798D03*
Y1061286D03*
Y1258727D03*
X734967Y1252034D03*
X737580Y1262074D03*
X739697Y1265420D03*
X755841Y957546D03*
Y954200D03*
Y994357D03*
X755541Y1057940D03*
X750890Y1248500D03*
X755890Y1255381D03*
X753000Y1261352D03*
X755841Y1252034D03*
Y1248688D03*
X750040Y1254179D03*
X755841Y1262074D03*
X755797Y1265420D03*
X769399Y766798D03*
Y1258727D03*
X767080Y1262074D03*
X766148Y1255882D03*
X769399Y1265420D03*
X785541Y957546D03*
Y954200D03*
Y994357D03*
Y1255381D03*
X783130Y1259372D03*
X794157Y1252034D03*
X785541Y1248688D03*
X796880Y1262074D03*
X796280Y1254402D03*
X785541Y1265420D03*
Y1262074D03*
X797417Y767345D03*
X799099Y1061286D03*
Y1258727D03*
X812440D03*
X799099Y1265420D03*
X815241Y957546D03*
Y954200D03*
Y994357D03*
Y1255381D03*
X826750Y1262074D03*
X823877Y1252034D03*
X815241Y1248688D03*
X826501Y1254553D03*
X815241Y1265420D03*
Y1262074D03*
X828699Y766798D03*
X828799Y1258727D03*
X842630Y1256912D03*
X828799Y1265420D03*
X844841Y957546D03*
Y954200D03*
Y994357D03*
X844941Y1258727D03*
Y1252034D03*
X844997Y1248155D03*
X844941Y1265420D03*
Y1262074D03*
X998205Y195735D03*
Y192191D03*
X1000705Y195735D03*
Y192191D03*
X998205Y199278D03*
X1000705D03*
X998205Y202821D03*
X1000705D03*
X1001970Y1251522D03*
X1003831Y1259077D03*
X1002070Y1256942D03*
X1003841Y1265420D03*
Y1262074D03*
X1012769Y766798D03*
X1019983Y994357D03*
X1017900Y1247632D03*
X1019983Y1255381D03*
Y1252034D03*
Y1248688D03*
Y1262074D03*
Y1265420D03*
X1033441Y766798D03*
X1028683Y957546D03*
Y954200D03*
X1033541Y1258727D03*
X1030830Y1261302D03*
X1030270Y1256042D03*
X1033541Y1265420D03*
X1042241Y1061286D03*
X1047010Y1259222D03*
X1049683Y1258727D03*
Y1265420D03*
Y1262074D03*
X1044930Y1263492D03*
X1063141Y766798D03*
X1058383Y957546D03*
Y954200D03*
Y994357D03*
X1063241Y1258727D03*
X1061330Y1262074D03*
X1058383Y1248688D03*
X1059410Y1252272D03*
X1063241Y1265420D03*
X1079383Y994357D03*
X1076520Y1259072D03*
X1079383Y1258727D03*
X1088262Y1252293D03*
X1079383Y1265420D03*
Y1262074D03*
X1092709Y766775D03*
X1088083Y957546D03*
Y954200D03*
X1101641Y1061286D03*
X1090273Y1246800D03*
X1092941Y1258727D03*
X1088083Y1248688D03*
X1091000Y1262074D03*
X1106200Y1250162D03*
X1092941Y1265420D03*
X1103530Y1263602D03*
X1117783Y957546D03*
Y954200D03*
Y994357D03*
Y1057940D03*
X1120800Y1262074D03*
X1117783Y1248688D03*
X1109083Y1265420D03*
X1109050Y1262972D03*
X1106740Y1267902D03*
X1122541Y766798D03*
X1122641Y1258727D03*
X1133200Y1255702D03*
X1122620Y1264622D03*
X1152241Y766798D03*
X1147483Y957546D03*
Y954200D03*
X1138783Y994357D03*
X1152341Y1258727D03*
X1138783Y1255381D03*
Y1258727D03*
Y1252034D03*
X1147483Y1248688D03*
X1150400Y1262074D03*
X1148563Y1257097D03*
X1152341Y1265420D03*
X1138783Y1262027D03*
X1137980Y1264212D03*
X1161041Y1061286D03*
X1168483Y1255381D03*
Y1258727D03*
Y1252034D03*
Y1265420D03*
Y1262074D03*
X1177183Y957546D03*
Y954200D03*
Y994357D03*
X1177120Y1248688D03*
X1177222Y1255567D03*
X1182041Y1265420D03*
X1181850Y1260192D03*
X1179180Y1265872D03*
X1198183Y957546D03*
Y954200D03*
Y994357D03*
Y1252034D03*
X1198180Y1262112D03*
X1196470Y1265382D03*
X1193590Y1267912D03*
X1195470Y1262802D03*
X1211641Y766798D03*
X1213983Y1000437D03*
X1216663Y1000395D03*
X1212533Y1002557D03*
X1205033D03*
X1207533D03*
X1210033D03*
X1208830Y1256692D03*
X1206883Y1248688D03*
X1207048Y1255174D03*
X1211240Y1265502D03*
X1208750Y1266546D03*
X1227883Y957546D03*
Y954200D03*
Y994357D03*
X1233703Y999608D03*
X1231023Y999650D03*
X1220441Y1061286D03*
X1224189Y1259155D03*
X1226899Y1257968D03*
X1227847Y1251715D03*
X1227670Y1265162D03*
X1225540Y1266402D03*
X1236583Y1057940D03*
Y1248688D03*
X1605800Y766478D03*
X1601922Y1000198D03*
X1599489Y999665D03*
X1597041Y1061286D03*
X1606481Y1258649D03*
X1608000Y1261662D03*
X1607897Y1264445D03*
X1613083Y957546D03*
Y954200D03*
X1616609Y1000735D03*
X1616469Y1003135D03*
X1623539Y1000135D03*
X1620489Y1003135D03*
X1623589Y1002865D03*
X1620399Y1000325D03*
X1621983Y1258727D03*
X1624600Y1262074D03*
X1613183Y1252034D03*
X1613027Y1248805D03*
X1609056Y1250602D03*
X1623930Y1252242D03*
X1613019Y1261235D03*
X1626741Y766798D03*
X1626249Y1002825D03*
X1626741Y1258727D03*
X1656441Y766798D03*
X1642783Y957546D03*
Y954200D03*
X1648205Y998632D03*
X1656441Y1061286D03*
X1642883Y1255381D03*
Y1258727D03*
Y1252034D03*
X1651679Y1248885D03*
X1653140Y1257862D03*
X1656188Y1264964D03*
X1642788Y1264464D03*
X1642883Y1262074D03*
X1656170Y1260352D03*
X1654600Y1262742D03*
X1672583Y957546D03*
Y954200D03*
Y994357D03*
Y1255381D03*
Y1258727D03*
Y1248688D03*
X1672188Y1263764D03*
X1686041Y766798D03*
X1686141Y1258727D03*
X1681179Y1252034D03*
X1683578Y1253780D03*
X1686119Y1264985D03*
X1681309Y1262074D03*
X1683500Y1264312D03*
X1702183Y957546D03*
Y954200D03*
Y994357D03*
X1702283Y1057940D03*
X1699852Y1245418D03*
X1699089Y1258842D03*
X1702283Y1248688D03*
X1702249Y1265420D03*
X1702283Y1262074D03*
X1699030Y1263912D03*
X1715841Y766798D03*
Y1061286D03*
X1713620Y1258512D03*
X1711109Y1252034D03*
X1713930Y1262074D03*
X1715839Y1265420D03*
X1737020Y112177D03*
Y109677D03*
X1731983Y957546D03*
Y954200D03*
Y994357D03*
X1731683Y1057940D03*
X1727041Y1248688D03*
X1731983Y1255381D03*
Y1258727D03*
Y1252034D03*
Y1248688D03*
X1731939Y1265420D03*
X1731983Y1262074D03*
X1747650Y109677D03*
Y112177D03*
X1744106Y109677D03*
Y112177D03*
X1740563Y109677D03*
Y112177D03*
X1745541Y766798D03*
Y1258727D03*
X1743710Y1262074D03*
X1742337Y1252300D03*
X1745541Y1265420D03*
X1761683Y957546D03*
Y954200D03*
Y994357D03*
X1756922Y1247632D03*
X1761683Y1255381D03*
Y1258727D03*
X1770299Y1252034D03*
X1761683Y1248688D03*
Y1262074D03*
Y1265420D03*
X1773559Y767345D03*
X1775241Y1061286D03*
Y1258727D03*
X1788219Y1259312D03*
X1773390Y1262074D03*
X1773480Y1253692D03*
X1775241Y1265420D03*
X1788360Y1264522D03*
X1791383Y957546D03*
Y954200D03*
Y994357D03*
X1788373Y1241769D03*
X1800427Y1248125D03*
X1803100Y1262074D03*
X1800019Y1252034D03*
X1791383Y1248688D03*
Y1265420D03*
Y1262074D03*
X1804841Y766798D03*
X1815063Y1233103D03*
X1804941Y1258727D03*
X1813814Y1254693D03*
X1804941Y1265420D03*
X1820983Y957546D03*
Y954200D03*
Y994357D03*
X1830379Y1250358D03*
X1829920Y1258322D03*
X1821139Y1248155D03*
X1821083Y1262074D03*
Y1265420D03*
X1829940Y1263662D03*
G54D29*
X159474Y1328627D03*
X183847Y1328652D03*
X208247D03*
X275289Y583576D03*
Y607735D03*
Y631889D03*
Y656043D03*
X270252Y676260D03*
Y700414D03*
X387897Y1242785D03*
X412297D03*
X436619D03*
X461019D03*
X485419D03*
X673093Y1328652D03*
X697466Y1328677D03*
X721866D03*
X1100800Y259362D03*
X1100700Y283662D03*
X1131100Y1364962D03*
X1155500D03*
X1179900D03*
X1364038Y1242785D03*
X1388438D03*
X1412760D03*
X1437160D03*
X1461560D03*
X1577000Y599762D03*
Y624262D03*
Y648762D03*
Y673162D03*
Y697662D03*
Y722162D03*
X1634259Y1362248D03*
X1658632Y1362273D03*
X1683032D03*
G54D52*
X705760Y-26500D03*
Y-16500D03*
D03*
Y-6500D03*
X730760Y-26500D03*
Y-16500D03*
D03*
Y-6500D03*
X822720Y3500D03*
Y13500D03*
D03*
Y23500D03*
X847720Y3500D03*
Y13500D03*
D03*
Y23500D03*
X973180Y-26500D03*
Y-16500D03*
D03*
Y-6500D03*
Y3500D03*
Y13500D03*
Y23500D03*
Y13500D03*
X998180Y-26500D03*
Y-16500D03*
D03*
Y-6500D03*
Y3500D03*
Y13500D03*
Y23500D03*
Y13500D03*
X1015152Y-26511D03*
Y-36511D03*
Y-26511D03*
Y-16511D03*
D03*
Y-6511D03*
D03*
Y3489D03*
D03*
Y13489D03*
D03*
Y23489D03*
X1040152Y-26511D03*
Y-36511D03*
Y-26511D03*
Y-16511D03*
D03*
Y-6511D03*
D03*
Y3489D03*
D03*
Y13489D03*
D03*
Y23489D03*
X1282572Y-36511D03*
Y-26511D03*
D03*
Y-16511D03*
D03*
Y-6511D03*
Y3489D03*
Y-6511D03*
Y3489D03*
Y13489D03*
Y23489D03*
Y13489D03*
X1307572Y-36511D03*
Y-26511D03*
D03*
Y-16511D03*
D03*
Y-6511D03*
Y3489D03*
Y-6511D03*
Y3489D03*
Y13489D03*
Y23489D03*
Y13489D03*
X1324471Y-26511D03*
Y-36511D03*
Y-26511D03*
Y-16511D03*
D03*
Y-6511D03*
D03*
Y3489D03*
D03*
Y13489D03*
D03*
Y23489D03*
X1349471Y-26511D03*
Y-36511D03*
Y-26511D03*
Y-16511D03*
D03*
Y-6511D03*
D03*
Y3489D03*
D03*
Y13489D03*
D03*
Y23489D03*
X1474931Y-36511D03*
Y-26511D03*
D03*
Y-16511D03*
D03*
Y-6511D03*
Y3489D03*
Y-6511D03*
Y3489D03*
Y13489D03*
Y23489D03*
Y13489D03*
X1499931Y-36511D03*
Y-26511D03*
D03*
Y-16511D03*
D03*
Y-6511D03*
Y3489D03*
Y-6511D03*
Y3489D03*
Y13489D03*
Y23489D03*
Y13489D03*
X1565236Y184783D03*
Y264035D03*
G54D55*
X793879Y194881D03*
X789942Y204724D03*
X793879Y214567D03*
X805690Y188976D03*
Y220472D03*
X817501Y194881D03*
Y214567D03*
X821438Y204724D03*
X841240Y1407480D03*
X832154Y1411244D03*
X828390Y1420330D03*
X832154Y1429416D03*
X841240Y1433180D03*
X850326Y1411244D03*
X854090Y1420330D03*
X850326Y1429416D03*
X1003390Y1420330D03*
X1016240Y1407480D03*
X1007154Y1411244D03*
Y1429416D03*
X1016240Y1433180D03*
X1025326Y1411244D03*
X1029090Y1420330D03*
X1025326Y1429416D03*
X1045847Y194881D03*
X1041910Y204724D03*
X1045847Y214567D03*
X1069469Y194881D03*
X1057658Y188976D03*
X1069469Y214567D03*
X1057658Y220472D03*
X1073406Y204724D03*
G54D11*
X3010Y63308D03*
Y123308D03*
Y163308D03*
Y183308D03*
Y203308D03*
Y223308D03*
Y243308D03*
Y263308D03*
Y283308D03*
Y303308D03*
X10884Y321693D03*
Y341693D03*
Y361693D03*
Y381693D03*
Y401693D03*
Y421693D03*
Y441693D03*
Y461693D03*
Y481693D03*
Y501693D03*
Y521693D03*
Y661693D03*
Y681693D03*
Y701693D03*
Y721693D03*
Y741693D03*
Y781693D03*
Y801693D03*
Y821693D03*
Y841693D03*
Y861693D03*
Y881693D03*
Y901693D03*
Y921693D03*
Y941693D03*
Y961693D03*
Y981693D03*
Y1001693D03*
Y1021693D03*
Y1041693D03*
Y1061693D03*
Y1081693D03*
Y1101693D03*
Y1121693D03*
Y1141693D03*
Y1161693D03*
Y1181693D03*
Y1201693D03*
Y1221693D03*
Y1241693D03*
Y1401693D03*
Y1421693D03*
Y1441693D03*
Y1461693D03*
Y1481693D03*
Y1501693D03*
Y1521693D03*
Y1541693D03*
Y1561693D03*
Y1581693D03*
X26615Y670036D03*
X28601Y1617541D03*
Y1637541D03*
Y1657541D03*
Y1677541D03*
X38220Y595862D03*
X54593Y19183D03*
X87565Y670441D03*
X94473Y698926D03*
X127313Y649765D03*
X114021Y669409D03*
X118021D03*
X127738Y659226D03*
X117220Y1680287D03*
X130067Y650213D03*
X134205Y643603D03*
X128193Y662015D03*
X128275Y665515D03*
X190800Y675662D03*
X219752Y1405499D03*
Y1401999D03*
Y1398599D03*
X259845Y461117D03*
X282640Y214102D03*
X301751Y127466D03*
Y124466D03*
Y121466D03*
X311758Y124469D03*
Y121469D03*
Y127469D03*
X313995Y237724D03*
X335285Y210609D03*
X332285D03*
X325755Y230719D03*
X338985Y229509D03*
X325855Y227619D03*
X325055Y237219D03*
X328965Y237214D03*
X332465D03*
X381068Y1674824D03*
X373320Y1688202D03*
X388220Y1631404D03*
X445944Y359053D03*
X446730Y382432D03*
X443744Y429553D03*
X451421D03*
X443744Y452462D03*
X437520Y484837D03*
X447520D03*
X442520D03*
X451520D03*
X448079Y1562177D03*
X443910Y1555602D03*
X450020Y1570412D03*
X453621Y359053D03*
X462720Y404762D03*
X465421Y424928D03*
X466520Y475812D03*
X456520Y484837D03*
X461520D03*
X456961Y1559697D03*
X456020Y1580412D03*
X464020D03*
X462079Y1572177D03*
X454661Y1596755D03*
X459779Y1609235D03*
X480393Y429412D03*
X479169Y484696D03*
X474169D03*
X484169D03*
X478308Y1439986D03*
X502070Y424787D03*
X488070Y429412D03*
X498169Y484696D03*
X493169D03*
X488169D03*
X513444Y473281D03*
X503169Y475671D03*
X550024Y369123D03*
Y401023D03*
X557701Y369123D03*
X649218Y504277D03*
X641386Y1687283D03*
X661534Y41748D03*
X656877Y514716D03*
X661743Y521166D03*
X657734Y528255D03*
X656725Y1657619D03*
X669004Y41698D03*
X694720Y491962D03*
X690720D03*
X702462Y1673258D03*
X725537Y-23978D03*
Y-19022D03*
Y-13978D03*
Y-9022D03*
X719194Y172909D03*
X714202D03*
X719194Y177865D03*
X714202D03*
X719194Y184909D03*
X714202D03*
X719194Y189865D03*
X714202D03*
X719194Y196409D03*
X714202D03*
X719194Y201365D03*
X714202D03*
X719194Y208243D03*
X714202D03*
X719194Y213199D03*
X714202D03*
X714203Y1639776D03*
X745685Y265322D03*
Y269322D03*
X730282Y1580391D03*
X741382Y1585251D03*
Y1580121D03*
X735882Y1580391D03*
X730282Y1590651D03*
Y1585521D03*
X735882Y1590651D03*
X732504Y1600321D03*
Y1597321D03*
X744504D03*
Y1600321D03*
X741504Y1597321D03*
Y1600321D03*
X735504Y1597321D03*
Y1600321D03*
X738504Y1597321D03*
Y1600321D03*
X744504Y1609521D03*
Y1612521D03*
X741504Y1609521D03*
X738504D03*
X735504D03*
X741504Y1612521D03*
X738504D03*
X735504D03*
X732504Y1603321D03*
Y1606321D03*
X744504Y1603321D03*
Y1606321D03*
X741504Y1603321D03*
Y1606321D03*
X738504Y1603321D03*
X735504D03*
X738504Y1606321D03*
X735504D03*
X742655Y1682362D03*
Y1678362D03*
X761720Y283262D03*
X748085Y278942D03*
X758360Y276122D03*
X747504Y1600321D03*
Y1609521D03*
Y1612521D03*
X750504D03*
Y1609521D03*
X747504Y1603321D03*
Y1606321D03*
X755859Y1686090D03*
X755183Y1709850D03*
X764850Y249792D03*
X776052Y1611893D03*
X763359Y1729520D03*
X785135Y281822D03*
Y267822D03*
X788079Y1580393D03*
X782479D03*
X793579D03*
X788079Y1590653D03*
X782479D03*
Y1585523D03*
X793579Y1590653D03*
Y1585523D03*
X785052Y1600693D03*
Y1597693D03*
X782052D03*
Y1600693D03*
X794052D03*
X788052D03*
X791052D03*
X794052Y1597693D03*
X788052D03*
X791052D03*
X785052Y1607793D03*
X782052D03*
X779052D03*
X785052Y1611893D03*
X782052D03*
X779052D03*
X794052Y1607793D03*
X791052D03*
X788052D03*
X797052Y1611893D03*
X794052D03*
X788052D03*
X791052D03*
X785052Y1603693D03*
X782052D03*
X794052D03*
X788052D03*
X791052D03*
X797052Y1607793D03*
X824479Y1580393D03*
Y1590653D03*
Y1585523D03*
X824052Y1597693D03*
Y1600693D03*
X827052D03*
Y1597693D03*
X824052Y1611893D03*
Y1607793D03*
Y1603693D03*
X827052Y1611893D03*
Y1607793D03*
Y1603693D03*
X821052Y1611893D03*
Y1607793D03*
X818052Y1611893D03*
X842497Y6022D03*
Y16022D03*
Y20978D03*
Y10978D03*
X830079Y1580393D03*
X835579D03*
X833052Y1597693D03*
X836052D03*
X830079Y1590653D03*
X835579D03*
X833052Y1600693D03*
X836052D03*
X835579Y1585523D03*
X830052Y1600693D03*
Y1597693D03*
X833052Y1603693D03*
X836052D03*
X839052Y1611893D03*
X833052Y1607793D03*
Y1611893D03*
X836052Y1607793D03*
Y1611893D03*
X830052D03*
Y1607793D03*
Y1603693D03*
X839052Y1607793D03*
X866479Y1580393D03*
X872079D03*
X866052Y1597693D03*
X869052D03*
X866479Y1590653D03*
X869052Y1600693D03*
X866052D03*
X872052Y1597693D03*
X872079Y1590653D03*
X872052Y1600693D03*
X866479Y1585523D03*
X875052Y1597693D03*
Y1600693D03*
X869052Y1603693D03*
X866052D03*
X872052D03*
X869052Y1607793D03*
Y1611893D03*
X866052Y1607793D03*
X863052Y1611893D03*
X866052D03*
X872052Y1607793D03*
Y1611893D03*
X875052Y1603693D03*
Y1607793D03*
Y1611893D03*
X863052Y1607793D03*
X860052Y1611893D03*
X877579Y1580393D03*
Y1585523D03*
X878052Y1597693D03*
Y1600693D03*
X877579Y1590653D03*
X878052Y1603693D03*
Y1607793D03*
X881052Y1611893D03*
X878052D03*
X881052Y1607793D03*
X908675Y455386D03*
X908479Y1580393D03*
Y1590653D03*
Y1585523D03*
X908052Y1600693D03*
Y1597693D03*
Y1611893D03*
X905052D03*
X902052D03*
X908052Y1607793D03*
X905052D03*
X908052Y1603693D03*
X913913Y455396D03*
X919579Y1580393D03*
X914079D03*
X919579Y1590653D03*
X914079D03*
X919579Y1585523D03*
X917052Y1600693D03*
Y1597693D03*
X914052Y1600693D03*
Y1597693D03*
X911052Y1600693D03*
Y1597693D03*
X920052Y1600693D03*
Y1597693D03*
X917052Y1611893D03*
X914052D03*
X911052D03*
X917052Y1607793D03*
X914052D03*
X911052D03*
X920052Y1611893D03*
X923052D03*
Y1607793D03*
X920052D03*
X917052Y1603693D03*
X914052D03*
X911052D03*
X920052D03*
X957420Y153699D03*
X960420D03*
X968022Y1620730D03*
X965022D03*
X971022D03*
X965022Y1632730D03*
X968022Y1629730D03*
X965022D03*
X968022Y1626730D03*
X965022D03*
Y1623730D03*
X968022D03*
X971022Y1626730D03*
Y1623730D03*
Y1629730D03*
Y1632730D03*
X968022D03*
X981445Y181058D03*
X1002735Y153943D03*
X999735D03*
X999915Y180548D03*
X996415D03*
X992505Y180553D03*
X993205Y174053D03*
X993305Y170953D03*
X990495Y212923D03*
X1001065Y304622D03*
Y307122D03*
Y309622D03*
X996662Y1620870D03*
X999662D03*
X1002662D03*
Y1626870D03*
Y1623870D03*
X996662Y1629870D03*
X999662Y1626870D03*
X996662D03*
Y1623870D03*
X999662D03*
X996662Y1632870D03*
X1021908Y60392D03*
Y120392D03*
X1015300Y148736D03*
X1012187Y148749D03*
X1006435Y172843D03*
X1009895Y192359D03*
X1008067Y194356D03*
X1019935Y206463D03*
Y203333D03*
X1010828Y304822D03*
Y307322D03*
Y309822D03*
X1034929Y-33989D03*
Y-29033D03*
Y-13989D03*
Y-9033D03*
Y-23989D03*
Y-19033D03*
Y-3989D03*
Y967D03*
X1036915Y290969D03*
X1035920Y428962D03*
X1034252Y1623870D03*
Y1626870D03*
X1031252Y1623870D03*
Y1626870D03*
X1028252Y1623870D03*
Y1626870D03*
X1031252Y1620870D03*
X1034252D03*
X1028252D03*
X1065721Y1633043D03*
X1068721D03*
Y1624043D03*
Y1627043D03*
Y1630043D03*
X1065721Y1624043D03*
Y1627043D03*
Y1630043D03*
X1062721Y1633043D03*
Y1624043D03*
Y1627043D03*
Y1630043D03*
X1059721Y1633043D03*
Y1624043D03*
Y1627043D03*
Y1630043D03*
X1068721Y1621043D03*
X1065721D03*
X1062721D03*
X1059721D03*
X1099901Y1633203D03*
Y1624203D03*
Y1627203D03*
Y1630203D03*
Y1621203D03*
X1093901Y1633203D03*
X1096901D03*
Y1624203D03*
Y1627203D03*
Y1630203D03*
X1093901Y1624203D03*
Y1627203D03*
Y1630203D03*
X1090901Y1633203D03*
X1087901D03*
X1090901Y1624203D03*
X1087901D03*
Y1627203D03*
X1090901D03*
X1087901Y1630203D03*
X1090901D03*
X1096901Y1621203D03*
X1093901D03*
X1087901D03*
X1090901D03*
X1132142Y1555301D03*
X1120472Y1615010D03*
X1127377Y1628485D03*
X1131632Y1625969D03*
X1148220Y501362D03*
X1139392Y1620851D03*
X1172720Y527862D03*
X1202600Y759662D03*
X1245574Y234042D03*
X1245593Y241462D03*
Y237462D03*
X1280223Y256841D03*
X1279841Y253052D03*
X1344248Y-33989D03*
Y-29033D03*
Y-13989D03*
Y-9033D03*
Y-23989D03*
Y-19033D03*
Y-3989D03*
Y967D03*
X1412954Y138742D03*
X1404402D03*
X1409716Y171696D03*
X1418268D03*
X1454829Y1439732D03*
X1465179Y213102D03*
X1477700Y236522D03*
X1466292Y631634D03*
X1473228D03*
X1486884Y374338D03*
X1479207D03*
X1478203Y406207D03*
X1493384Y419263D03*
X1481384Y419392D03*
X1505378Y225502D03*
X1509571Y239053D03*
X1507860Y249792D03*
X1513110Y247412D03*
X1522883Y305187D03*
X1526216Y306909D03*
X1529002Y32290D03*
X1528716Y306909D03*
X1533716D03*
X1536216D03*
X1534899Y310447D03*
X1559387Y589340D03*
X1564690Y663302D03*
X1619980Y590685D03*
X1615800Y584062D03*
X1620170Y623762D03*
X1622770D03*
X1612980D03*
X1620170Y626362D03*
X1622770D03*
X1612980D03*
X1615580Y650092D03*
Y657762D03*
X1620170D03*
X1622770D03*
X1622109Y652469D03*
X1619509D03*
X1612980Y657762D03*
Y650092D03*
X1615580Y660362D03*
X1620170D03*
X1622770D03*
X1612980D03*
X1622109Y686469D03*
X1619509D03*
X1615580Y684092D03*
X1612980D03*
X1622770Y691762D03*
Y694362D03*
X1620170Y691762D03*
Y694362D03*
X1615580D03*
X1612980D03*
X1615580Y691762D03*
X1612980D03*
X1619509Y720469D03*
X1622109D03*
X1612980Y718092D03*
X1615580D03*
X1610100Y725152D03*
X1637667Y587844D03*
Y590444D03*
X1629867D03*
Y587844D03*
X1632467Y590444D03*
Y587844D03*
X1635067Y590444D03*
Y587844D03*
X1626606Y616576D03*
X1629206D03*
X1631806D03*
X1634406D03*
X1637006D03*
X1639606D03*
X1630570Y623762D03*
X1627970D03*
X1625370D03*
X1636412Y638451D03*
X1636417Y630007D03*
X1640061Y639497D03*
X1636412Y641051D03*
X1630570Y626362D03*
X1627970D03*
X1625370D03*
X1630198Y638651D03*
Y636051D03*
Y641251D03*
X1633305Y638651D03*
Y641251D03*
X1630198Y632851D03*
X1630214Y629907D03*
X1633321D03*
X1640061Y644457D03*
Y641977D03*
X1630570Y657762D03*
X1627970D03*
X1625370D03*
X1629909Y652469D03*
X1632509D03*
X1624709D03*
X1627309D03*
X1630198Y643851D03*
X1633305Y646451D03*
Y643851D03*
X1630198Y646451D03*
X1636412Y672451D03*
X1636417Y664007D03*
X1640061Y673497D03*
X1630570Y660362D03*
X1627970D03*
X1625370D03*
X1630198Y672651D03*
Y670051D03*
X1633305Y672651D03*
X1630198Y666851D03*
X1630214Y663907D03*
X1633321D03*
X1629909Y686469D03*
X1632509D03*
X1624709D03*
X1627309D03*
X1640061Y678457D03*
Y675977D03*
X1636412Y675051D03*
X1630198Y677851D03*
Y675251D03*
X1633305Y680451D03*
Y675251D03*
Y677851D03*
X1630198Y680451D03*
X1636417Y698007D03*
X1636412Y706451D03*
X1630214Y697907D03*
X1633321D03*
X1630198Y704051D03*
Y706651D03*
X1633305D03*
X1630198Y700851D03*
X1625370Y691762D03*
Y694362D03*
X1630570D03*
Y691762D03*
X1627970D03*
Y694362D03*
X1640061Y707497D03*
Y712457D03*
Y709977D03*
X1636412Y709051D03*
X1632509Y720469D03*
X1627309D03*
X1629909D03*
X1624709D03*
X1633305Y711851D03*
Y709251D03*
X1630198D03*
Y711851D03*
X1633305Y714451D03*
X1630198D03*
X1642873Y604206D03*
Y607206D03*
X1645625Y600495D03*
Y603295D03*
X1642873Y601206D03*
Y598206D03*
X1645625Y597795D03*
Y594995D03*
X1642873Y595006D03*
X1642340Y618546D03*
X1642873Y610206D03*
X1645661Y639497D03*
X1656550Y653086D03*
X1645661Y644457D03*
Y641977D03*
Y673497D03*
X1656550Y687086D03*
X1645661Y678457D03*
Y675977D03*
Y707497D03*
Y709977D03*
Y712457D03*
X1665700Y583462D03*
X1661510Y583442D03*
X1672770Y580512D03*
X1669770D03*
X1663720Y620434D03*
X1659914Y649681D03*
Y683681D03*
Y717681D03*
X1686154Y434160D03*
X1704444Y407045D03*
X1697914Y427155D03*
X1698014Y424055D03*
X1701124Y433650D03*
X1697214Y433655D03*
X1704624Y433650D03*
X1717280Y174970D03*
X1707444Y407045D03*
X1711144Y425945D03*
X1765870Y179392D03*
X1780320Y177602D03*
G54D14*
X26054Y195148D03*
X25752Y203274D03*
X24754Y220220D03*
X24814Y236472D03*
X35600Y227380D03*
X45182Y426310D03*
X45034Y449106D03*
X62833Y410047D03*
X62808Y418425D03*
X50138Y426310D03*
X60393D03*
X49990Y449106D03*
X73020Y28406D03*
Y40020D03*
X65349Y426310D03*
X75516Y436519D03*
X73865Y763164D03*
X94279Y28406D03*
X87193D03*
X80106D03*
X94279Y40020D03*
X87193D03*
X80106D03*
X85826Y424319D03*
Y420319D03*
X82661Y449604D03*
X79451Y699517D03*
X92895Y1737108D03*
X108453Y28406D03*
X101366D03*
X108453Y40020D03*
X101366D03*
X104220Y400862D03*
X101720D03*
X113597Y488434D03*
X102152Y509374D03*
X102334Y500628D03*
X102359Y497374D03*
X102152Y513374D03*
X108909Y654926D03*
X102909Y648926D03*
Y642926D03*
Y655102D03*
X108909Y642926D03*
X122626Y28406D03*
X115539D03*
X122626Y40020D03*
X115539D03*
X125007Y392071D03*
Y388071D03*
Y384071D03*
Y396071D03*
X114507Y404571D03*
X117597Y488434D03*
X114909Y654926D03*
Y648926D03*
Y642926D03*
X116798Y1617262D03*
X112895Y1737108D03*
X129713Y28406D03*
Y40020D03*
X136301Y179095D03*
X143340Y204622D03*
X140974Y396885D03*
Y401885D03*
Y399385D03*
X142166Y490835D03*
X144263Y1412275D03*
X138492Y1717592D03*
X132895Y1737108D03*
X158492Y28406D03*
X151405D03*
X158492Y40020D03*
X151405D03*
X147901Y188852D03*
X159125Y448664D03*
X152171Y490615D03*
X149472Y502810D03*
X149486Y498810D03*
X149518Y522810D03*
X159898Y1360790D03*
X152895Y1737108D03*
X172665Y28406D03*
X165579D03*
X172665Y40020D03*
X165579D03*
X175640Y453779D03*
X162398Y1360790D03*
X164898D03*
X172895Y1737108D03*
X166761Y1732967D03*
X179752Y28406D03*
Y40020D03*
X184490Y402203D03*
X191305Y430216D03*
X188221Y454048D03*
X184147Y447078D03*
X192895Y1737108D03*
X202626Y28406D03*
X195539D03*
X202626Y40020D03*
X195539D03*
X199047Y428626D03*
X199139Y422882D03*
X196215Y447565D03*
X194858Y684348D03*
X203441Y1360790D03*
X198041D03*
X200941D03*
X223886Y28406D03*
X216799D03*
X209713D03*
X223886Y40020D03*
X216799D03*
X209713D03*
X223330Y426467D03*
X220843Y430004D03*
X220874Y442079D03*
X224137Y1414345D03*
X224077Y1416975D03*
X224350Y1432032D03*
X212895Y1737108D03*
X230972Y28406D03*
Y40020D03*
X242215Y151788D03*
X253000Y28362D03*
X256500D03*
X249500D03*
X252195Y144320D03*
X257434Y415896D03*
X252895Y1737108D03*
X260000Y28362D03*
X258746Y407842D03*
X260807Y424403D03*
X270322Y740207D03*
X272895Y1737108D03*
X286071Y28406D03*
X278984D03*
X279277Y99183D03*
X289557Y121803D03*
X280687Y140746D03*
X284482Y569548D03*
X286582Y630757D03*
X305025Y144202D03*
X302891Y141811D03*
X292895Y1737108D03*
X324733Y148598D03*
X321119Y1313108D03*
X317119D03*
X313119D03*
X330417Y380482D03*
X336370Y406302D03*
X325119Y1313108D03*
X328915Y1326704D03*
X331515D03*
X332895Y1737108D03*
X344776Y148462D03*
X343411Y363143D03*
Y375364D03*
X343354Y387988D03*
X343720Y400628D03*
X339769Y1299868D03*
X342769D03*
X352895Y1737108D03*
X366675Y158702D03*
X364179Y394596D03*
X371066Y400628D03*
X369690Y431812D03*
X365970Y444662D03*
X361769Y1300008D03*
X364769D03*
X383140Y119822D03*
X375330Y121182D03*
X374981Y131433D03*
X376770Y387272D03*
X385520Y429262D03*
X373190Y438342D03*
X384510Y438662D03*
X385730Y460922D03*
X382860Y471122D03*
X383239Y1286578D03*
X378069Y1286568D03*
X375069D03*
X386239Y1286578D03*
X372895Y1737108D03*
X403700Y402422D03*
X390892Y406863D03*
X403260Y439352D03*
X391150Y445302D03*
X396570Y472602D03*
X391360Y495712D03*
X402780Y499372D03*
X394860Y518812D03*
X403200Y572622D03*
X396139Y1286708D03*
X399139D03*
X400926Y1402207D03*
X391249Y1401048D03*
X396921Y1549810D03*
X396946Y1560810D03*
X419012Y368762D03*
X418602Y394722D03*
X417010Y439352D03*
X415130Y480202D03*
X410532Y1153341D03*
X407948Y1153370D03*
Y1161570D03*
X410532Y1161541D03*
X407948Y1169597D03*
X410532D03*
X429050Y117491D03*
X430980Y132672D03*
X432006Y363644D03*
X431596Y389604D03*
X424980Y439462D03*
X427790Y500862D03*
X427880Y506442D03*
X428510Y515842D03*
X436822Y1161570D03*
Y1153370D03*
X431722D03*
Y1161570D03*
X434272Y1153370D03*
Y1161570D03*
X436822Y1170070D03*
X431722D03*
X434272D03*
X430999Y1286758D03*
X423229D03*
X426229D03*
X433999D03*
X436920Y1541562D03*
X422566Y1550046D03*
X432996Y1558322D03*
X436840Y1632682D03*
X436880Y1622442D03*
X432895Y1737108D03*
X447100Y1622562D03*
X447020Y1632632D03*
X452895Y1737108D03*
X465236Y293823D03*
X467736Y312938D03*
X455326Y520389D03*
X457196Y1161570D03*
X459696D03*
X462196D03*
X459696Y1153370D03*
X457196D03*
X462196D03*
X459696Y1170070D03*
X462196D03*
X457196D03*
X460049Y1286978D03*
X463049D03*
X469019Y1286718D03*
X465749Y1401238D03*
X455602Y1412334D03*
X473870Y506622D03*
X474220Y572782D03*
X471940Y597532D03*
X483030Y1153370D03*
Y1161570D03*
Y1170070D03*
X474509Y1286848D03*
X481509D03*
X477509D03*
X484509D03*
X475285Y1395402D03*
X477835Y1673462D03*
Y1685462D03*
X472895Y1737108D03*
X498636Y293123D03*
X501136Y312238D03*
X486861Y309398D03*
X490759Y1291978D03*
X495309Y1300058D03*
X498309D03*
X492895Y1737108D03*
X517914Y42257D03*
X517902Y49194D03*
X510815D03*
X517989Y1300108D03*
X514989D03*
X508881Y1404880D03*
X506181D03*
X503559Y1405025D03*
X508775Y1409889D03*
X508828Y1407385D03*
X508802Y1412420D03*
X506075Y1409889D03*
X506128Y1407385D03*
X503572Y1407539D03*
Y1415039D03*
Y1412539D03*
X506102Y1412420D03*
X503572Y1410039D03*
X512895Y1737108D03*
X525000Y42257D03*
X524988Y49194D03*
X532533Y299500D03*
X529533D03*
X526941Y447802D03*
X521561Y550819D03*
X526280Y569122D03*
X520710Y592552D03*
X532895Y1737108D03*
X549610Y120682D03*
X535290Y572932D03*
X543450Y590262D03*
X562780Y32842D03*
X564430Y45132D03*
X565849Y1346968D03*
X552895Y1737108D03*
X578620Y45112D03*
X573849Y1346968D03*
X569849D03*
X572895Y1737108D03*
X596840Y45152D03*
X593925Y49193D03*
X590350Y294402D03*
X607890Y34389D03*
X615420Y42342D03*
X605060Y42402D03*
X615185Y49193D03*
X611310Y266272D03*
X612895Y1737108D03*
X621740Y265952D03*
X632895Y1737108D03*
X661681Y49193D03*
X654595D03*
X652895Y1737108D03*
X675854Y49193D03*
X668768D03*
X673517Y1360815D03*
X676017D03*
X678517D03*
X671112Y1639962D03*
X672895Y1737108D03*
X697122Y1632667D03*
X683592Y1634844D03*
X697197Y1644667D03*
X712433Y103308D03*
X712060Y1360815D03*
X722580Y49182D03*
X724133Y141288D03*
X713820Y488762D03*
Y484662D03*
X714560Y1360815D03*
X717060D03*
X744800Y1664840D03*
X732895Y1737108D03*
X762198Y129684D03*
Y126684D03*
X758110Y172636D03*
X752895Y1737108D03*
X777283Y320892D03*
X772208Y1731911D03*
X792208D03*
X810781Y372615D03*
X821164Y372312D03*
X812208Y1731911D03*
X836502Y161553D03*
X837975Y210064D03*
X832208Y1731911D03*
X856776Y129268D03*
X846846Y127064D03*
X851895Y160262D03*
X849710Y212062D03*
X845220Y216532D03*
X854706Y229878D03*
X852206D03*
X856842Y410760D03*
X852208Y1731911D03*
X874295Y163862D03*
X863488Y176332D03*
X872208Y1731911D03*
X886280Y174085D03*
X887671Y487831D03*
Y494767D03*
X878931Y509051D03*
X878941Y503813D03*
X892208Y1731911D03*
X899625Y473856D03*
X893321Y480293D03*
X893311Y485531D03*
X893572Y503050D03*
Y496114D03*
X920246Y184138D03*
X914550Y239924D03*
X923403Y983327D03*
X923322Y990227D03*
X921880Y1525110D03*
X924380D03*
X921880Y1527610D03*
X924380D03*
X912208Y1731911D03*
X935496Y195925D03*
Y203012D03*
Y210098D03*
Y217185D03*
Y224272D03*
Y231358D03*
X940596Y498648D03*
X939097Y527257D03*
X939282Y534020D03*
X930233Y983298D03*
X930274Y990237D03*
X939380Y1525110D03*
X926880D03*
X929380D03*
X931880D03*
X934380D03*
X936880D03*
X926880Y1527610D03*
X929380D03*
X931880D03*
X934380D03*
X936880D03*
X939380D03*
X932208Y1731911D03*
X947190Y527330D03*
X952208Y1731911D03*
X972208D03*
X989910Y-27961D03*
X989925Y-25446D03*
X983632Y-26655D03*
X989925Y-21572D03*
X983632Y-16626D03*
X989910Y-17932D03*
X989925Y-15417D03*
Y-11543D03*
X989910Y-7903D03*
X989925Y-5388D03*
X983632Y-6597D03*
X989925Y4641D03*
X989910Y2126D03*
X983632Y3432D03*
X989925Y14670D03*
X989910Y12155D03*
X989925Y8515D03*
X983632Y13461D03*
X989925Y19044D03*
X983632Y23990D03*
X987259Y276094D03*
X998500Y269862D03*
X1002500D03*
X992208Y1731911D03*
X1014500Y269862D03*
X1018000D03*
X1006500D03*
X1010500D03*
X1021419Y305704D03*
X1012208Y1731911D03*
X1032208D03*
X1053028Y246518D03*
X1053428Y261118D03*
X1052208Y1731911D03*
X1058028Y246518D03*
X1055528D03*
X1068093Y265503D03*
X1058428Y261118D03*
X1055928D03*
X1067618Y273800D03*
X1070718Y273700D03*
X1067718Y285600D03*
X1070618D03*
X1072208Y1731911D03*
X1102561Y78461D03*
X1117574Y1448604D03*
X1111866Y1737108D03*
X1135709Y1397119D03*
X1133209D03*
X1127008Y1524203D03*
X1135748Y1524187D03*
X1131866Y1737108D03*
X1138209Y1397119D03*
X1170337Y607327D03*
X1171752Y1397119D03*
X1176752D03*
X1174252D03*
X1179922Y1524203D03*
X1201110Y1681767D03*
X1191866Y1737108D03*
X1211866D03*
X1231866D03*
X1253586Y1334649D03*
X1257586D03*
X1251866Y1737108D03*
X1276745Y125850D03*
X1275807Y132922D03*
X1281600Y137962D03*
X1282568Y212722D03*
X1272707Y1334865D03*
X1271866Y1737108D03*
X1293024Y-36695D03*
Y-26666D03*
Y-16637D03*
Y-6608D03*
Y3421D03*
Y13450D03*
Y23979D03*
X1291280Y58262D03*
X1293860Y58312D03*
X1284930Y124922D03*
X1285793Y141562D03*
X1288258Y145501D03*
X1283781Y149115D03*
Y155788D03*
X1283425Y179272D03*
X1283397Y202085D03*
X1295150Y1323217D03*
X1298150D03*
X1291010Y1323307D03*
X1288010D03*
X1291866Y1737108D03*
X1299317Y-35486D03*
Y-31612D03*
X1299302Y-38001D03*
Y-27972D03*
X1299317Y-25457D03*
Y-21583D03*
X1299302Y-17943D03*
X1299317Y-15428D03*
Y-11554D03*
X1299302Y-7914D03*
X1299317Y-5399D03*
Y4630D03*
X1299302Y2115D03*
X1299317Y-1525D03*
Y14659D03*
X1299302Y12144D03*
X1299317Y8504D03*
Y19033D03*
X1304066Y1323578D03*
X1307656Y1326704D03*
X1305056D03*
X1311866Y1737108D03*
X1323958Y146227D03*
X1333811Y235348D03*
X1338652Y536654D03*
Y543590D03*
X1337663Y1301001D03*
X1340663D03*
X1331866Y1737108D03*
X1349704Y145385D03*
X1357888Y145893D03*
X1361111Y236448D03*
X1353982Y1287048D03*
X1362382D03*
X1359382D03*
X1350982D03*
X1351866Y1737108D03*
X1366868Y147341D03*
X1369593Y147462D03*
X1369916Y154132D03*
X1379969Y176330D03*
X1370586Y176366D03*
X1370405Y186938D03*
X1369479Y208384D03*
X1370636Y227292D03*
X1369410Y224504D03*
X1375463Y1287048D03*
X1372463D03*
X1376666Y1402778D03*
X1376686Y1399758D03*
X1371866Y1737108D03*
X1384173Y1161549D03*
X1384089Y1153369D03*
X1386673Y1161520D03*
Y1153340D03*
X1384173Y1169599D03*
X1386673Y1169570D03*
X1391866Y1737108D03*
X1407613Y177159D03*
X1398770D03*
X1402258Y184263D03*
X1411101D03*
X1407913Y1161569D03*
X1410413Y1153369D03*
X1407913D03*
X1410613Y1161569D03*
X1407913Y1170069D03*
X1410613D03*
X1410819Y1287198D03*
X1407819D03*
X1399419D03*
X1402419D03*
X1411866Y1737108D03*
X1420222Y184263D03*
X1429250Y1623391D03*
X1419270Y1631000D03*
X1429382Y184263D03*
X1430000Y220018D03*
X1435387Y1161569D03*
X1435837Y1153369D03*
X1432887Y1161569D03*
X1433337Y1153369D03*
X1435387Y1170069D03*
X1432887D03*
X1437258Y1287198D03*
X1445106Y1287158D03*
X1440258Y1287198D03*
X1431829Y1412370D03*
X1443325Y1410068D03*
X1431717Y1424125D03*
X1441800Y1620300D03*
Y1632900D03*
X1431866Y1737108D03*
X1458911Y1161569D03*
Y1170069D03*
X1453366Y1287198D03*
X1458766D03*
X1461766D03*
X1450366D03*
X1474180Y1300407D03*
X1471180D03*
X1491661Y-27972D03*
X1491676Y-25457D03*
X1485383Y-26666D03*
X1491661Y-38001D03*
X1491676Y-35486D03*
Y-31612D03*
X1485383Y-36695D03*
X1491661Y-17943D03*
X1491676Y-15428D03*
Y-11554D03*
X1485383Y-16637D03*
X1491676Y-21583D03*
X1485383Y3421D03*
X1491661Y2115D03*
X1491676Y4630D03*
X1491661Y-7914D03*
X1491676Y-5399D03*
Y-1525D03*
X1485383Y-6608D03*
X1491676Y14659D03*
X1491661Y12144D03*
X1485383Y13450D03*
X1491676Y8504D03*
Y19033D03*
X1485383Y23979D03*
X1487058Y281456D03*
X1484958Y289656D03*
X1487658D03*
X1484758Y312356D03*
X1487458D03*
X1484858Y305956D03*
X1487558D03*
X1491840Y1300447D03*
X1479658Y1405397D03*
X1485301Y1409442D03*
X1485274Y1406911D03*
X1485380Y1412202D03*
X1479671Y1410411D03*
Y1412911D03*
Y1407911D03*
X1482201Y1409442D03*
X1482174Y1406911D03*
X1482280Y1412202D03*
X1491866Y1737108D03*
X1504602Y312867D03*
X1494840Y1300447D03*
X1511866Y1737108D03*
X1540937Y576522D03*
X1536527Y589012D03*
X1531866Y1737108D03*
X1547429Y28406D03*
X1554515D03*
Y40020D03*
X1547429D03*
X1547312Y579080D03*
X1551866Y1737108D03*
X1561602Y28406D03*
X1568688D03*
Y40020D03*
X1561602D03*
X1575775Y28406D03*
X1582862D03*
X1589948D03*
Y40020D03*
X1582862D03*
X1575775D03*
X1591866Y1737108D03*
X1597035Y28406D03*
X1604122D03*
Y40020D03*
X1597035D03*
X1623881Y117627D03*
X1619980Y615201D03*
X1614116Y1411169D03*
X1611866Y1737108D03*
X1625814Y28406D03*
X1632901D03*
X1639988D03*
X1625814Y40020D03*
X1632901D03*
X1639988D03*
X1637183Y1394411D03*
X1639683D03*
X1634683D03*
X1631866Y1737108D03*
X1654161Y28406D03*
X1647074D03*
Y40020D03*
X1654161D03*
X1652113Y527325D03*
X1652138Y524071D03*
X1651931Y540071D03*
Y536071D03*
X1649291Y556057D03*
X1649149Y607022D03*
X1653929Y604546D03*
X1649139Y604576D03*
X1653736Y607033D03*
X1649117Y602139D03*
X1653930Y602099D03*
X1651866Y1737108D03*
X1669948Y28406D03*
Y40020D03*
X1663376Y515531D03*
X1667376D03*
X1664997Y604762D03*
X1659458Y637149D03*
X1658085Y639511D03*
X1659458Y671149D03*
X1658085Y673511D03*
X1659458Y705149D03*
X1658085Y707511D03*
X1673226Y1394411D03*
X1671866Y1737108D03*
X1677035Y28406D03*
X1684122D03*
X1677035Y40020D03*
X1684122D03*
X1681612Y499290D03*
X1675926Y1394411D03*
X1678426D03*
X1691208Y28406D03*
X1698295D03*
X1705381D03*
X1697824Y39974D03*
X1691208Y40020D03*
X1693987Y230174D03*
Y233174D03*
X1703487Y232174D03*
X1699265Y525507D03*
X1699291Y537507D03*
X1699251Y529507D03*
X1699297Y549507D03*
X1705723Y1583821D03*
X1691866Y1737108D03*
X1711866D03*
X1738200Y193862D03*
X1731866Y1737108D03*
X1753388Y28360D03*
X1754398Y100307D03*
X1752200Y197762D03*
X1748500Y193862D03*
X1745500D03*
X1741200D03*
X1740831Y489362D03*
X1740886Y493960D03*
X1751866Y1737108D03*
X1760475Y28360D03*
X1764678Y122927D03*
X1766880Y234842D03*
Y231842D03*
X1758500Y231822D03*
Y234822D03*
X1755378Y233528D03*
X1782000Y128455D03*
X1771915Y128393D03*
X1782000Y125955D03*
Y123455D03*
X1771915Y125893D03*
Y123393D03*
X1783800Y231762D03*
Y234762D03*
X1775140Y234792D03*
Y231792D03*
X1779226Y275604D03*
X1783563Y273471D03*
X1786089D03*
X1771866Y1737108D03*
X1797663Y269571D03*
X1800189D03*
X1790563Y273471D03*
X1793089D03*
X1802763Y308671D03*
X1795763D03*
X1798289D03*
X1788763D03*
X1791289D03*
X1814349Y269634D03*
X1811823D03*
X1807249D03*
X1804723D03*
X1812349Y308734D03*
X1809823D03*
X1805289Y308671D03*
X1828777Y156520D03*
X1841257Y151402D03*
G54D19*
X20188Y1599396D03*
G54D67*
X1156378Y133866D03*
G54D71*
X1850331Y311946D03*
G54D25*
X60303Y20354D03*
X312921Y24291D03*
X505185Y41142D03*
X757803Y45079D03*
X922441Y237697D03*
X929331Y160413D03*
X1534712Y20354D03*
X1787330Y24291D03*
G54D42*
X337778Y854584D03*
X335924Y857789D03*
X334079Y880219D03*
X332228Y877014D03*
X335928D03*
X334078Y893036D03*
X335928Y896240D03*
X332229Y902649D03*
X332228Y915466D03*
X335928D03*
X332229Y921875D03*
Y941100D03*
X332228Y934692D03*
X335928D03*
X334079Y957122D03*
X335928Y953917D03*
X332228D03*
X332229Y973143D03*
X334079Y976347D03*
X338210Y996480D03*
X332661Y1006093D03*
X338211Y1002888D03*
X332661Y1025318D03*
Y1018910D03*
X338211Y1015705D03*
Y1022114D03*
X332661Y1044544D03*
X338211Y1041340D03*
X334511D03*
X338211Y1060565D03*
X336360Y1082995D03*
X338211Y1111834D03*
Y1105426D03*
Y1124651D03*
X336361Y1115039D03*
Y1127856D03*
X347028Y844971D03*
X345178Y848176D03*
X350727Y844971D03*
X347027Y851380D03*
X343327D03*
X354429D03*
X341478Y854584D03*
X339628Y857789D03*
X347029Y864197D03*
Y857789D03*
X348878Y854584D03*
X345179Y860993D03*
X343327Y857789D03*
X354429Y864197D03*
X350729D03*
X341479Y867401D03*
X348879D03*
X352579D03*
X354429Y877014D03*
X339629D03*
X341479Y873810D03*
X345179Y880219D03*
Y873810D03*
X343329Y877014D03*
X352579Y880219D03*
X350729Y877014D03*
X339629Y883423D03*
X347029D03*
X350729D03*
X352578Y899445D03*
X339629Y896240D03*
Y889832D03*
X348879Y886627D03*
X345179Y893036D03*
X343328Y896240D03*
X352578Y893036D03*
Y886627D03*
X345179Y899445D03*
X348878Y905853D03*
X352578D03*
X341479Y912262D03*
X341478Y905853D03*
X347029Y909057D03*
Y902649D03*
X345179Y912262D03*
X352578D03*
X339629Y915466D03*
X343329D03*
X348878Y925079D03*
X352578D03*
Y918670D03*
X341478Y925079D03*
X347029Y928283D03*
Y921875D03*
X345179Y918670D03*
X341479Y931488D03*
X345179D03*
X352578D03*
X341478Y944304D03*
X352578D03*
X347029Y941100D03*
X348878Y944304D03*
X347029Y947509D03*
X352578Y937896D03*
X339629Y934692D03*
X345179Y937896D03*
X343328Y934692D03*
X348878Y963530D03*
X347029Y960326D03*
X343328D03*
X343329Y966735D03*
X339629D03*
Y953917D03*
X343328D03*
X345179Y957122D03*
X352578D03*
X347029Y966735D03*
X352578Y963530D03*
X341479Y950713D03*
X345179D03*
X352578D03*
X354428Y973143D03*
X339629D03*
X345179Y976347D03*
Y969939D03*
X350729Y973143D03*
X347029Y979552D03*
X352579Y976347D03*
X352578Y969939D03*
X348878Y982756D03*
X352578D03*
X339629Y979552D03*
X343329Y973143D03*
X341911Y1009297D03*
Y1002888D03*
X347461Y999684D03*
X345611Y1009297D03*
X343761Y1006093D03*
X345611Y1002888D03*
X351162Y1006093D03*
X354861D03*
X353011Y1009297D03*
Y1002888D03*
X347461Y1012501D03*
X353011Y1028523D03*
Y1015705D03*
X341911Y1022114D03*
Y1015705D03*
X349311D03*
X347461Y1018910D03*
X345611Y1028523D03*
X343761Y1018910D03*
X345611Y1022114D03*
Y1015705D03*
X353011Y1022114D03*
X343761Y1031727D03*
X347461D03*
X353011Y1034931D03*
Y1047749D03*
X341911Y1041340D03*
X343761Y1038136D03*
X349311Y1034931D03*
X347461Y1038136D03*
X345611Y1041340D03*
X343761Y1044544D03*
X353011Y1041340D03*
X345611Y1047749D03*
X349311Y1054157D03*
X353011Y1060565D03*
Y1054157D03*
X343761Y1057361D03*
Y1050952D03*
X347461D03*
Y1057361D03*
X345611Y1060565D03*
X343761Y1063770D03*
X353011Y1073383D03*
X343761Y1076587D03*
Y1070178D03*
X340062Y1076587D03*
X347461D03*
Y1070178D03*
X349312Y1073383D03*
X345611Y1066974D03*
X353011D03*
X345611Y1079791D03*
X341911D03*
X353011D03*
Y1086200D03*
X349310Y1092609D03*
X347461Y1089404D03*
X345610Y1086200D03*
X343760Y1082995D03*
X340060D03*
X353011Y1092608D03*
X340061Y1095813D03*
X347461Y1108630D03*
X354861D03*
X353011Y1099017D03*
X340061Y1108630D03*
Y1102221D03*
X349311Y1099017D03*
X347461Y1102221D03*
X343761D03*
X340061Y1115039D03*
X349311Y1124651D03*
X349312Y1118243D03*
X345611D03*
X343761Y1115039D03*
X341911Y1124651D03*
X354861Y1115039D03*
X351161Y1121447D03*
Y1115039D03*
X345611Y1137469D03*
Y1131060D03*
X349311D03*
X343761Y1134264D03*
X353011Y1137469D03*
Y1131060D03*
X361829Y851380D03*
X358129D03*
X365529Y864197D03*
X361829D03*
X359979Y854584D03*
X358129Y864197D03*
X369229D03*
X367379Y854584D03*
X359979Y867401D03*
X367379D03*
X365529Y877014D03*
X361829D03*
X358129D03*
X369229D03*
X367379Y880219D03*
X356278Y886627D03*
X365529Y896240D03*
Y889832D03*
X361828Y896240D03*
X361829Y889832D03*
X359979Y893036D03*
X358128Y889832D03*
X369229Y896240D03*
Y889832D03*
X356278Y905853D03*
X365529Y909057D03*
Y902649D03*
X359978Y912262D03*
X358128Y909057D03*
X358129Y902649D03*
X371079Y912262D03*
X365529Y915466D03*
X361828D03*
X369229D03*
X356279Y925079D03*
X365529Y928283D03*
Y921875D03*
X358128Y928283D03*
X358129Y921875D03*
X371078Y918670D03*
X359978Y931488D03*
X371079D03*
X358128Y947509D03*
X358129Y941100D03*
X356279Y944304D03*
X365529Y947509D03*
Y934691D03*
X361828D03*
X369229D03*
X356279Y963530D03*
X358129Y960326D03*
X359979Y957122D03*
X358128Y966735D03*
X361829Y953917D03*
X359978Y950713D03*
X371078Y957122D03*
X371079Y950713D03*
X365529Y953917D03*
X367378Y963530D03*
X363679D03*
X365529Y960326D03*
X365528Y966735D03*
X369229Y953917D03*
X359979Y976347D03*
X358129Y979552D03*
X359978Y969939D03*
X361828Y973143D03*
X356279Y982756D03*
X371078Y976347D03*
X371079Y969939D03*
X369229Y973143D03*
X365529Y979552D03*
Y973143D03*
X365962Y999684D03*
Y1006093D03*
X362261D03*
X360411Y1009297D03*
X360412Y1002888D03*
X358562Y999684D03*
X371512Y1009297D03*
X365961Y1012501D03*
X358561D03*
X356712Y1015705D03*
X365962Y1025318D03*
Y1018910D03*
X364112Y1015705D03*
X360411Y1028523D03*
X362261Y1025318D03*
X360412Y1022114D03*
X358562Y1018910D03*
X369662Y1025318D03*
X367811Y1015705D03*
X371511Y1028523D03*
Y1022114D03*
X365962Y1031727D03*
X358561D03*
X356712Y1034931D03*
X365962Y1044544D03*
Y1038136D03*
X362261Y1044544D03*
X360412Y1041340D03*
X358562Y1038136D03*
X369662Y1044544D03*
X371511Y1041340D03*
X360411Y1047749D03*
X371511D03*
X356712Y1054157D03*
X365962Y1057361D03*
Y1050952D03*
X360412Y1060565D03*
X358562Y1057361D03*
X358561Y1050952D03*
X371511Y1060565D03*
X365962Y1063770D03*
X362261D03*
X369662D03*
X356712Y1073383D03*
X365962Y1070178D03*
X360411Y1066974D03*
X358561Y1070178D03*
X358562Y1076587D03*
X371512Y1066974D03*
X360412Y1079791D03*
X371511D03*
X365962Y1089404D03*
Y1082995D03*
X362261D03*
X360411Y1086200D03*
X358561Y1089404D03*
X356712Y1092608D03*
X369662Y1082995D03*
X371512Y1086200D03*
X365962Y1095813D03*
X358561D03*
X365962Y1102221D03*
X362262D03*
X360411Y1099017D03*
X356711Y1105426D03*
Y1099017D03*
X371512Y1105426D03*
Y1099017D03*
X364112Y1111834D03*
X356712D03*
X371512D03*
X364111Y1118243D03*
X362261Y1115039D03*
X360411Y1118243D03*
X356711D03*
X367811D03*
X371511D03*
X365962Y1127856D03*
X358561D03*
X365961Y1140973D03*
X364112Y1131060D03*
X360412D03*
X358561Y1140973D03*
X356712Y1131060D03*
X367811D03*
X371511D03*
X382179Y854584D03*
X380329Y864197D03*
X376629D03*
X374779Y854584D03*
X372929Y864197D03*
X384029D03*
X387729D03*
X382179Y867401D03*
X374779D03*
X382179Y880219D03*
X380329Y877014D03*
X376629D03*
X374779Y880219D03*
X372929Y877014D03*
X384029D03*
X387729D03*
X380329Y889832D03*
X378479Y893036D03*
X376629Y889832D03*
X372929D03*
X384029D03*
X387729Y896240D03*
Y889832D03*
X378478Y899445D03*
X385879D03*
X382179Y905853D03*
X378478Y912262D03*
Y905853D03*
X374778D03*
X372929Y909057D03*
X372928Y902649D03*
X385878Y912262D03*
X384028Y909057D03*
X384029Y902649D03*
X387728Y915466D03*
X382179Y925079D03*
X378478D03*
Y918670D03*
X374778Y925079D03*
X372929Y928283D03*
X372928Y921875D03*
X385879Y918670D03*
X384028Y928283D03*
X384029Y921875D03*
X385878Y931488D03*
X384029Y941100D03*
X384028Y947509D03*
X374778Y944304D03*
X372929Y947509D03*
X372928Y941100D03*
X382179Y944304D03*
X378478D03*
Y937896D03*
X385879D03*
X387728Y934691D03*
X387729Y953917D03*
X372928Y960326D03*
X374778Y963530D03*
X372929Y966735D03*
X382179Y963530D03*
X378478D03*
Y957122D03*
X384029Y960326D03*
X385879Y957122D03*
X384028Y966735D03*
X385878Y950713D03*
X378478D03*
X387728Y973143D03*
X376629D03*
X380328D03*
X378479Y976347D03*
X378478Y969939D03*
X385879Y976347D03*
X384029Y979552D03*
X385878Y969939D03*
X374778Y982756D03*
X382179D03*
X378478D03*
X372928Y979552D03*
X375210Y996480D03*
X373361Y999684D03*
X378911Y1009297D03*
Y1002888D03*
X386311Y1009297D03*
X386312Y1002888D03*
X384462Y999684D03*
X373362Y1012501D03*
X384461D03*
X382612Y1015705D03*
X378911Y1028523D03*
Y1022114D03*
Y1015705D03*
X375211D03*
X373361Y1018910D03*
X386311Y1028523D03*
X386312Y1022114D03*
X384462Y1018910D03*
X373362Y1031727D03*
X384461D03*
X382612Y1034931D03*
X378911Y1041340D03*
Y1034931D03*
X375211D03*
X373361Y1038136D03*
X386312Y1041340D03*
X384462Y1038136D03*
X378911Y1047749D03*
X386311D03*
X382612Y1054157D03*
X378911D03*
X375211D03*
X373361Y1057361D03*
X373362Y1050952D03*
X386312Y1060565D03*
X384462Y1057361D03*
X384461Y1050952D03*
X382612Y1073383D03*
X378911D03*
Y1066974D03*
X375211Y1073383D03*
X373361Y1076587D03*
X373362Y1070178D03*
X386311Y1066974D03*
X384462Y1076587D03*
X384461Y1070178D03*
X378911Y1079791D03*
X386311D03*
X382611Y1092608D03*
X378911D03*
Y1086200D03*
X375211Y1092608D03*
X373362Y1089404D03*
X386311Y1086200D03*
X384461Y1089404D03*
X373362Y1095813D03*
X384462D03*
X380762Y1108630D03*
X378911Y1099017D03*
X377062Y1102221D03*
X373361Y1108630D03*
Y1102221D03*
X386312Y1099017D03*
X384462Y1102221D03*
X382611Y1118243D03*
X378911D03*
X377061Y1115039D03*
X375211Y1118243D03*
X373361Y1115039D03*
X386311Y1118243D03*
X384461Y1115039D03*
X380761Y1127856D03*
X373361D03*
X382611Y1131060D03*
X380761Y1140973D03*
X378911Y1131060D03*
X375211D03*
X373361Y1140973D03*
X386311Y1131060D03*
X396979Y841467D03*
X398829Y851380D03*
X395129D03*
X391429D03*
X402529D03*
X398829Y864197D03*
X396979Y854584D03*
X395129Y864197D03*
X391429D03*
X389579Y854584D03*
X402529Y864197D03*
X396979Y867401D03*
X389579D03*
X398829Y877014D03*
X396979Y880219D03*
X395129Y877014D03*
X391429D03*
X389579Y880219D03*
X402529Y877014D03*
X398829Y889832D03*
X395129Y896240D03*
Y889832D03*
X391428Y896240D03*
X391429Y889832D03*
X389579Y893036D03*
X402529Y889832D03*
X398829Y909057D03*
X398828Y902649D03*
X396979Y912262D03*
X391429Y909057D03*
Y902649D03*
X395129Y915466D03*
X391429D03*
X398829Y928283D03*
X398828Y921875D03*
X396978Y918670D03*
X391429Y928283D03*
Y921875D03*
X400678Y925079D03*
X396979Y931488D03*
X398828Y941100D03*
X395129Y934691D03*
X391429Y941100D03*
Y934691D03*
X400678Y937896D03*
X398829Y947509D03*
X391429D03*
X398828Y960326D03*
X396978Y957122D03*
X396979Y950713D03*
X395129Y953917D03*
X391429Y960326D03*
Y953917D03*
X400678Y957122D03*
X398829Y966735D03*
X391429D03*
X400678Y963530D03*
X398828Y979552D03*
X396978Y976347D03*
X396979Y969939D03*
X395129Y973143D03*
X391429Y979552D03*
Y973143D03*
X400678Y982756D03*
Y969939D03*
X397412Y1009297D03*
X397411Y1002888D03*
X395562Y1006093D03*
X391862D03*
Y999684D03*
X388161Y1006093D03*
X401111Y1002888D03*
X399262Y1012501D03*
X391861D03*
X399261Y1018910D03*
X397411Y1028523D03*
Y1022114D03*
X395562Y1025318D03*
X393711Y1015705D03*
X391862Y1025318D03*
Y1018910D03*
X390012Y1015705D03*
X388161Y1025318D03*
X399262Y1031727D03*
X391862D03*
X399261Y1038136D03*
X397411Y1041340D03*
X395562Y1044544D03*
X391862D03*
Y1038136D03*
X388161Y1044544D03*
X397411Y1047749D03*
X399261Y1057361D03*
X399262Y1050952D03*
X397411Y1060565D03*
X391862Y1057361D03*
Y1050952D03*
X395562Y1063770D03*
X391862D03*
X388161D03*
X399261Y1076587D03*
X399262Y1070178D03*
X397412Y1066974D03*
X391862Y1076587D03*
Y1070178D03*
X401111Y1073383D03*
X397411Y1079791D03*
X401111D03*
X399262Y1089404D03*
X397412Y1086200D03*
X395562Y1082995D03*
X391862Y1089404D03*
Y1082995D03*
X388161D03*
X401112Y1092608D03*
X401111Y1086200D03*
X399261Y1095813D03*
X391862D03*
X402962D03*
X399262Y1102221D03*
X397412Y1099017D03*
X395562Y1102221D03*
X390011Y1105426D03*
X388162Y1108630D03*
Y1102221D03*
X401111Y1105426D03*
X397411Y1111834D03*
X390011D03*
X397411Y1118243D03*
X395561Y1115039D03*
X393711Y1118243D03*
X390011D03*
X388161Y1115039D03*
X401111Y1118243D03*
X395561Y1127856D03*
X388161D03*
X402961D03*
X397411Y1131060D03*
X395561Y1140973D03*
X393711Y1131060D03*
X390011D03*
X388161Y1140973D03*
X402961D03*
X401111Y1131060D03*
X419179Y841467D03*
X404379D03*
X411779D03*
X413629Y851380D03*
X409929D03*
X406229D03*
X417329D03*
X404379Y854584D03*
X413629Y864197D03*
X411779Y854584D03*
X409929Y864197D03*
X406229D03*
X419179Y854584D03*
X417329Y864197D03*
X404379Y867401D03*
X411779D03*
X419179D03*
X404379Y880219D03*
X413629Y877014D03*
X411779Y880219D03*
X409929Y877014D03*
Y870606D03*
X406229Y877014D03*
X419179Y880219D03*
X417329Y877014D03*
X413629Y889832D03*
X411779Y893036D03*
X409929Y889832D03*
X408079Y893036D03*
X406229Y889832D03*
X419179Y893036D03*
X417329Y889832D03*
X413629Y902649D03*
X409929Y909057D03*
Y902649D03*
X404378Y912262D03*
Y905853D03*
X419178Y912262D03*
X419179Y905853D03*
X417329Y902649D03*
X409929Y915466D03*
Y921875D03*
X404378Y918670D03*
X418229Y926896D03*
X419178Y918670D03*
X405048Y930812D03*
X405145Y946239D03*
Y948539D03*
X414093Y942098D03*
X405048Y938046D03*
Y935746D03*
X416393Y942098D03*
X418693D03*
X405122Y965896D03*
Y963596D03*
X414365Y971140D03*
X416755D03*
X404861Y981269D03*
Y978969D03*
Y986421D03*
X405101Y992971D03*
Y995271D03*
X404861Y988721D03*
X405227Y1007156D03*
X405231Y1004848D03*
X417575Y1000060D03*
X415185D03*
X404986Y1022427D03*
X404998Y1026821D03*
X408325Y1031971D03*
Y1034271D03*
X408511Y1041340D03*
X417762Y1044544D03*
X412211Y1047749D03*
X404811D03*
X415911Y1060565D03*
Y1054157D03*
X412211Y1060565D03*
X410361Y1050952D03*
X408511Y1054157D03*
X404811Y1060565D03*
X417761Y1050952D03*
X415911Y1066974D03*
X410362Y1076587D03*
Y1070178D03*
X406661Y1076587D03*
X404811Y1066974D03*
X419611Y1073383D03*
X412211Y1079791D03*
X404811D03*
X415911Y1092608D03*
X415912Y1086200D03*
X412211Y1092608D03*
X408511Y1086200D03*
X417761Y1089404D03*
Y1082995D03*
X410362Y1095813D03*
X406662D03*
X415912Y1099017D03*
X414062Y1108630D03*
X412211Y1099017D03*
X410362Y1102221D03*
X406661Y1108630D03*
Y1102221D03*
X404812Y1105426D03*
X417762Y1102221D03*
X404812Y1111834D03*
X415911Y1118243D03*
X414061Y1121447D03*
X412211Y1124651D03*
Y1118243D03*
X410361Y1115039D03*
X408511Y1118243D03*
X406661Y1115039D03*
X404811Y1118243D03*
X417761Y1115039D03*
X410361Y1127856D03*
X414062Y1134264D03*
X412212Y1131060D03*
X410361Y1140973D03*
X408511Y1131060D03*
X404811D03*
X432128Y844671D03*
X426579Y841467D03*
X432129Y851380D03*
X428429D03*
X424729D03*
X421029D03*
X432129Y864197D03*
X428429D03*
X426579Y854584D03*
X424729Y864197D03*
X421029D03*
X433979Y854584D03*
X426579Y867401D03*
X433979D03*
X432129Y877014D03*
X428429D03*
X426579Y880219D03*
X424729Y877014D03*
X421029D03*
X433979Y880219D03*
X432129Y889832D03*
X428429D03*
X426579Y893036D03*
X424729Y889832D03*
X421029D03*
X433979Y893036D03*
X424729Y902649D03*
X432129D03*
X428429Y909057D03*
Y902649D03*
X421029D03*
X428429Y915466D03*
X433980Y925079D03*
Y931487D03*
X426875Y947199D03*
Y949499D03*
X427875Y936470D03*
X426905Y965935D03*
Y963635D03*
Y980336D03*
Y978036D03*
Y994722D03*
Y992422D03*
Y1006875D03*
Y1009175D03*
Y1021963D03*
Y1019663D03*
X428862Y1044544D03*
X430712Y1047749D03*
X423311D03*
X425162Y1057361D03*
X432561Y1050952D03*
X434411Y1060565D03*
Y1054157D03*
X421462Y1063770D03*
X430711Y1073383D03*
X427011D03*
Y1066974D03*
X425162Y1076587D03*
X423311Y1066974D03*
X432561Y1076587D03*
X434411Y1073383D03*
Y1066974D03*
X427012Y1079791D03*
X434411D03*
X428861Y1082995D03*
X425162Y1089404D03*
X421462Y1082995D03*
X432561Y1089404D03*
Y1082995D03*
X434411Y1086200D03*
X428861Y1095813D03*
X421462D03*
X432561D03*
X427011Y1099017D03*
X425161Y1102221D03*
X423311Y1105426D03*
X421462Y1108630D03*
X434411Y1105426D03*
X423311Y1111834D03*
X434411D03*
X423311Y1124651D03*
Y1118243D03*
X421462Y1115039D03*
X434411Y1124651D03*
Y1118243D03*
X423312Y1137469D03*
X423311Y1131060D03*
X434412Y1137769D03*
X434411Y1131060D03*
X452478Y848176D03*
X445078D03*
X441378D03*
X439529Y844671D03*
X446929Y851380D03*
X443228D03*
X439529D03*
X448779Y854584D03*
X446929Y864197D03*
X443229D03*
X441379Y854584D03*
X439529Y864197D03*
X439528Y857789D03*
X437680Y860992D03*
X450629Y864197D03*
X448779Y867401D03*
X441379D03*
X448779Y880219D03*
X446929Y877014D03*
X443229D03*
X441379Y880219D03*
X439529Y877014D03*
X448779Y893036D03*
X446929Y889832D03*
X443229D03*
X441379Y893036D03*
X439529Y896240D03*
Y889832D03*
X437678Y886627D03*
X450629Y889832D03*
X437679Y899445D03*
X446929Y909057D03*
Y902649D03*
X443229D03*
X439528D03*
X437679Y905853D03*
X450629Y902649D03*
X446929Y915466D03*
X446930Y928283D03*
X441379Y925079D03*
Y931487D03*
X446929Y921875D03*
X437678Y918670D03*
X448779Y937897D03*
X447360Y1038136D03*
X452911Y1041340D03*
X451061Y1044544D03*
X449211Y1047749D03*
X447361Y1057361D03*
Y1050952D03*
X452911Y1060565D03*
X447361Y1063770D03*
Y1076587D03*
Y1070178D03*
X449211Y1073383D03*
X452911Y1079791D03*
X449211D03*
X447361Y1082995D03*
X452911Y1092608D03*
X451062Y1089404D03*
X449212Y1086200D03*
X451062Y1095813D03*
X447361Y1108630D03*
Y1102221D03*
X452911Y1099017D03*
X447361Y1121447D03*
Y1115039D03*
Y1127856D03*
Y1134264D03*
X461729Y851380D03*
X458029D03*
X454328D03*
X456179Y841467D03*
X463579D03*
X469129Y851380D03*
X465429D03*
X456179Y854584D03*
X463579D03*
X461729Y864197D03*
X458029D03*
X454329D03*
X469129D03*
X465429D03*
X456179Y867401D03*
X463579D03*
X461729Y877014D03*
X458029D03*
X456179Y880219D03*
X454329Y877014D03*
X463579Y880219D03*
X469129Y877014D03*
X465429D03*
X461729Y889832D03*
X458029D03*
X456179Y893036D03*
X454329Y889832D03*
X463579Y893036D03*
X469129Y896240D03*
Y889832D03*
X465429D03*
X461729Y902649D03*
X458029D03*
X456178Y905853D03*
X454329Y902649D03*
X465429D03*
Y909057D03*
Y915466D03*
X454103Y931359D03*
Y933659D03*
X456178Y918670D03*
X454434Y1022186D03*
Y1019886D03*
X460311Y1041340D03*
X467372Y1036874D03*
X465861Y1044544D03*
X456611Y1047749D03*
X464011D03*
X456611Y1054157D03*
X462162Y1050952D03*
X454761Y1076587D03*
X462162Y1070178D03*
X456612Y1079791D03*
X467711D03*
X458461Y1082995D03*
X456611Y1086200D03*
X460311Y1092608D03*
X464011Y1086200D03*
X467712D03*
Y1092608D03*
X460312Y1105426D03*
X458462Y1102221D03*
X456611Y1099017D03*
X464012Y1105426D03*
Y1099017D03*
X462162Y1108630D03*
X465861D03*
Y1102221D03*
X464012Y1111834D03*
X467711Y1105426D03*
Y1111834D03*
X458462Y1121447D03*
Y1115039D03*
X467712Y1124651D03*
X467711Y1118243D03*
X465862Y1121447D03*
Y1115039D03*
X458462Y1127856D03*
Y1134264D03*
X478379Y841467D03*
X470979D03*
X476529Y851380D03*
X480229D03*
X472829D03*
X483929D03*
X480229Y864197D03*
X478379Y854584D03*
X476529Y864197D03*
X470979Y854584D03*
X472829Y864197D03*
X483929D03*
X478379Y867401D03*
X470979D03*
X480229Y877014D03*
X478379Y880219D03*
X476529Y877014D03*
X472829D03*
X472828Y870606D03*
X470979Y880219D03*
Y873810D03*
X483929Y877014D03*
X480228Y896240D03*
X480229Y889832D03*
X478379Y893036D03*
X470979D03*
X476529Y889832D03*
X472829D03*
X483929D03*
X482078Y899445D03*
X474678Y905853D03*
X483929Y909057D03*
X482079Y912262D03*
X483928Y902649D03*
X476285Y930126D03*
X476528Y921875D03*
X474678Y918670D03*
X483929Y928283D03*
X482078Y918670D03*
X483928Y921875D03*
X482079Y931488D03*
X476285Y934726D03*
X476180Y945355D03*
Y947655D03*
X478378Y944304D03*
X480229Y934691D03*
X483928Y941100D03*
X482079Y944304D03*
X482078Y937896D03*
X483928Y947509D03*
X476285Y962326D03*
Y960026D03*
Y964626D03*
X483928Y960326D03*
X482078Y957122D03*
X482079Y950713D03*
X483929Y966735D03*
X476285Y966926D03*
X476192Y977670D03*
X476335Y980737D03*
X482079Y969939D03*
X483928Y979552D03*
X482078Y976347D03*
X476285Y996826D03*
Y994526D03*
Y989926D03*
Y987626D03*
X476295Y1010500D03*
X476285Y1012926D03*
Y1006026D03*
Y1003726D03*
X484361Y999684D03*
X482512Y1009297D03*
X482511Y1002888D03*
X484362Y1012501D03*
X476275Y1022636D03*
X476285Y1017526D03*
X482511Y1028523D03*
Y1022114D03*
X484361Y1018910D03*
Y1031727D03*
X471282Y1036526D03*
X473507Y1035928D03*
X475111Y1041340D03*
X482511D03*
X482512Y1034931D03*
X484361Y1038136D03*
X471411Y1047749D03*
X482511D03*
X480662Y1050952D03*
X471411Y1054157D03*
X482511Y1060565D03*
X484362Y1050952D03*
Y1070178D03*
X482511Y1079791D03*
X480662Y1082995D03*
X476962Y1089404D03*
X473262Y1082995D03*
X469561Y1089404D03*
X482512Y1086200D03*
X484362Y1089404D03*
X480661Y1095813D03*
X469562D03*
X484362D03*
X480662Y1108630D03*
X478811Y1099017D03*
X473262Y1108630D03*
X476962Y1102221D03*
X475112Y1099017D03*
X471411D03*
X469562Y1102221D03*
X482511Y1105426D03*
Y1111834D03*
X484362Y1108630D03*
X475111Y1111834D03*
X471411D03*
X478811Y1105426D03*
X469562Y1108630D03*
X473262Y1102221D03*
X482511Y1099017D03*
X478811Y1111834D03*
X476962Y1108630D03*
X471411Y1105426D03*
X475111D03*
X484362Y1102221D03*
X480661Y1115039D03*
X478811Y1118243D03*
X476961Y1115039D03*
X475111Y1118243D03*
X471411D03*
X469561Y1115039D03*
X482511Y1118243D03*
X476961Y1127856D03*
X469562D03*
X484361D03*
X484362Y1115039D03*
X473262D03*
X478811Y1131060D03*
X476961Y1140973D03*
X475111Y1131060D03*
X471412Y1137469D03*
Y1131060D03*
X469561Y1140973D03*
X473261Y1134264D03*
X482511Y1131060D03*
X484361Y1140973D03*
X493179Y841467D03*
X485779D03*
X500579D03*
X495029Y851380D03*
X491329D03*
X487629D03*
X498729D03*
X495029Y864197D03*
X493179Y854584D03*
X491329Y864197D03*
X487629D03*
X485779Y854584D03*
X498729Y864197D03*
X500579Y854584D03*
X493179Y867401D03*
X485779D03*
X500579D03*
X495029Y877014D03*
X493179Y880219D03*
X491329Y877014D03*
X487629D03*
X485779Y880219D03*
X500579D03*
X498729Y877014D03*
X489479Y893036D03*
X495029Y889832D03*
X491329D03*
X487629D03*
X498729D03*
X500579Y893036D03*
X498729Y896240D03*
X496879Y899445D03*
X489478D03*
X496878Y912262D03*
X495029Y909057D03*
X489478Y905853D03*
X495029Y902649D03*
X493179Y905853D03*
X485778D03*
X498728Y915466D03*
X495028Y928283D03*
X493179Y925079D03*
X489478D03*
Y918670D03*
X485778Y925079D03*
X496879Y918670D03*
X495029Y921875D03*
X496878Y931488D03*
X489478D03*
X496879Y937896D03*
X495029Y941100D03*
X493179Y944304D03*
X489478D03*
Y937896D03*
X485778Y944304D03*
X498729Y934691D03*
X495028Y947509D03*
X496879Y957122D03*
X495029Y960326D03*
X489478Y957122D03*
Y950713D03*
X496878D03*
X498729Y953917D03*
X495028Y966735D03*
X493179Y963530D03*
X485778D03*
X489478D03*
X500579D03*
X496879Y976347D03*
X496878Y969939D03*
X489478Y976347D03*
Y969939D03*
X495029Y979552D03*
X498728Y973143D03*
X493179Y982756D03*
X489478D03*
X485778D03*
X497311Y1009297D03*
X497312Y1002888D03*
X495462Y999684D03*
X489911Y1009297D03*
X489912Y1002888D03*
X491761Y1006093D03*
X488062D03*
X499161D03*
X495461Y1012501D03*
X497311Y1028523D03*
X489911D03*
Y1022114D03*
Y1015705D03*
X497311Y1022114D03*
X495462Y1018910D03*
X493612Y1015705D03*
X486211D03*
X501012D03*
X499161Y1025318D03*
X495461Y1031727D03*
X497312Y1041340D03*
X489911D03*
Y1034931D03*
X495462Y1038136D03*
X493612Y1034931D03*
X486211D03*
X499161Y1044544D03*
X489911Y1047749D03*
X497311D03*
Y1060565D03*
X489911D03*
Y1054157D03*
X495461Y1050952D03*
X493611Y1054157D03*
X486211D03*
X489911Y1066974D03*
X495461Y1070178D03*
X489911Y1073383D03*
X497312Y1079791D03*
X489911D03*
X497311Y1086200D03*
X493612Y1092608D03*
X489911D03*
Y1086200D03*
X486211Y1092608D03*
X495461Y1089404D03*
X499161Y1082995D03*
X495462Y1095813D03*
X499162D03*
X491762D03*
X497312Y1105426D03*
X493611D03*
X491762Y1102221D03*
X488061D03*
X486211Y1105426D03*
X486212Y1099017D03*
X499161Y1108630D03*
Y1102221D03*
X497312Y1111834D03*
X489911D03*
Y1099017D03*
X495462Y1102221D03*
X501011Y1099017D03*
X493611D03*
X497311D03*
X489911Y1105426D03*
X486211Y1111834D03*
X491762Y1108630D03*
X488062D03*
X497311Y1118243D03*
X495462Y1121447D03*
X493612Y1118243D03*
X489911D03*
X486211D03*
X501011D03*
X499161Y1115039D03*
X491761Y1127856D03*
X499161D03*
X491762Y1115039D03*
X495462D03*
X497311Y1131060D03*
X493611D03*
X489911D03*
X486211D03*
X491761Y1140973D03*
X501011Y1131060D03*
X499161Y1140973D03*
X507979Y841467D03*
X515379D03*
X506129Y851380D03*
X502429D03*
X513529D03*
X509829D03*
X517229D03*
X513529Y864197D03*
X509829D03*
X506129D03*
X502429D03*
X507979Y854584D03*
X515379D03*
X517229Y864197D03*
X507979Y867401D03*
X515379D03*
X509829Y877014D03*
X507979Y880219D03*
X502429Y877014D03*
X513529D03*
X506129D03*
X515379Y880219D03*
X517229Y877014D03*
X506129Y889832D03*
X502428Y896240D03*
X502429Y889832D03*
X513529D03*
X509829D03*
X506128Y896240D03*
X504279Y893036D03*
X515379D03*
X517229Y889832D03*
X507978Y899445D03*
X515378D03*
X511678Y905853D03*
X509829Y909057D03*
X507979Y912262D03*
X502429Y909057D03*
Y902649D03*
X509828D03*
X515378Y912262D03*
Y905853D03*
X502429Y915466D03*
X506129D03*
X511678Y925079D03*
X509829Y928283D03*
X502429D03*
Y921875D03*
X509828D03*
X507978Y918670D03*
X515378Y925079D03*
Y918670D03*
X507979Y931488D03*
X515378D03*
X511678Y944304D03*
X509828Y941100D03*
X506129Y934691D03*
X502429Y941100D03*
Y934691D03*
X515378Y944304D03*
Y937896D03*
X502429Y947509D03*
X509828Y960326D03*
X507978Y957122D03*
X506129Y953917D03*
X502429Y960326D03*
Y953917D03*
X507979Y950713D03*
X515378Y957122D03*
Y950713D03*
X509829Y966735D03*
X502428D03*
X511678Y963530D03*
X504278D03*
X515378D03*
X507978Y976347D03*
X507979Y969939D03*
X502429Y979552D03*
Y973143D03*
X513529D03*
X509828Y979552D03*
X506129Y973143D03*
X515379Y976347D03*
X515378Y969939D03*
X517228Y973143D03*
X511678Y982756D03*
X515378D03*
X510261Y999684D03*
X508411Y1002888D03*
X506562Y1006093D03*
X502862Y999684D03*
X502861Y1012501D03*
X508412Y1009297D03*
X510262Y1012501D03*
X515811Y1009297D03*
Y1002888D03*
X508411Y1028523D03*
X502862Y1025318D03*
Y1018910D03*
X510261D03*
X508411Y1022114D03*
X506562Y1025318D03*
X504711Y1015705D03*
X515811Y1028523D03*
Y1022114D03*
X510262Y1031727D03*
X502862D03*
X515811Y1015705D03*
X512111D03*
X502862Y1044544D03*
Y1038136D03*
X512111Y1034931D03*
X510261Y1038136D03*
X508411Y1041340D03*
X506562Y1044544D03*
X515811Y1034931D03*
Y1041340D03*
X508411Y1047749D03*
X515811D03*
X508411Y1060565D03*
X502862Y1057361D03*
Y1050952D03*
X512111Y1054157D03*
X510262Y1050952D03*
X515811Y1054157D03*
Y1060565D03*
X502862Y1063770D03*
X510262Y1070178D03*
X502862Y1076587D03*
Y1070178D03*
X515811Y1073383D03*
Y1079791D03*
X512112Y1092608D03*
X510262Y1089404D03*
X508412Y1086200D03*
X506562Y1082995D03*
X502862Y1089404D03*
Y1082995D03*
X515812Y1092608D03*
X513961Y1095813D03*
X502862D03*
X517662D03*
X513962Y1108630D03*
Y1102221D03*
X512112Y1099017D03*
X508411D03*
X506562Y1108630D03*
X504711Y1099017D03*
X502862Y1102221D03*
X515811Y1105426D03*
Y1111834D03*
X517662Y1108630D03*
X513961Y1115039D03*
X512111Y1118243D03*
X508411D03*
X504711D03*
X510261Y1115039D03*
X515811Y1118243D03*
X513961Y1127856D03*
X506561D03*
X517662Y1115039D03*
X513961Y1140973D03*
X512111Y1131060D03*
X508411D03*
X504711D03*
X506561Y1140973D03*
X515811Y1131060D03*
X528329Y844671D03*
X522779Y841467D03*
X528329Y851380D03*
X524629D03*
X520929D03*
X532029D03*
X528329Y864197D03*
X524629D03*
X520929D03*
X530179Y860993D03*
Y854584D03*
X522779D03*
X532028Y857789D03*
X533879Y860993D03*
X530178Y867401D03*
X522779D03*
X533879D03*
X528329Y877014D03*
X522779Y880219D03*
X520929Y877014D03*
X530179Y880219D03*
X524629Y877014D03*
X532029D03*
X533879Y880219D03*
Y873810D03*
X532028Y883423D03*
X528329Y896240D03*
Y889832D03*
X524629D03*
X526479Y893036D03*
X524629Y896240D03*
X520929Y889832D03*
X532029D03*
Y896240D03*
X533879Y893036D03*
X522779Y899445D03*
X533879D03*
X528329Y902649D03*
X522778Y912262D03*
X520928Y909057D03*
X519079Y905853D03*
X520929Y902649D03*
X528329Y915466D03*
X524628D03*
X532029D03*
X528329Y909057D03*
X533879Y912262D03*
X528329Y921875D03*
X520928Y928283D03*
X519079Y925079D03*
X522779Y918670D03*
X520929Y921875D03*
X522778Y931488D03*
X528329Y928283D03*
X533879Y918670D03*
X533878Y931488D03*
X528329Y941100D03*
Y934691D03*
X524628D03*
X522779Y937896D03*
X520929Y941100D03*
X519079Y944304D03*
X520928Y947509D03*
X532029Y934691D03*
X533879Y937896D03*
X528329Y947509D03*
Y960326D03*
Y953917D03*
X524629D03*
X522779Y957122D03*
X520929Y960326D03*
X522778Y950713D03*
X520928Y966735D03*
X526479Y963530D03*
X519079D03*
X533879Y957122D03*
X532029Y953917D03*
X533879Y950713D03*
X530178Y963530D03*
X528329Y966735D03*
Y979552D03*
Y973143D03*
X522779Y976347D03*
X522778Y969939D03*
X524628Y973143D03*
X520929Y979552D03*
X533879Y976347D03*
X519079Y982756D03*
X533901Y980606D03*
X533879Y969939D03*
X532029Y973143D03*
X521361Y1012501D03*
Y999684D03*
X528762Y1006093D03*
Y999684D03*
X525061Y1006093D03*
X523211Y1009297D03*
X523212Y1002888D03*
X534311Y1009297D03*
Y1002888D03*
X532461Y1006093D03*
X528761Y1012501D03*
X528762Y1025318D03*
X523211Y1028523D03*
X525061Y1025318D03*
X528762Y1031727D03*
X521361D03*
X519512Y1015705D03*
X521362Y1018910D03*
X523211Y1022114D03*
X526912Y1015705D03*
X528762Y1018910D03*
X530611Y1015705D03*
X534311Y1028523D03*
X534310Y1022114D03*
X532461Y1025318D03*
X528762Y1044544D03*
X525061D03*
X523212Y1041340D03*
X521362Y1038136D03*
X519512Y1034931D03*
X532462Y1044544D03*
X523211Y1047749D03*
X528762Y1038136D03*
X534311Y1041340D03*
Y1047749D03*
X528762Y1057361D03*
Y1050952D03*
X523212Y1060565D03*
X521361Y1050952D03*
X519512Y1054157D03*
X528762Y1063770D03*
X534311Y1060565D03*
X528762Y1076587D03*
Y1070178D03*
X521361D03*
X523212Y1079791D03*
X534311D03*
X523211Y1086200D03*
X521361Y1089404D03*
X519511Y1092608D03*
X528762Y1089404D03*
Y1082995D03*
X525061D03*
X532462Y1082996D03*
X534311Y1086200D03*
X528761Y1095813D03*
X526911Y1105426D03*
X521361Y1102221D03*
X519511Y1105426D03*
X519512Y1099017D03*
X532461Y1108630D03*
X530612Y1111834D03*
X523211D03*
X526911Y1099017D03*
X534311D03*
X532460Y1102221D03*
X521362Y1108630D03*
X525062D03*
X534311Y1111834D03*
X523211Y1105426D03*
X534311D03*
X528762Y1108630D03*
X519511Y1111834D03*
X526911D03*
X530611Y1124651D03*
Y1118243D03*
X528762Y1121447D03*
X523211Y1118243D03*
X521361Y1115039D03*
X519511Y1118243D03*
X532461Y1115039D03*
X528761Y1127856D03*
X521361D03*
X525062Y1115039D03*
X528762D03*
X530612Y1137469D03*
Y1131060D03*
X526912D03*
X523211D03*
X519511D03*
X528761Y1134264D03*
X521361Y1140973D03*
X534311Y1131060D03*
X537580Y848176D03*
X535729Y844671D03*
Y851380D03*
X544979Y860993D03*
Y854584D03*
X539428Y864197D03*
X537579Y854584D03*
Y860993D03*
X544979Y867401D03*
X541279D03*
X537579D03*
X546829Y870606D03*
X541279Y873810D03*
X535729Y870606D03*
Y883423D03*
X541279Y880219D03*
X546829Y883423D03*
X537579Y893036D03*
X541279Y886627D03*
X544979D03*
X537579D03*
X535729Y889832D03*
X550529D03*
X537579Y899445D03*
X548679Y912262D03*
X537579D03*
X539429Y909057D03*
X537579Y905853D03*
X535729Y909057D03*
X543129D03*
X535729Y902649D03*
X548679Y905853D03*
X537579Y918670D03*
X535729Y921875D03*
X537578Y931488D03*
X548678D03*
X537579Y937896D03*
X535729Y941100D03*
X539429Y947509D03*
X535729D03*
X537579Y957122D03*
Y950713D03*
X535729Y960326D03*
Y966735D03*
X537579Y963530D03*
X539429Y979552D03*
X537579Y982756D03*
X541279Y969939D03*
X539429Y973143D03*
X535729D03*
X539862Y1006092D03*
X539861Y999684D03*
X536161D03*
Y1006093D03*
X543563Y1006092D03*
X549254Y1000648D03*
X536161Y1012501D03*
Y1025318D03*
X539861Y1018910D03*
X541712Y1015705D03*
X545412D03*
X538012D03*
X536161Y1018910D03*
X549112Y1015705D03*
X536161Y1031727D03*
X545412Y1034931D03*
X539862Y1044544D03*
X539861Y1038136D03*
X541711Y1034931D03*
X538011D03*
X536161Y1038136D03*
X549112Y1034931D03*
X541711Y1054157D03*
X538011D03*
X545411D03*
X538011Y1060565D03*
X536161Y1050952D03*
X538011Y1066974D03*
X539861Y1076587D03*
X536162Y1082996D03*
X538011Y1092608D03*
X536161Y1089404D03*
X545411Y1092608D03*
X547262Y1082996D03*
X543561Y1095813D03*
X536161D03*
X547261D03*
X545412Y1105426D03*
X541711D03*
X539861Y1108630D03*
Y1102221D03*
X536161D03*
X541711Y1111834D03*
X545411D03*
X538011Y1105426D03*
X536161Y1108630D03*
X538011Y1111834D03*
X543561Y1108630D03*
X545411Y1124651D03*
Y1118243D03*
X543562Y1115039D03*
X539862D03*
X538011Y1124651D03*
X536161Y1115039D03*
X541711Y1131060D03*
X536162Y1134264D03*
X551429Y979057D03*
X550701Y972608D03*
X550961Y1031727D03*
X560571Y1614292D03*
X580431Y1602380D03*
X688999Y1051247D03*
X748399D03*
X1293802Y162999D03*
X1297007Y161149D03*
X1297012Y168549D03*
X1297007Y164849D03*
X1293802Y183349D03*
Y187049D03*
Y190749D03*
Y198149D03*
Y194449D03*
Y201849D03*
X1296999Y209249D03*
X1300774Y155288D03*
X1309832Y161149D03*
X1303417D03*
X1309832Y168549D03*
X1303417D03*
X1303422Y172249D03*
X1313033Y174099D03*
X1306622D03*
X1300207Y185199D03*
X1306617Y181499D03*
X1300207Y192599D03*
X1309817Y187049D03*
X1306617Y192599D03*
X1313023Y199999D03*
X1306617D03*
X1300207D03*
X1303407Y201849D03*
X1303422Y209249D03*
X1313032Y214799D03*
X1306622Y218499D03*
X1303417Y212949D03*
Y216649D03*
X1300207Y214799D03*
X1301151Y225450D03*
X1309828Y224049D03*
X1306622Y222199D03*
X1309100Y236477D03*
X1313920Y854584D03*
X1312266Y857972D03*
X1312070Y877014D03*
X1310221Y880219D03*
X1308370Y877014D03*
X1312070Y896240D03*
X1310220Y893036D03*
X1308371Y902649D03*
X1312070Y915466D03*
X1308370D03*
X1308371Y921875D03*
X1312070Y934692D03*
X1308371Y941100D03*
X1308370Y934692D03*
X1312070Y953917D03*
X1308370D03*
X1310221Y957122D03*
X1308371Y973143D03*
X1310221Y976347D03*
X1314352Y996480D03*
X1314353Y1002888D03*
X1308803Y1006093D03*
X1314353Y1015705D03*
Y1022114D03*
X1308803Y1025318D03*
Y1018910D03*
X1314353Y1041340D03*
X1308803Y1044544D03*
X1310653Y1041340D03*
X1314353Y1060565D03*
X1312502Y1082995D03*
X1314353Y1111834D03*
Y1105426D03*
X1312503Y1115039D03*
Y1127856D03*
X1320469Y155288D03*
X1322652Y161149D03*
X1316242D03*
X1319452Y166699D03*
X1329062Y168549D03*
X1319442Y170399D03*
X1318502Y176574D03*
Y186024D03*
Y182874D03*
X1329062Y172249D03*
X1316237D03*
X1331102Y176574D03*
X1327952Y186024D03*
Y182874D03*
X1318502Y189174D03*
X1315352Y195474D03*
X1327952Y189174D03*
X1331102Y195474D03*
X1327952Y198624D03*
X1321652D03*
X1325852Y214799D03*
X1319442Y218499D03*
X1329062Y209249D03*
X1319442Y207399D03*
X1329062Y216649D03*
X1319442Y222199D03*
X1329061Y224049D03*
X1326377Y235784D03*
X1321986Y236726D03*
X1326869Y844971D03*
X1323170D03*
X1321320Y848176D03*
X1330571Y851380D03*
X1323170D03*
X1319469D03*
X1317620Y854584D03*
X1315770Y857789D03*
X1330571Y864197D03*
X1326871D03*
X1323171D03*
Y857789D03*
X1325020Y854584D03*
X1321321Y860993D03*
X1319469Y857789D03*
X1317621Y867401D03*
X1328721D03*
X1325021D03*
X1330571Y877014D03*
X1328722Y880219D03*
X1326871Y877014D03*
X1321321Y873810D03*
X1315771Y877014D03*
X1317621Y873810D03*
X1321321Y880219D03*
X1319471Y877014D03*
X1315771Y883423D03*
X1326871D03*
X1323171D03*
X1328720Y899445D03*
X1315771Y896240D03*
Y889832D03*
X1328720Y893036D03*
Y886627D03*
X1325021D03*
X1321321Y893036D03*
X1319470Y896240D03*
X1321321Y899445D03*
X1328720Y905853D03*
X1325020D03*
X1317621Y912262D03*
X1317620Y905853D03*
X1328720Y912262D03*
X1323171Y909057D03*
Y902649D03*
X1321321Y912262D03*
X1315771Y915466D03*
X1319471D03*
X1328720Y925079D03*
Y918670D03*
X1325020Y925079D03*
X1317620D03*
X1323171Y928283D03*
Y921875D03*
X1321321Y918670D03*
X1317621Y931488D03*
X1328720D03*
X1321321D03*
X1323171Y941100D03*
X1325020Y944304D03*
X1323171Y947509D03*
X1317620Y944304D03*
X1328720D03*
Y937896D03*
X1315771Y934692D03*
X1321321Y937896D03*
X1319470Y934692D03*
X1321321Y957122D03*
X1323171Y966735D03*
X1325020Y963530D03*
X1323171Y960326D03*
X1321321Y950713D03*
X1315771Y953917D03*
Y966735D03*
X1319470Y953917D03*
X1319471Y966735D03*
X1319470Y960326D03*
X1317621Y950713D03*
X1328720Y957122D03*
Y963530D03*
Y950713D03*
X1321321Y969939D03*
X1325020Y982756D03*
X1323171Y979552D03*
X1321321Y976347D03*
X1315771Y973143D03*
X1319471D03*
X1328720Y969939D03*
X1330570Y973143D03*
X1326871D03*
X1328720Y982756D03*
X1328721Y976347D03*
X1315771Y979552D03*
X1318053Y1009297D03*
Y1002888D03*
X1327304Y1006093D03*
X1331003D03*
X1329153Y1009297D03*
Y1002888D03*
X1323603Y999684D03*
X1321753Y1009297D03*
X1319903Y1006093D03*
X1321753Y1002888D03*
X1323603Y1012501D03*
X1329153Y1028523D03*
Y1015705D03*
X1318053Y1022114D03*
Y1015705D03*
X1329153Y1022114D03*
X1325453Y1015705D03*
X1323603Y1018910D03*
X1321753Y1028523D03*
X1319903Y1018910D03*
X1321753Y1022114D03*
Y1015705D03*
X1319903Y1031727D03*
X1323603D03*
X1329153Y1034931D03*
Y1047749D03*
X1318053Y1041340D03*
X1319903Y1038136D03*
X1329153Y1041340D03*
X1325453Y1034931D03*
X1323603Y1038136D03*
X1321753Y1041340D03*
X1319903Y1044544D03*
X1321753Y1047749D03*
X1329153Y1060565D03*
Y1054157D03*
X1325453D03*
X1319903Y1057361D03*
Y1050952D03*
X1323603D03*
Y1057361D03*
X1321753Y1060565D03*
X1319903Y1063770D03*
X1329153Y1073383D03*
X1319903Y1076587D03*
Y1070178D03*
X1316204Y1076587D03*
X1329153Y1066974D03*
X1323603Y1076587D03*
Y1070178D03*
X1325454Y1073383D03*
X1321753Y1066974D03*
X1329153Y1079791D03*
X1321753D03*
X1318053D03*
X1329153Y1086200D03*
Y1092608D03*
X1325452Y1092609D03*
X1323603Y1089404D03*
X1321752Y1086200D03*
X1319902Y1082995D03*
X1316202D03*
X1316203Y1095813D03*
X1331003Y1108630D03*
X1329153Y1099017D03*
X1323603Y1108630D03*
X1316203D03*
Y1102221D03*
X1325453Y1099017D03*
X1323603Y1102221D03*
X1319903D03*
X1316203Y1115039D03*
X1331003D03*
X1327303Y1121447D03*
Y1115039D03*
X1325453Y1124651D03*
X1325454Y1118243D03*
X1321753D03*
X1319903Y1115039D03*
X1329152Y1137469D03*
X1329153Y1131060D03*
X1321752Y1137469D03*
X1325453Y1131060D03*
X1319903Y1134264D03*
X1344103Y155288D03*
X1342936Y159301D03*
X1335472Y161149D03*
X1346137Y168549D03*
X1342907Y166699D03*
X1332268D03*
X1346137Y164849D03*
X1339727D03*
X1335472Y168549D03*
X1339568Y176028D03*
X1339727Y179649D03*
X1342937Y181499D03*
Y185199D03*
X1346137Y172249D03*
X1335472D03*
X1339727Y190749D03*
X1342937Y188899D03*
X1334252Y195474D03*
X1346137Y194449D03*
Y190749D03*
X1346147Y209248D03*
X1332262Y218499D03*
Y214799D03*
X1332285Y226210D03*
X1342937Y222199D03*
X1332267D03*
X1343521Y841467D03*
X1336121D03*
X1345371Y851380D03*
X1341671D03*
X1337971D03*
X1334271D03*
X1345371Y864197D03*
X1343521Y854584D03*
X1341671Y864197D03*
X1337971D03*
X1336121Y854584D03*
X1334271Y864197D03*
X1343521Y867401D03*
X1336121D03*
X1345371Y877014D03*
X1343521Y880219D03*
X1341671Y877014D03*
X1337971D03*
X1334271D03*
X1332420Y886627D03*
X1345371Y896240D03*
Y889832D03*
X1341671Y896240D03*
Y889832D03*
X1337970Y896240D03*
X1337971Y889832D03*
X1336121Y893036D03*
X1334270Y889832D03*
X1332420Y905853D03*
X1341671Y909057D03*
Y902649D03*
X1336120Y912262D03*
X1334270Y909057D03*
X1334271Y902649D03*
X1347221Y912262D03*
X1345371Y915466D03*
X1341671D03*
X1337970D03*
X1332421Y925079D03*
X1341671Y928283D03*
Y921875D03*
X1334270Y928283D03*
X1334271Y921875D03*
X1347220Y918670D03*
X1336120Y931488D03*
X1347221D03*
X1341671Y947509D03*
X1334270D03*
X1334271Y941100D03*
X1332421Y944304D03*
X1345371Y934691D03*
X1341671D03*
X1337970D03*
X1337971Y953917D03*
X1345371D03*
X1341671D03*
Y960326D03*
X1347220Y957122D03*
X1343520Y963530D03*
X1339821D03*
X1341670Y966735D03*
X1347221Y950713D03*
X1334271Y960326D03*
X1336121Y957122D03*
X1332421Y963530D03*
X1334270Y966735D03*
X1336120Y950713D03*
X1347221Y969939D03*
X1337970Y973143D03*
X1347220Y976347D03*
X1345371Y973143D03*
X1341671Y979552D03*
Y973143D03*
X1336120Y969939D03*
X1336121Y976347D03*
X1334271Y979552D03*
X1332421Y982756D03*
X1342104Y999684D03*
Y1006093D03*
X1338403D03*
X1336553Y1009297D03*
X1336554Y1002888D03*
X1334704Y999684D03*
X1347654Y1009297D03*
X1342103Y1012501D03*
X1334703D03*
X1332854Y1015705D03*
X1345804Y1025318D03*
X1343953Y1015705D03*
X1342104Y1025318D03*
Y1018910D03*
X1340254Y1015705D03*
X1336553Y1028523D03*
X1338403Y1025318D03*
X1336554Y1022114D03*
X1334704Y1018910D03*
X1347653Y1028523D03*
Y1022114D03*
X1342104Y1031727D03*
X1334703D03*
X1332854Y1034931D03*
X1345804Y1044544D03*
X1342104D03*
Y1038136D03*
X1338403Y1044544D03*
X1336554Y1041340D03*
X1334704Y1038136D03*
X1347653Y1041340D03*
X1336553Y1047749D03*
X1347653D03*
X1332854Y1054157D03*
X1342104Y1057361D03*
Y1050952D03*
X1336554Y1060565D03*
X1334704Y1057361D03*
X1334703Y1050952D03*
X1347653Y1060565D03*
X1345804Y1063770D03*
X1342104D03*
X1338403D03*
X1332854Y1073383D03*
X1342104Y1070178D03*
X1336553Y1066974D03*
X1334703Y1070178D03*
X1334704Y1076587D03*
X1347654Y1066974D03*
X1336554Y1079791D03*
X1347653D03*
X1345804Y1082995D03*
X1342104Y1089404D03*
Y1082995D03*
X1338403D03*
X1336553Y1086200D03*
X1334703Y1089404D03*
X1332854Y1092608D03*
X1347654Y1086200D03*
X1342104Y1095813D03*
X1334703D03*
X1342104Y1102221D03*
X1338404D03*
X1336553Y1099017D03*
X1332853Y1105426D03*
Y1099017D03*
X1347654Y1105426D03*
Y1099017D03*
X1340254Y1111834D03*
X1332854D03*
X1347654D03*
X1343953Y1118243D03*
X1340253D03*
X1338403Y1115039D03*
X1336553Y1118243D03*
X1332853D03*
X1347653D03*
X1342104Y1127856D03*
X1334703D03*
X1343953Y1131060D03*
X1342103Y1140973D03*
X1340254Y1131060D03*
X1336554D03*
X1334703Y1140973D03*
X1332854Y1131060D03*
X1347653D03*
X1349351Y159298D03*
X1355758D03*
X1355761Y162998D03*
X1358865Y166732D03*
Y158854D03*
Y162793D03*
X1349351Y166698D03*
X1352557Y164848D03*
X1358865Y170671D03*
Y174603D03*
Y182484D03*
Y178544D03*
X1355761Y170398D03*
X1352557Y179648D03*
X1358371Y188778D03*
X1358865Y195240D03*
Y199180D03*
X1349351Y196298D03*
X1352561Y194448D03*
X1352551Y190748D03*
X1349345Y188898D03*
X1355761Y192598D03*
X1358865Y207060D03*
Y203120D03*
Y213994D03*
Y217934D03*
X1352560Y205549D03*
X1355765Y207399D03*
X1349351Y214798D03*
X1352561Y212948D03*
X1349351Y211098D03*
Y222198D03*
X1358321Y841467D03*
X1350921D03*
X1360171Y851380D03*
X1356471D03*
X1352771D03*
X1349071D03*
X1363871D03*
X1360171Y864197D03*
X1358321Y854584D03*
X1356471Y864197D03*
X1352771D03*
X1350921Y854584D03*
X1349071Y864197D03*
X1363871D03*
X1358321Y867401D03*
X1350921D03*
X1360171Y877014D03*
X1358321Y880219D03*
X1356471Y877014D03*
X1352771D03*
X1350921Y880219D03*
X1349071Y877014D03*
X1363871D03*
X1360171Y889832D03*
X1356471D03*
X1354621Y893036D03*
X1352771Y889832D03*
X1349071D03*
X1363871Y896240D03*
Y889832D03*
X1362021Y899445D03*
X1354620D03*
X1362020Y912262D03*
X1360170Y909057D03*
X1360171Y902649D03*
X1358321Y905853D03*
X1354620Y912262D03*
Y905853D03*
X1350920D03*
X1349071Y909057D03*
X1349070Y902649D03*
X1363870Y915466D03*
X1362021Y918670D03*
X1360170Y928283D03*
X1360171Y921875D03*
X1358321Y925079D03*
X1354620D03*
Y918670D03*
X1350920Y925079D03*
X1349071Y928283D03*
X1349070Y921875D03*
X1362020Y931488D03*
X1360171Y941100D03*
X1358321Y944304D03*
X1354620D03*
X1360170Y947509D03*
X1350920Y944304D03*
X1349071Y947509D03*
X1349070Y941100D03*
X1362021Y937896D03*
X1354620D03*
X1363870Y934691D03*
X1363871Y953917D03*
X1360171Y960326D03*
X1362021Y957122D03*
X1354620D03*
X1358321Y963530D03*
X1354620D03*
X1360170Y966735D03*
X1354620Y950713D03*
X1362020D03*
X1349070Y960326D03*
X1350920Y963530D03*
X1349071Y966735D03*
X1362020Y969939D03*
X1354620D03*
X1363870Y973143D03*
X1362021Y976347D03*
X1360171Y979552D03*
X1358321Y982756D03*
X1356470Y973143D03*
X1354620Y982756D03*
X1354621Y976347D03*
X1350920Y982756D03*
X1349070Y979552D03*
X1352771Y973143D03*
X1351352Y996480D03*
X1349503Y999684D03*
X1362453Y1009297D03*
X1362454Y1002888D03*
X1360604Y999684D03*
X1355053Y1009297D03*
Y1002888D03*
X1360603Y1012501D03*
X1349504D03*
X1362453Y1028523D03*
X1362454Y1022114D03*
X1360604Y1018910D03*
X1358754Y1015705D03*
X1355053Y1028523D03*
Y1022114D03*
Y1015705D03*
X1351353D03*
X1349503Y1018910D03*
X1360603Y1031727D03*
X1349504D03*
X1362454Y1041340D03*
X1360604Y1038136D03*
X1358754Y1034931D03*
X1355053Y1041340D03*
Y1034931D03*
X1351353D03*
X1349503Y1038136D03*
X1362453Y1047749D03*
X1355053D03*
X1362454Y1060565D03*
X1360604Y1057361D03*
X1360603Y1050952D03*
X1358754Y1054157D03*
X1355053D03*
X1351353D03*
X1349503Y1057361D03*
X1349504Y1050952D03*
X1362453Y1066974D03*
X1360604Y1076587D03*
X1360603Y1070178D03*
X1358754Y1073383D03*
X1355053D03*
Y1066974D03*
X1351353Y1073383D03*
X1349503Y1076587D03*
X1349504Y1070178D03*
X1362453Y1079791D03*
X1355053D03*
X1362453Y1086200D03*
X1360603Y1089404D03*
X1358753Y1092608D03*
X1355053D03*
Y1086200D03*
X1351353Y1092608D03*
X1349504Y1089404D03*
X1360604Y1095813D03*
X1349504D03*
X1362454Y1099017D03*
X1360604Y1102221D03*
X1356904Y1108630D03*
X1355053Y1099017D03*
X1353204Y1102221D03*
X1349503Y1108630D03*
Y1102221D03*
X1362453Y1118243D03*
X1360603Y1115039D03*
X1358753Y1118243D03*
X1355053D03*
X1353203Y1115039D03*
X1351353Y1118243D03*
X1349503Y1115039D03*
X1356903Y1127856D03*
X1349503D03*
X1362453Y1131060D03*
X1358753D03*
X1356903Y1140973D03*
X1355053Y1131060D03*
X1351353D03*
X1349503Y1140973D03*
X1373121Y841467D03*
X1365721D03*
X1378671Y851380D03*
X1374971D03*
X1371271D03*
X1367571D03*
X1378671Y864197D03*
X1374971D03*
X1373121Y854584D03*
X1371271Y864197D03*
X1367571D03*
X1365721Y854584D03*
X1373121Y867401D03*
X1365721D03*
X1378671Y877014D03*
X1374971D03*
X1373121Y880219D03*
X1371271Y877014D03*
X1367571D03*
X1365721Y880219D03*
X1378671Y889832D03*
X1374971D03*
X1371271Y896240D03*
Y889832D03*
X1367570Y896240D03*
X1367571Y889832D03*
X1365721Y893036D03*
X1374971Y909057D03*
X1374970Y902649D03*
X1373121Y912262D03*
X1367571Y909057D03*
Y902649D03*
X1371271Y915466D03*
X1367571D03*
X1376820Y925079D03*
X1374971Y928283D03*
X1374970Y921875D03*
X1373120Y918670D03*
X1367571Y928283D03*
Y921875D03*
X1376820Y937896D03*
X1374970Y941100D03*
X1371271Y934691D03*
X1367571Y941100D03*
Y934691D03*
X1374971Y947509D03*
X1367571D03*
X1376820Y957122D03*
X1374970Y960326D03*
X1373120Y957122D03*
X1373121Y950713D03*
X1371271Y953917D03*
X1367571Y960326D03*
Y953917D03*
X1376820Y963530D03*
X1374971Y966735D03*
X1367571D03*
X1376820Y982756D03*
Y969939D03*
X1374970Y979552D03*
X1373120Y976347D03*
X1373121Y969939D03*
X1371271Y973143D03*
X1367571Y979552D03*
Y973143D03*
X1364303Y1006093D03*
X1377253Y1002888D03*
X1373554Y1009297D03*
X1373553Y1002888D03*
X1371704Y1006093D03*
X1368004D03*
Y999684D03*
X1375404Y1012501D03*
X1368003D03*
X1364303Y1025318D03*
X1375403Y1018910D03*
X1373553Y1028523D03*
Y1022114D03*
X1371704Y1025318D03*
X1369853Y1015705D03*
X1368004Y1025318D03*
Y1018910D03*
X1366154Y1015705D03*
X1375404Y1031727D03*
X1368004D03*
X1364303Y1044544D03*
X1375403Y1038136D03*
X1373553Y1041340D03*
X1371704Y1044544D03*
X1368004D03*
Y1038136D03*
X1373553Y1047749D03*
X1375403Y1057361D03*
X1375404Y1050952D03*
X1373553Y1060565D03*
X1368004Y1057361D03*
Y1050952D03*
X1364303Y1063770D03*
X1371704D03*
X1368004D03*
X1377253Y1073383D03*
X1375403Y1076587D03*
X1375404Y1070178D03*
X1373554Y1066974D03*
X1368004Y1076587D03*
Y1070178D03*
X1377253Y1079791D03*
X1373553D03*
X1364303Y1082995D03*
X1377254Y1092608D03*
X1377253Y1086200D03*
X1375404Y1089404D03*
X1373554Y1086200D03*
X1371704Y1082995D03*
X1368004Y1089404D03*
Y1082995D03*
X1379104Y1095813D03*
X1375403D03*
X1368004D03*
X1364304Y1108630D03*
Y1102221D03*
X1377253Y1105426D03*
X1375404Y1102221D03*
X1373554Y1099017D03*
X1371704Y1102221D03*
X1366153Y1105426D03*
X1373553Y1111834D03*
X1366153D03*
X1364303Y1115039D03*
X1377253Y1118243D03*
X1373553D03*
X1371703Y1115039D03*
X1369853Y1118243D03*
X1366153D03*
X1364303Y1127856D03*
X1379103D03*
X1371703D03*
X1364303Y1140973D03*
X1379103D03*
X1377253Y1131060D03*
X1373553D03*
X1371703Y1140973D03*
X1369853Y1131060D03*
X1366153D03*
X1380521Y841467D03*
X1395321D03*
X1387921D03*
X1393471Y851380D03*
X1389771D03*
X1386071D03*
X1382371D03*
X1380521Y854584D03*
X1395321D03*
X1393471Y864197D03*
X1389771D03*
X1387921Y854584D03*
X1386071Y864197D03*
X1382371D03*
X1380521Y867401D03*
X1395321D03*
X1387921D03*
X1380521Y880219D03*
X1395321D03*
X1393471Y877014D03*
X1389771D03*
X1387921Y880219D03*
X1386071Y877014D03*
Y870606D03*
X1382371Y877014D03*
X1395321Y893036D03*
X1393471Y889832D03*
X1389771D03*
X1387921Y893036D03*
X1386071Y889832D03*
X1384221Y893036D03*
X1382371Y889832D03*
X1386071Y902649D03*
X1380520Y912262D03*
Y905853D03*
X1395320Y912262D03*
X1395321Y905853D03*
X1393471Y902649D03*
X1389771D03*
X1386071Y909057D03*
Y915466D03*
X1380520Y918670D03*
X1395187Y926265D03*
X1395320Y918670D03*
X1386071Y921875D03*
X1381189Y930811D03*
Y938045D03*
X1381287Y946239D03*
Y948539D03*
X1381189Y935745D03*
X1390234Y942097D03*
X1381264Y965896D03*
Y963596D03*
X1390506Y971139D03*
X1392896D03*
X1381003Y981269D03*
Y978969D03*
Y986421D03*
X1381243Y992971D03*
Y995271D03*
X1381003Y988721D03*
X1381369Y1007156D03*
X1381373Y1004848D03*
X1393716Y1000059D03*
X1391326D03*
X1381128Y1022427D03*
X1381140Y1026821D03*
X1384466Y1034270D03*
Y1031970D03*
X1393904Y1044544D03*
X1384653Y1041340D03*
X1380953Y1047749D03*
X1388353D03*
X1380953Y1060565D03*
X1393904Y1050952D03*
X1392053Y1060565D03*
Y1054157D03*
X1388353Y1060565D03*
X1386504Y1050952D03*
X1384653Y1054157D03*
X1380953Y1066974D03*
X1395753Y1073383D03*
X1392053Y1066974D03*
X1386504Y1076587D03*
Y1070178D03*
X1382803Y1076587D03*
X1380953Y1079791D03*
X1388353D03*
X1393903Y1089404D03*
Y1082995D03*
X1392053Y1092608D03*
X1392054Y1086200D03*
X1388353Y1092608D03*
X1384653Y1086200D03*
X1386504Y1095813D03*
X1382804D03*
X1380954Y1105426D03*
X1393904Y1102221D03*
X1392054Y1099017D03*
X1390204Y1108630D03*
X1388353Y1099017D03*
X1386504Y1102221D03*
X1382803Y1108630D03*
Y1102221D03*
X1380954Y1111834D03*
X1380953Y1118243D03*
X1386503Y1115039D03*
X1384653Y1118243D03*
X1382803Y1115039D03*
X1386503Y1127856D03*
X1380953Y1131060D03*
X1386503Y1140973D03*
X1384653Y1131060D03*
X1408269Y844971D03*
X1402721Y841467D03*
X1397171Y851380D03*
X1408271D03*
X1404571D03*
X1400871D03*
X1397171Y864197D03*
X1408271D03*
X1404571D03*
X1402721Y854584D03*
X1400871Y864197D03*
X1410121Y854584D03*
Y867401D03*
X1402721D03*
X1397171Y877014D03*
X1410121Y880219D03*
X1408271Y877014D03*
X1404571D03*
X1402721Y880219D03*
X1400871Y877014D03*
X1397171Y889832D03*
X1410121Y893036D03*
X1408271Y889832D03*
X1404571D03*
X1402721Y893036D03*
X1400871Y889832D03*
Y902649D03*
X1397171D03*
X1408271D03*
X1404571Y909057D03*
Y902649D03*
Y915466D03*
X1410121Y925079D03*
Y931488D03*
X1403016Y949498D03*
Y947198D03*
X1406420Y937896D03*
X1404016Y936469D03*
X1410120Y937896D03*
X1403046Y963634D03*
Y965934D03*
Y978035D03*
Y980335D03*
Y992421D03*
Y994721D03*
Y1009174D03*
Y1006874D03*
Y1021962D03*
Y1019662D03*
X1397604Y1063770D03*
Y1082995D03*
Y1095813D03*
X1428620Y848176D03*
X1415669Y844971D03*
X1421220Y848176D03*
X1417520D03*
X1423070Y851380D03*
X1419370D03*
X1415671D03*
X1413822Y860993D03*
X1426771Y864197D03*
X1424921Y854584D03*
X1423071Y864197D03*
X1419371D03*
X1417521Y854584D03*
X1415671Y864197D03*
Y857789D03*
X1424921Y867401D03*
X1417521D03*
X1424921Y880219D03*
X1423071Y877014D03*
X1419371D03*
X1417521Y880219D03*
X1415671Y877014D03*
X1413820Y886627D03*
X1426771Y889832D03*
X1424921Y893036D03*
X1423071Y889832D03*
X1419371D03*
X1417521Y893036D03*
X1415671Y896240D03*
Y889832D03*
X1413821Y899445D03*
Y905853D03*
X1426771Y902649D03*
X1423071Y909057D03*
Y902649D03*
X1419371D03*
X1415670D03*
X1423071Y915466D03*
Y928283D03*
X1417520Y925079D03*
Y931488D03*
X1413820Y918670D03*
X1423071Y921875D03*
X1424920Y937896D03*
X1421220D03*
X1417520D03*
X1413820D03*
X1427203Y1044544D03*
X1425353Y1047749D03*
X1429053Y1060565D03*
X1423503Y1057361D03*
Y1050952D03*
Y1063770D03*
X1425353Y1073383D03*
X1423503Y1076587D03*
Y1070178D03*
X1429053Y1079791D03*
X1425353D03*
X1425354Y1086200D03*
X1423503Y1082995D03*
X1437871Y851380D03*
X1434171D03*
X1430470D03*
X1432321Y841467D03*
X1439721D03*
X1445271Y851380D03*
X1441571D03*
X1439721Y854584D03*
X1432321D03*
X1437871Y864197D03*
X1434171D03*
X1430471D03*
X1445271D03*
X1441571D03*
X1432321Y867401D03*
X1439721D03*
X1437871Y877014D03*
X1434171D03*
X1432321Y880219D03*
X1430471Y877014D03*
X1445271D03*
X1441571D03*
X1439721Y880219D03*
X1437871Y889832D03*
X1434171D03*
X1432321Y893036D03*
X1430471Y889832D03*
X1445271Y896240D03*
X1439721Y893036D03*
X1445271Y889832D03*
X1441571D03*
X1437871Y902649D03*
X1434171D03*
X1432320Y905853D03*
X1430471Y902649D03*
X1441571D03*
Y909057D03*
Y915466D03*
X1430244Y931358D03*
Y933658D03*
X1432320Y918670D03*
X1430575Y1022185D03*
Y1019885D03*
X1443541Y1036914D03*
X1436453Y1041340D03*
X1442003Y1044544D03*
X1432753Y1047749D03*
X1440153D03*
X1432753Y1054157D03*
X1442004Y1057361D03*
X1438304Y1050952D03*
X1434604Y1063770D03*
X1442004D03*
X1432753Y1073383D03*
X1430903Y1076587D03*
X1430904Y1070178D03*
X1443853Y1073383D03*
Y1066974D03*
X1438304Y1070178D03*
X1432754Y1079791D03*
X1443853D03*
X1434603Y1082995D03*
X1432753Y1086200D03*
X1436453Y1092608D03*
X1443854Y1086200D03*
X1440153D03*
X1443854Y1092608D03*
X1442003Y1108630D03*
Y1102221D03*
X1440154Y1099017D03*
X1443853Y1105426D03*
Y1111834D03*
X1454521Y841467D03*
X1447121D03*
X1460071Y851380D03*
X1452671D03*
X1456371D03*
X1448971D03*
X1460071Y864197D03*
X1456371D03*
X1454521Y854584D03*
X1452671Y864197D03*
X1447121Y854584D03*
X1448971Y864197D03*
X1454521Y867401D03*
X1447121D03*
X1460071Y877014D03*
X1456371D03*
X1454521Y880219D03*
X1452671Y877014D03*
X1448971D03*
X1448970Y870606D03*
X1447121Y880219D03*
Y873810D03*
X1456370Y896240D03*
X1456371Y889832D03*
X1454521Y893036D03*
X1447121D03*
X1460071Y889832D03*
X1452671D03*
X1448971D03*
X1458220Y899445D03*
X1460071Y909057D03*
X1458221Y912262D03*
X1450820Y905853D03*
X1460070Y902649D03*
X1452426Y930125D03*
X1460071Y928283D03*
X1458220Y918670D03*
X1456371Y921875D03*
X1460070D03*
X1452670D03*
X1450820Y918670D03*
X1458220Y931488D03*
X1452426Y934725D03*
X1454520Y944304D03*
X1452321Y945354D03*
Y947654D03*
X1460070Y941100D03*
X1458221Y944304D03*
X1458220Y937896D03*
X1456371Y934691D03*
X1460070Y947509D03*
X1452426Y962325D03*
Y960025D03*
Y964625D03*
X1460070Y960326D03*
X1458220Y957122D03*
X1458221Y950713D03*
X1460071Y966735D03*
X1452426Y966925D03*
X1452333Y977669D03*
X1452476Y980736D03*
X1458221Y969939D03*
X1460070Y979552D03*
X1458220Y976347D03*
X1452426Y996825D03*
Y994525D03*
Y989925D03*
Y987625D03*
X1452436Y1010499D03*
X1452426Y1006025D03*
Y1003725D03*
Y1012925D03*
X1460503Y999684D03*
X1458654Y1009297D03*
X1458653Y1002888D03*
X1460504Y1012501D03*
X1452416Y1022635D03*
X1452426Y1017525D03*
X1458653Y1028523D03*
Y1022114D03*
X1460503Y1018910D03*
Y1031727D03*
X1447424Y1036526D03*
X1449649Y1035928D03*
X1458653Y1041340D03*
X1458654Y1034931D03*
X1451253Y1041340D03*
X1460503Y1038136D03*
X1458653Y1047749D03*
X1447553D03*
X1460503Y1057361D03*
X1458653Y1060565D03*
X1456804Y1050952D03*
X1451253Y1060565D03*
X1447553Y1054157D03*
X1460504Y1050952D03*
X1460503Y1076587D03*
X1451253Y1066974D03*
X1449404Y1070178D03*
X1460504D03*
X1458654Y1066974D03*
X1454953Y1073383D03*
X1458653Y1079791D03*
X1454954D03*
X1451253D03*
X1445703Y1089404D03*
X1458654Y1086200D03*
X1456804Y1082995D03*
X1453104Y1089404D03*
X1449404Y1082995D03*
X1460504Y1089404D03*
X1445704Y1095813D03*
X1460504D03*
X1456803D03*
X1445704Y1102221D03*
X1458653Y1105426D03*
X1456804Y1108630D03*
X1454953Y1099017D03*
X1449404Y1108630D03*
X1453104Y1102221D03*
X1451254Y1099017D03*
X1447553D03*
X1458653Y1111834D03*
X1460504Y1108630D03*
X1451253Y1111834D03*
X1447553D03*
X1454953Y1105426D03*
X1445704Y1108630D03*
X1449404Y1102221D03*
X1458653Y1099017D03*
X1454953Y1111834D03*
X1453104Y1108630D03*
X1447553Y1105426D03*
X1451253D03*
X1460504Y1102221D03*
X1458653Y1118243D03*
X1456803Y1115039D03*
X1454953Y1118243D03*
X1453103Y1115039D03*
X1451253Y1118243D03*
X1460503Y1127856D03*
X1453103D03*
X1460504Y1115039D03*
X1449404D03*
X1458653Y1131060D03*
X1454953D03*
X1453103Y1140973D03*
X1451253Y1131060D03*
X1449403Y1134264D03*
X1460503Y1140973D03*
X1469321Y841467D03*
X1461921D03*
X1476721D03*
X1474871Y851380D03*
X1471171D03*
X1467471D03*
X1463771D03*
X1461921Y854584D03*
X1474871Y864197D03*
X1471171D03*
X1469321Y854584D03*
X1467471Y864197D03*
X1463771D03*
X1476721Y854584D03*
X1461921Y867401D03*
X1476721D03*
X1469321D03*
X1461921Y880219D03*
X1471171Y877014D03*
X1476721Y880219D03*
X1474871Y877014D03*
X1469321Y880219D03*
X1467471Y877014D03*
X1463771D03*
X1474871Y889832D03*
X1465621Y893036D03*
X1476721D03*
X1474871Y896240D03*
X1471171Y889832D03*
X1467471D03*
X1463771D03*
X1473021Y899445D03*
X1465620D03*
X1461920Y905853D03*
X1473020Y912262D03*
X1471171Y909057D03*
X1465620Y905853D03*
X1471171Y902649D03*
X1469321Y905853D03*
X1474870Y915466D03*
X1461920Y925079D03*
X1471170Y928283D03*
X1469321Y925079D03*
X1465620D03*
Y918670D03*
X1473021D03*
X1471171Y921875D03*
X1473020Y931488D03*
X1465620D03*
X1461920Y944304D03*
X1474871Y934691D03*
X1473021Y937896D03*
X1471171Y941100D03*
X1469321Y944304D03*
X1465620D03*
Y937896D03*
X1471170Y947509D03*
X1474871Y953917D03*
X1473021Y957122D03*
X1471171Y960326D03*
X1465620Y957122D03*
Y950713D03*
X1473020D03*
X1461920Y963530D03*
X1476721D03*
X1471170Y966735D03*
X1469321Y963530D03*
X1465620D03*
X1473021Y976347D03*
X1473020Y969939D03*
X1465620Y976347D03*
Y969939D03*
X1474870Y973143D03*
X1471171Y979552D03*
X1461920Y982756D03*
X1469321D03*
X1465620D03*
X1475303Y1006093D03*
X1473453Y1009297D03*
X1473454Y1002888D03*
X1471604Y999684D03*
X1466053Y1009297D03*
X1466054Y1002888D03*
X1467903Y1006093D03*
X1464204D03*
X1471603Y1012501D03*
X1462353Y1015705D03*
X1473453Y1028523D03*
X1466053D03*
Y1022114D03*
Y1015705D03*
X1477154D03*
X1475303Y1025318D03*
X1473453Y1022114D03*
X1471604Y1018910D03*
X1469754Y1015705D03*
X1471603Y1031727D03*
X1462353Y1034931D03*
X1473454Y1041340D03*
X1466053D03*
Y1034931D03*
X1475303Y1044544D03*
X1471604Y1038136D03*
X1469754Y1034931D03*
X1466053Y1047749D03*
X1473453D03*
X1462353Y1054157D03*
X1473453Y1060565D03*
X1471604Y1057361D03*
X1466053Y1060565D03*
Y1054157D03*
X1471603Y1050952D03*
X1469753Y1054157D03*
X1475304Y1063770D03*
X1462353Y1073383D03*
X1471604Y1076587D03*
X1469754Y1073383D03*
X1466053Y1066974D03*
X1473453D03*
X1471603Y1070178D03*
X1466053Y1073383D03*
X1473454Y1079791D03*
X1466053D03*
X1462353Y1092608D03*
X1475303Y1082995D03*
X1473453Y1086200D03*
X1469754Y1092608D03*
X1466053D03*
Y1086200D03*
X1471603Y1089404D03*
X1475304Y1095813D03*
X1471604D03*
X1467904D03*
X1462353Y1105426D03*
X1462354Y1099017D03*
X1475303Y1108630D03*
Y1102221D03*
X1473454Y1105426D03*
X1469753D03*
X1467904Y1102221D03*
X1464203D03*
X1473454Y1111834D03*
X1466053D03*
Y1099017D03*
X1471604Y1102221D03*
X1477153Y1099017D03*
X1469753D03*
X1473453D03*
X1466053Y1105426D03*
X1462353Y1111834D03*
X1467904Y1108630D03*
X1464204D03*
X1462353Y1118243D03*
X1477153D03*
X1475303Y1115039D03*
X1473453Y1118243D03*
X1471604Y1121447D03*
X1469754Y1118243D03*
X1466053D03*
X1475303Y1127856D03*
X1467903D03*
X1467904Y1115039D03*
X1471604D03*
X1462353Y1131060D03*
X1477153D03*
X1475303Y1140973D03*
X1473453Y1131060D03*
X1469753D03*
X1466053D03*
X1467903Y1140973D03*
X1491521Y841467D03*
X1484121D03*
X1478571Y851380D03*
X1482271D03*
X1489671D03*
X1485971D03*
X1493371D03*
X1478571Y864197D03*
X1491521Y854584D03*
X1489671Y864197D03*
X1485971D03*
X1482271D03*
X1493371D03*
X1491521Y867401D03*
X1484121D03*
Y854584D03*
X1478571Y877014D03*
X1491521Y880219D03*
X1485971Y877014D03*
X1484121Y880219D03*
X1489671Y877014D03*
X1482271D03*
X1493371D03*
X1478570Y896240D03*
X1478571Y889832D03*
X1491521Y893036D03*
X1482271Y889832D03*
X1489671D03*
X1485971D03*
X1482270Y896240D03*
X1480421Y893036D03*
X1493371Y889832D03*
X1491520Y899445D03*
X1484120D03*
X1478571Y909057D03*
Y902649D03*
X1491520Y912262D03*
X1487820Y905853D03*
X1485971Y909057D03*
X1484121Y912262D03*
X1491520Y905853D03*
X1485970Y902649D03*
X1478571Y915466D03*
X1482271D03*
X1478571Y928283D03*
Y921875D03*
X1491520Y925079D03*
Y918670D03*
X1487820Y925079D03*
X1485971Y928283D03*
X1485970Y921875D03*
X1484120Y918670D03*
X1491520Y931488D03*
X1484121D03*
X1478571Y941100D03*
Y934691D03*
X1491520Y944304D03*
Y937896D03*
X1487820Y944304D03*
X1485970Y941100D03*
X1482271Y934691D03*
X1478571Y947509D03*
Y960326D03*
Y953917D03*
X1491520Y957122D03*
Y950713D03*
X1485970Y960326D03*
X1484120Y957122D03*
X1482271Y953917D03*
X1484121Y950713D03*
X1478570Y966735D03*
X1491520Y963530D03*
X1485971Y966735D03*
X1487820Y963530D03*
X1480420D03*
X1478571Y979552D03*
Y973143D03*
X1491521Y976347D03*
X1491520Y969939D03*
X1484120Y976347D03*
X1484121Y969939D03*
X1489671Y973143D03*
X1485970Y979552D03*
X1482271Y973143D03*
X1493370D03*
X1491520Y982756D03*
X1487820D03*
X1479004Y999684D03*
X1486403D03*
X1484553Y1002888D03*
X1482704Y1006093D03*
X1479003Y1012501D03*
X1486404D03*
X1491953Y1009297D03*
Y1002888D03*
X1484554Y1009297D03*
X1479004Y1025318D03*
Y1018910D03*
X1491953Y1028523D03*
Y1022114D03*
X1484553Y1028523D03*
X1486403Y1018910D03*
X1484553Y1022114D03*
X1482704Y1025318D03*
X1480853Y1015705D03*
X1479004Y1031727D03*
X1486404D03*
X1488253Y1015705D03*
X1491953D03*
X1479004Y1044544D03*
Y1038136D03*
X1491953Y1034931D03*
Y1041340D03*
X1488253Y1034931D03*
X1486403Y1038136D03*
X1484553Y1041340D03*
X1482704Y1044544D03*
X1491953Y1047749D03*
X1484553D03*
X1479004Y1057361D03*
Y1050952D03*
X1491953Y1054157D03*
X1486404Y1057361D03*
X1484553Y1060565D03*
X1488253Y1054157D03*
X1486404Y1050952D03*
X1491953Y1060565D03*
X1479004Y1063770D03*
X1482704D03*
X1479004Y1076587D03*
Y1070178D03*
X1486404Y1076587D03*
Y1070178D03*
X1488253Y1073383D03*
X1484553Y1066974D03*
X1491953Y1073383D03*
Y1066974D03*
X1484553Y1079791D03*
X1491953D03*
X1479004Y1089404D03*
Y1082995D03*
X1488254Y1092608D03*
X1486404Y1089404D03*
X1484554Y1086200D03*
X1482704Y1082995D03*
X1491954Y1092608D03*
X1479004Y1095813D03*
X1490103D03*
X1493804D03*
X1479004Y1102221D03*
X1490104Y1108630D03*
Y1102221D03*
X1488254Y1099017D03*
X1484553D03*
X1482704Y1108630D03*
X1480853Y1099017D03*
X1491953Y1105426D03*
Y1111834D03*
X1493804Y1108630D03*
X1490103Y1115039D03*
X1488253Y1118243D03*
X1484553D03*
X1480853D03*
X1486403Y1115039D03*
X1491953Y1118243D03*
X1490103Y1127856D03*
X1482703D03*
X1493804Y1115039D03*
X1490103Y1140973D03*
X1488253Y1131060D03*
X1484553D03*
X1480853D03*
X1482703Y1140973D03*
X1491953Y1131060D03*
X1504471Y844671D03*
X1498921Y841467D03*
X1508171Y851380D03*
X1504471D03*
X1500771D03*
X1497071D03*
X1504471Y864197D03*
X1500771D03*
X1508170Y857789D03*
X1497071Y864197D03*
X1506321Y860993D03*
Y854584D03*
X1498921D03*
X1510021Y860993D03*
X1506320Y867401D03*
X1498921D03*
X1510021D03*
X1504471Y877014D03*
X1498921Y880219D03*
X1508171Y877014D03*
X1497071D03*
X1506321Y880219D03*
X1500771Y877014D03*
X1510021Y880219D03*
Y873810D03*
X1508170Y883423D03*
X1508171Y889832D03*
X1504471Y896240D03*
Y889832D03*
X1500771D03*
X1508171Y896240D03*
X1502621Y893036D03*
X1500771Y896240D03*
X1497071Y889832D03*
X1510021Y893036D03*
X1498921Y899445D03*
X1510021D03*
X1495221Y905853D03*
X1504471Y902649D03*
X1498920Y912262D03*
X1497070Y909057D03*
X1497071Y902649D03*
X1508171Y915466D03*
X1504471D03*
X1500770D03*
X1504471Y909057D03*
X1510021Y912262D03*
X1495221Y925079D03*
X1504471Y921875D03*
X1497070Y928283D03*
X1498921Y918670D03*
X1497071Y921875D03*
X1498920Y931488D03*
X1504471Y928283D03*
X1510021Y918670D03*
X1510020Y931488D03*
X1495221Y944304D03*
X1504471Y941100D03*
Y934691D03*
X1500770D03*
X1498921Y937896D03*
X1497071Y941100D03*
X1497070Y947509D03*
X1508171Y934691D03*
X1510021Y937896D03*
X1504471Y947509D03*
Y960326D03*
Y953917D03*
X1500771D03*
X1498921Y957122D03*
X1497071Y960326D03*
X1498920Y950713D03*
X1495221Y963530D03*
X1497070Y966735D03*
X1502621Y963530D03*
X1510021Y957122D03*
X1508171Y953917D03*
X1510021Y950713D03*
X1506320Y963530D03*
X1504471Y966735D03*
Y979552D03*
Y973143D03*
X1498921Y976347D03*
X1498920Y969939D03*
X1500770Y973143D03*
X1497071Y979552D03*
X1510021Y976347D03*
X1495221Y982756D03*
X1510043Y980606D03*
X1510021Y969939D03*
X1508171Y973143D03*
X1497503Y1012501D03*
Y999684D03*
X1504904Y1006093D03*
Y999684D03*
X1501203Y1006093D03*
X1499353Y1009297D03*
X1499354Y1002888D03*
X1510453Y1009297D03*
Y1002888D03*
X1508603Y1006093D03*
X1504903Y1012501D03*
X1504904Y1025318D03*
X1499353Y1028523D03*
X1501203Y1025318D03*
X1504904Y1031727D03*
X1497503D03*
X1495654Y1015705D03*
X1497504Y1018910D03*
X1499353Y1022114D03*
X1503054Y1015705D03*
X1504904Y1018910D03*
X1506753Y1015705D03*
X1510453Y1028523D03*
X1510452Y1022114D03*
X1508603Y1025318D03*
X1504904Y1044544D03*
X1501203D03*
X1499354Y1041340D03*
X1497504Y1038136D03*
X1495654Y1034931D03*
X1508604Y1044544D03*
X1499353Y1047749D03*
X1504904Y1038136D03*
X1510453Y1041340D03*
Y1047749D03*
X1504904Y1057361D03*
Y1050952D03*
X1499354Y1060565D03*
X1497504Y1057361D03*
X1497503Y1050952D03*
X1495654Y1054157D03*
X1504904Y1063770D03*
X1501203D03*
X1510453Y1060565D03*
X1508604Y1063770D03*
X1504904Y1076587D03*
Y1070178D03*
X1497504Y1076587D03*
X1497503Y1070178D03*
X1495654Y1073383D03*
X1499353Y1066974D03*
X1499354Y1079791D03*
X1510453Y1066974D03*
Y1079791D03*
X1499353Y1086200D03*
X1497503Y1089404D03*
X1495653Y1092608D03*
X1504904Y1089404D03*
Y1082995D03*
X1501203D03*
X1508604Y1082996D03*
X1510453Y1086200D03*
X1504903Y1095813D03*
X1503053Y1105426D03*
X1497503Y1102221D03*
X1495653Y1105426D03*
X1495654Y1099017D03*
X1508603Y1108630D03*
X1506754Y1111834D03*
X1499353D03*
X1503053Y1099017D03*
X1510453D03*
X1508602Y1102221D03*
X1497504Y1108630D03*
X1501204D03*
X1510453Y1111834D03*
X1499353Y1105426D03*
X1510453D03*
X1504904Y1108630D03*
X1495653Y1111834D03*
X1503053D03*
X1506753Y1124651D03*
Y1118243D03*
X1504904Y1121447D03*
X1499353Y1118243D03*
X1497503Y1115039D03*
X1495653Y1118243D03*
X1508603Y1115039D03*
X1504904Y1127856D03*
X1497503D03*
X1501204Y1115039D03*
X1504904D03*
X1506754Y1137469D03*
X1506753Y1131060D03*
X1503053D03*
X1499353D03*
X1495653D03*
X1504904Y1134264D03*
X1497503Y1140973D03*
X1510453Y1131060D03*
X1511871Y844671D03*
X1513722Y848176D03*
X1511871Y851380D03*
X1521121Y860993D03*
Y854584D03*
X1515570Y864197D03*
X1513721Y854584D03*
Y860993D03*
X1521121Y867401D03*
X1517421D03*
X1513721D03*
X1511871Y870606D03*
X1522971D03*
X1517421Y873810D03*
X1511871Y883423D03*
X1517421Y880219D03*
X1522971Y883423D03*
X1511871Y889832D03*
X1513721Y893036D03*
X1517421Y886627D03*
X1521121D03*
X1513721D03*
X1526671Y889832D03*
X1513721Y899445D03*
X1524821Y912262D03*
X1511871Y909057D03*
Y902649D03*
X1513721Y912262D03*
X1515571Y909057D03*
X1524821Y905853D03*
X1513721D03*
X1519271Y909057D03*
X1511871Y921875D03*
X1513721Y918670D03*
X1524820Y931488D03*
X1513720D03*
X1511871Y941100D03*
X1513721Y937896D03*
X1511871Y947509D03*
X1519271D03*
X1515571D03*
X1511871Y960326D03*
X1513721Y957122D03*
Y950713D03*
X1511871Y966735D03*
X1513721Y963530D03*
X1515571Y979552D03*
X1513721Y982756D03*
X1511871Y973143D03*
X1517421Y969939D03*
X1515571Y973143D03*
X1516004Y1006092D03*
X1516003Y999684D03*
X1512303D03*
Y1006093D03*
X1519705Y1006092D03*
X1525396Y1000648D03*
X1512303Y1012501D03*
Y1025318D03*
X1516003Y1018910D03*
X1517854Y1015705D03*
X1525254D03*
X1521554D03*
X1514154D03*
X1512303Y1018910D03*
Y1031727D03*
X1525254Y1034931D03*
X1521554D03*
X1516004Y1044544D03*
X1516003Y1038136D03*
X1517853Y1034931D03*
X1514153D03*
X1512303Y1038136D03*
X1517853Y1054157D03*
X1514153D03*
X1512303Y1057361D03*
X1521553Y1054157D03*
X1514153Y1060565D03*
X1512303Y1050952D03*
X1525564Y1064850D03*
X1523404Y1070178D03*
X1514153Y1066974D03*
X1517853Y1073383D03*
X1521553Y1066974D03*
X1516003Y1076587D03*
X1512303D03*
X1512304Y1070178D03*
X1514153Y1073383D03*
X1523404Y1082996D03*
X1512304D03*
X1514153Y1092608D03*
X1512303Y1089404D03*
X1521553Y1092608D03*
X1523403Y1095813D03*
X1519703D03*
X1512303D03*
X1521554Y1105426D03*
X1517853D03*
X1516003Y1108630D03*
Y1102221D03*
X1512303D03*
X1517853Y1111834D03*
X1521553D03*
X1514153Y1105426D03*
X1512303Y1108630D03*
X1514153Y1111834D03*
X1519703Y1108630D03*
X1521553Y1124651D03*
Y1118243D03*
X1519704Y1115039D03*
X1516004D03*
X1514153Y1124651D03*
X1512303Y1115039D03*
X1517854Y1131560D03*
X1512304Y1134264D03*
X1527571Y979057D03*
X1526843Y972608D03*
X1527103Y1031726D03*
X1665141Y1051247D03*
X1724541D03*
G54D44*
X333834Y1062790D03*
X329632Y1092168D03*
X335344Y1097289D03*
X549719Y962436D03*
X548146Y965640D03*
X543729Y984866D03*
X1309976Y1062790D03*
X1305774Y1092168D03*
X1311486Y1097289D03*
X1337102Y206675D03*
X1525861Y962436D03*
X1524288Y965640D03*
X1519871Y984866D03*
X1879155Y468898D03*
Y716798D03*
X1889155Y468898D03*
Y716798D03*
X1900275Y840758D03*
X1910275D03*
X1921395Y-19332D03*
X1931395D03*
X1942395Y593048D03*
X1952395D03*
X1963362Y-19190D03*
X1973362D03*
X1984482Y593020D03*
X1994482D03*
X2005452Y-19180D03*
X2015452D03*
X2026452Y593200D03*
X2047419Y-19038D03*
X2036452Y593200D03*
X2057419Y-19038D03*
X2068539Y593172D03*
X2078539D03*
G54D53*
X717313Y-27626D03*
Y-21471D03*
Y-17597D03*
X717298Y-15082D03*
X717313Y-11442D03*
X717298Y-25111D03*
X717313Y-7568D03*
X717298Y-5053D03*
X834273Y2374D03*
X834258Y4889D03*
X834273Y22432D03*
Y8529D03*
Y12403D03*
X834258Y14918D03*
X834273Y18558D03*
X834258Y24947D03*
X1026705Y-27695D03*
Y-38224D03*
X1023437Y-38210D03*
X1026690Y-35709D03*
X1023422Y-35695D03*
X1026705Y-32069D03*
Y-17666D03*
X1026690Y-15151D03*
X1026705Y-11511D03*
X1026690Y-25180D03*
X1026705Y-21540D03*
X1026690Y4907D03*
X1026705Y2392D03*
X1026690Y-5122D03*
X1026705Y-7637D03*
Y-1482D03*
Y22450D03*
Y18576D03*
Y8547D03*
X1026690Y14936D03*
X1026705Y12421D03*
X1026690Y24965D03*
X1336024Y-27695D03*
Y-32069D03*
X1332741Y-35695D03*
X1336009Y-35709D03*
X1332756Y-38210D03*
X1336024Y-38224D03*
Y-11511D03*
X1336009Y-15151D03*
X1336024Y-17666D03*
Y-21540D03*
X1336009Y-25180D03*
X1336024Y2392D03*
X1336009Y4907D03*
X1336024Y-1482D03*
Y-7637D03*
X1336009Y-5122D03*
X1336024Y18576D03*
Y22450D03*
Y12421D03*
X1336009Y14936D03*
X1336024Y8547D03*
X1336009Y24965D03*
G54D63*
X918780Y1684890D03*
Y1694890D03*
Y1714890D03*
X928780Y1684890D03*
X938780D03*
X928780Y1694890D03*
X938780D03*
X928780Y1704890D03*
X938780D03*
X928780Y1714890D03*
X938780D03*
G54D73*
X1879155Y354948D03*
Y458898D03*
Y478898D03*
Y582848D03*
Y602848D03*
Y706798D03*
Y726798D03*
Y830748D03*
X1900275Y-9342D03*
X1889155Y354948D03*
Y458898D03*
Y478898D03*
X1900275Y582858D03*
X1889155Y582848D03*
Y602848D03*
Y706798D03*
X1900275Y726808D03*
X1889155Y726798D03*
X1900275Y830758D03*
X1889155Y830748D03*
X1900275Y850758D03*
Y954708D03*
X1910275Y-9342D03*
Y582858D03*
Y726808D03*
Y830758D03*
Y850758D03*
Y954708D03*
X1921395Y-9332D03*
X1931395D03*
Y582868D03*
X1921395D03*
X1931395Y602868D03*
X1921395D03*
Y1195068D03*
X1931395D03*
X1942395Y-9152D03*
Y583048D03*
Y603048D03*
Y1195248D03*
X1963362Y-9190D03*
X1952395Y-9152D03*
X1963362Y583010D03*
X1952395Y583048D03*
X1963362Y603010D03*
X1952395Y603048D03*
X1963362Y1195210D03*
X1952395Y1195248D03*
X1973362Y-9190D03*
Y583010D03*
Y603010D03*
Y1195210D03*
X1994482Y-9180D03*
X1984482D03*
Y583020D03*
X1994482D03*
X1984482Y603020D03*
X1994482D03*
Y1195220D03*
X1984482D03*
X2005452Y-9180D03*
X2015452D03*
Y583020D03*
X2005452D03*
X2015452Y603020D03*
X2005452D03*
Y1195220D03*
X2015452D03*
X2026452Y-9000D03*
Y583200D03*
Y603200D03*
Y1195400D03*
X2047419Y-9038D03*
X2036452Y-9000D03*
X2047419Y583162D03*
X2036452Y583200D03*
X2047419Y603162D03*
X2036452Y603200D03*
X2047419Y1195362D03*
X2036452Y1195400D03*
X2057419Y-9038D03*
Y583162D03*
Y603162D03*
Y1195362D03*
X2068539Y603172D03*
X2078539D03*
Y1195372D03*
X2068539D03*
G54D74*
X1879155Y468898D03*
Y716798D03*
X1889155Y468898D03*
X1900275Y592858D03*
X1889155Y716798D03*
X1900275Y840758D03*
X1910275Y592858D03*
Y840758D03*
X1921395Y1205068D03*
X1931395D03*
X1942395Y593048D03*
X1952395D03*
X1963362Y1205210D03*
X1984482Y593020D03*
X1973362Y1205210D03*
X1994482Y593020D03*
X2005452Y1205220D03*
X2015452D03*
X2026452Y593200D03*
X2036452D03*
X2047419Y1205362D03*
X2057419D03*
G54D50*
X676508Y224606D03*
G54D23*
X36399Y960892D03*
Y957546D03*
Y967585D03*
Y1054593D03*
X52541Y964239D03*
Y1021129D03*
Y1024475D03*
Y1051247D03*
X66099Y780184D03*
Y773491D03*
Y786877D03*
Y803609D03*
Y796916D03*
Y790223D03*
Y816995D03*
Y810302D03*
Y833727D03*
Y823688D03*
Y827034D03*
Y847113D03*
Y840420D03*
Y853806D03*
Y860499D03*
Y863845D03*
Y883924D03*
Y877231D03*
Y870538D03*
Y890617D03*
Y897310D03*
Y900656D03*
Y914042D03*
Y907349D03*
Y927428D03*
Y920735D03*
Y934121D03*
Y944160D03*
Y937467D03*
Y960892D03*
Y950853D03*
Y957546D03*
Y980971D03*
Y974278D03*
Y967585D03*
Y994357D03*
Y987664D03*
Y1027822D03*
Y1021129D03*
Y1047900D03*
Y1041207D03*
Y1034515D03*
Y1054593D03*
Y1074672D03*
Y1067979D03*
Y1091404D03*
Y1081365D03*
Y1084711D03*
Y1098097D03*
Y1111483D03*
Y1104790D03*
Y1128215D03*
Y1118176D03*
Y1121522D03*
Y1141601D03*
Y1134908D03*
Y1148294D03*
Y1154987D03*
Y1158333D03*
Y1171719D03*
Y1165026D03*
Y1185105D03*
Y1178412D03*
Y1191798D03*
Y1208530D03*
Y1201837D03*
Y1195144D03*
Y1221916D03*
Y1215223D03*
Y1238648D03*
Y1228609D03*
Y1231955D03*
Y1245341D03*
X82241Y770144D03*
Y776837D03*
Y786877D03*
Y783530D03*
Y800263D03*
Y793570D03*
Y813648D03*
Y806955D03*
Y820341D03*
Y830381D03*
Y823688D03*
Y850459D03*
Y843766D03*
Y837074D03*
Y867192D03*
Y860499D03*
Y857152D03*
Y873885D03*
Y880577D03*
Y887270D03*
Y897310D03*
Y893963D03*
Y917389D03*
Y910696D03*
Y904003D03*
Y924081D03*
Y934121D03*
Y930774D03*
Y947507D03*
Y940814D03*
Y964239D03*
Y977625D03*
Y970932D03*
Y991011D03*
Y984318D03*
Y1021129D03*
Y1024475D03*
Y1031168D03*
Y1044554D03*
Y1037861D03*
Y1051247D03*
Y1071326D03*
Y1064633D03*
Y1078018D03*
Y1094751D03*
Y1088058D03*
Y1081365D03*
Y1108137D03*
Y1101444D03*
Y1124869D03*
Y1118176D03*
Y1114829D03*
Y1144948D03*
Y1138255D03*
Y1131562D03*
Y1161680D03*
Y1154987D03*
Y1151641D03*
Y1175066D03*
Y1168373D03*
Y1181759D03*
Y1191798D03*
Y1188452D03*
Y1205184D03*
Y1198491D03*
Y1218570D03*
Y1211877D03*
Y1225263D03*
Y1241995D03*
Y1235302D03*
Y1228609D03*
X95799Y960892D03*
Y957546D03*
Y967585D03*
Y1054593D03*
X125499Y780184D03*
Y773491D03*
Y786877D03*
Y803609D03*
Y796916D03*
Y790223D03*
Y816995D03*
Y810302D03*
Y833727D03*
Y823688D03*
Y827034D03*
Y847113D03*
Y840420D03*
Y853806D03*
Y860499D03*
Y863845D03*
Y883924D03*
Y877231D03*
Y870538D03*
Y890617D03*
Y897310D03*
Y900656D03*
Y914042D03*
Y907349D03*
Y927428D03*
Y920735D03*
Y934121D03*
Y944160D03*
Y937467D03*
Y960892D03*
Y950853D03*
X111941Y964239D03*
X125499Y957546D03*
Y980971D03*
Y974278D03*
Y967585D03*
Y994357D03*
Y987664D03*
X111941Y1021129D03*
Y1024475D03*
X125499Y1027822D03*
Y1021129D03*
Y1047900D03*
Y1041207D03*
Y1034515D03*
X111941Y1051247D03*
X125499Y1054593D03*
Y1074672D03*
Y1067979D03*
Y1091404D03*
Y1081365D03*
Y1084711D03*
Y1098097D03*
Y1111483D03*
Y1104790D03*
Y1128215D03*
Y1118176D03*
Y1121522D03*
Y1141601D03*
Y1134908D03*
Y1148294D03*
Y1154987D03*
Y1158333D03*
Y1171719D03*
Y1165026D03*
Y1185105D03*
Y1178412D03*
Y1191798D03*
Y1208530D03*
Y1201837D03*
Y1195144D03*
Y1221916D03*
Y1215223D03*
Y1238648D03*
Y1228609D03*
Y1231955D03*
Y1245341D03*
X141641Y770144D03*
Y776837D03*
Y786877D03*
Y783530D03*
Y800263D03*
Y793570D03*
Y813648D03*
Y806955D03*
Y820341D03*
Y830381D03*
Y823688D03*
Y850459D03*
Y843766D03*
Y837074D03*
Y867192D03*
Y860499D03*
Y857152D03*
Y873885D03*
Y880577D03*
Y887270D03*
Y897310D03*
Y893963D03*
Y917389D03*
Y910696D03*
Y904003D03*
Y924081D03*
Y934121D03*
Y930774D03*
Y947507D03*
Y940814D03*
Y964239D03*
Y977625D03*
Y970932D03*
Y991011D03*
Y984318D03*
Y1021129D03*
Y1024475D03*
Y1031168D03*
Y1044554D03*
Y1037861D03*
Y1051247D03*
Y1071326D03*
Y1064633D03*
Y1078018D03*
Y1094751D03*
Y1088058D03*
Y1081365D03*
Y1108137D03*
Y1101444D03*
Y1124869D03*
Y1118176D03*
Y1114829D03*
Y1144948D03*
Y1138255D03*
Y1131562D03*
Y1161680D03*
Y1154987D03*
Y1151641D03*
Y1175066D03*
Y1168373D03*
Y1181759D03*
Y1191798D03*
Y1188452D03*
Y1205184D03*
Y1198491D03*
Y1218570D03*
Y1211877D03*
Y1225263D03*
Y1241995D03*
Y1235302D03*
Y1228609D03*
X155199Y960892D03*
Y957546D03*
Y967585D03*
Y1054593D03*
X171341Y964239D03*
Y1021129D03*
Y1024475D03*
Y1051247D03*
X184899Y780184D03*
Y773491D03*
Y786877D03*
Y803609D03*
Y796916D03*
Y790223D03*
Y816995D03*
Y810302D03*
Y833727D03*
Y823688D03*
Y827034D03*
Y847113D03*
Y840420D03*
Y853806D03*
Y860499D03*
Y863845D03*
Y883924D03*
Y877231D03*
Y870538D03*
Y890617D03*
Y897310D03*
Y900656D03*
Y914042D03*
Y907349D03*
Y927428D03*
Y920735D03*
Y934121D03*
Y944160D03*
Y937467D03*
Y960892D03*
Y950853D03*
Y957546D03*
Y980971D03*
Y974278D03*
Y967585D03*
Y994357D03*
Y987664D03*
Y1027822D03*
Y1021129D03*
Y1047900D03*
Y1041207D03*
Y1034515D03*
Y1054593D03*
Y1074672D03*
Y1067979D03*
Y1091404D03*
Y1081365D03*
Y1084711D03*
Y1098097D03*
Y1111483D03*
Y1104790D03*
Y1128215D03*
Y1118176D03*
Y1121522D03*
Y1141601D03*
Y1134908D03*
Y1148294D03*
Y1154987D03*
Y1158333D03*
Y1171719D03*
Y1165026D03*
Y1185105D03*
Y1178412D03*
Y1191798D03*
Y1208530D03*
Y1201837D03*
Y1195144D03*
Y1221916D03*
Y1215223D03*
Y1238648D03*
Y1228609D03*
Y1231955D03*
Y1245341D03*
X201041Y770144D03*
Y776837D03*
Y786877D03*
Y783530D03*
Y800263D03*
Y793570D03*
Y813648D03*
Y806955D03*
Y820341D03*
Y830381D03*
Y823688D03*
Y850459D03*
Y843766D03*
Y837074D03*
Y867192D03*
Y860499D03*
Y857152D03*
Y873885D03*
Y880577D03*
Y887270D03*
Y897310D03*
Y893963D03*
Y917389D03*
Y910696D03*
Y904003D03*
Y924081D03*
Y934121D03*
Y930774D03*
Y947507D03*
Y940814D03*
Y964239D03*
Y977625D03*
Y970932D03*
Y991011D03*
Y984318D03*
X201141Y1021129D03*
Y1024475D03*
Y1031168D03*
Y1044554D03*
Y1037861D03*
Y1051247D03*
Y1071326D03*
Y1064633D03*
Y1078018D03*
Y1094752D03*
Y1088059D03*
Y1081366D03*
Y1108137D03*
Y1101444D03*
X201041Y1124869D03*
X201141Y1118177D03*
Y1114830D03*
Y1144948D03*
Y1138255D03*
X201041Y1131562D03*
X201141Y1161680D03*
Y1154988D03*
Y1151641D03*
Y1175066D03*
Y1168373D03*
Y1181759D03*
Y1191799D03*
Y1188452D03*
Y1205184D03*
Y1198491D03*
Y1218570D03*
Y1211877D03*
Y1225263D03*
Y1241995D03*
Y1235302D03*
Y1228609D03*
X214599Y960892D03*
Y957546D03*
X244299Y883924D03*
Y890617D03*
Y897310D03*
Y900656D03*
Y914042D03*
Y907349D03*
Y960892D03*
Y957546D03*
Y1185105D03*
Y1178412D03*
Y1191798D03*
Y1208530D03*
Y1201837D03*
Y1195144D03*
X260441Y880577D03*
Y887270D03*
Y897310D03*
Y893963D03*
Y910696D03*
Y904003D03*
Y1175066D03*
Y1181759D03*
Y1191798D03*
Y1188452D03*
Y1205184D03*
Y1198491D03*
X337779Y880219D03*
X335928Y883423D03*
X337779Y893036D03*
X335928Y889832D03*
X334079Y886627D03*
X337779D03*
X336361Y1121447D03*
X350727Y851380D03*
X354427Y844971D03*
X348878Y848176D03*
X352578D03*
X350729Y857789D03*
X352578Y860993D03*
X354429Y857789D03*
X341479Y880219D03*
X343329Y883423D03*
X350729Y870606D03*
X354429D03*
X352578Y873810D03*
X354429Y883423D03*
X348878Y899445D03*
Y893036D03*
X350729Y889832D03*
X354429D03*
X341478Y893036D03*
X343328Y889832D03*
X347029Y896240D03*
X354429D03*
X341479Y886627D03*
X350729Y896240D03*
X345179Y886627D03*
X348878Y912262D03*
X350729Y909057D03*
X354429D03*
X350729Y902649D03*
X354429D03*
X347029Y915466D03*
X354429D03*
X350729D03*
X348879Y931488D03*
X350729Y928283D03*
X354429D03*
Y921875D03*
X350729D03*
X348878Y918670D03*
X350729Y941100D03*
X348878Y937896D03*
X354429Y941100D03*
X347029Y934691D03*
X354429D03*
X350729D03*
Y947509D03*
X354429D03*
X348878Y950713D03*
X350729Y960326D03*
X348878Y957122D03*
X354429Y960326D03*
X350729Y966735D03*
X354429D03*
X350729Y953917D03*
X354429D03*
X347030D03*
X350729Y979552D03*
X354429D03*
X348878Y976347D03*
X347029Y973143D03*
X348878Y969939D03*
X347461Y1006093D03*
X349311Y1002888D03*
X351161Y999684D03*
X354861D03*
X351161Y1012501D03*
X349311Y1009297D03*
X354861Y1012501D03*
X351162Y1031727D03*
X349311Y1028523D03*
X354861Y1031727D03*
X349311Y1022114D03*
X351161Y1018910D03*
X354861D03*
X347461Y1025318D03*
X354862D03*
X351162D03*
X349311Y1047749D03*
Y1041340D03*
X351161Y1038136D03*
X354861D03*
X347461Y1044544D03*
X354861D03*
X351161D03*
X349311Y1060565D03*
X351161Y1057361D03*
X354861D03*
X347461Y1063770D03*
X351161D03*
X354861D03*
X351161Y1050952D03*
X354861D03*
Y1070178D03*
X351162D03*
X349311Y1066974D03*
Y1079791D03*
X351161Y1076587D03*
X354861D03*
X351161Y1089404D03*
X349311Y1086200D03*
X354861Y1089404D03*
X347461Y1082995D03*
X354861D03*
X351161D03*
X341911Y1105426D03*
X343762Y1108630D03*
X345611Y1111834D03*
X351161Y1102221D03*
X349312Y1111834D03*
X353011Y1105426D03*
X345611D03*
X341912Y1111834D03*
X354861Y1102221D03*
X353012Y1111834D03*
X351162Y1108630D03*
X353011Y1124651D03*
X354861Y1127856D03*
X347461Y1115039D03*
X341912Y1118243D03*
X340061Y1127856D03*
X343761D03*
X347461Y1121447D03*
X340061D03*
X343761D03*
X347461Y1127856D03*
X345611Y1124651D03*
X349312Y1137469D03*
X351161Y1134264D03*
X341911Y1131060D03*
X356279Y841467D03*
X361827Y844971D03*
X363679Y841467D03*
X369227Y844971D03*
X371079Y841467D03*
X358127Y844971D03*
X359978Y848176D03*
X365527Y844971D03*
X367378Y848176D03*
X371078Y867401D03*
X356278D03*
X363678D03*
X356278Y854584D03*
X358129Y857789D03*
X363678Y854584D03*
X365529Y857789D03*
X371078Y854584D03*
X359978Y860993D03*
X361829Y857789D03*
X367378Y860993D03*
X369229Y857789D03*
X358129Y870606D03*
X361829D03*
X365529D03*
X359978Y873810D03*
X367378D03*
X369229Y870606D03*
X356278Y880219D03*
X358129Y883423D03*
X363678Y880219D03*
X365529Y883423D03*
X371078Y880219D03*
X361829Y883423D03*
X369229D03*
X356278Y899445D03*
Y893036D03*
X358129Y896240D03*
X363678Y899445D03*
X367378D03*
X371078Y893036D03*
X359978Y886627D03*
X367378D03*
X356278Y912262D03*
X358129Y915466D03*
X363678Y912262D03*
X361829Y909057D03*
X367378Y912262D03*
X369229Y909057D03*
X361829Y902649D03*
X369229D03*
X359978Y905853D03*
X367378D03*
X363678D03*
X371078D03*
X356278Y931488D03*
X363678D03*
X356278Y918670D03*
X361829Y928283D03*
X367378Y931488D03*
X369229Y928283D03*
X361829Y921875D03*
X363678Y918670D03*
X369229Y921875D03*
X367378Y918670D03*
X359978Y925079D03*
X367378D03*
X363678D03*
X371078D03*
X356278Y937896D03*
X358129Y934691D03*
X361829Y941100D03*
X363678Y937896D03*
X369229Y941100D03*
X367378Y937896D03*
X361829Y947509D03*
X369229D03*
X367378Y944304D03*
X359978D03*
X371078D03*
X363678D03*
X356278Y950713D03*
Y957122D03*
X358129Y953917D03*
X361829Y966735D03*
X369229D03*
X359978Y963530D03*
X363678Y950713D03*
X367378D03*
X361829Y960326D03*
X363678Y957122D03*
X369229Y960326D03*
X367378Y957122D03*
X371078Y963530D03*
X359978Y982756D03*
X367378D03*
X363678D03*
X371078D03*
X369229Y979552D03*
X367378Y976347D03*
X361829Y979552D03*
X363678Y976347D03*
X356278D03*
Y969939D03*
X358129Y973143D03*
X363678Y969939D03*
X367378D03*
X358562Y1006093D03*
X356711Y1002888D03*
Y1009297D03*
X362262Y1012501D03*
X369662D03*
X364111Y1009297D03*
X367811D03*
X364111Y1002888D03*
X362262Y999684D03*
X371511Y1002888D03*
X369662Y999684D03*
X356711Y1028523D03*
Y1022114D03*
X362262Y1031727D03*
X364111Y1028523D03*
X369662Y1031727D03*
X367811Y1028523D03*
X358562Y1025318D03*
X360411Y1015705D03*
X371511D03*
X364111Y1022114D03*
X362262Y1018910D03*
X367811Y1022114D03*
X369662Y1018910D03*
X356711Y1047749D03*
Y1041340D03*
X364111D03*
X362262Y1038136D03*
X367811Y1041340D03*
X369662Y1038136D03*
X360411Y1034931D03*
X371511D03*
X364111D03*
X358562Y1044544D03*
X367811Y1034931D03*
X364111Y1047749D03*
X367811D03*
X356711Y1060565D03*
X358562Y1063770D03*
X364111Y1060565D03*
X362262Y1057361D03*
X367811Y1060565D03*
X369662Y1057361D03*
X362262Y1050952D03*
X369662D03*
X360411Y1054157D03*
X371511D03*
X364111D03*
X367811D03*
X356711Y1066974D03*
X367811Y1079791D03*
X369662Y1076587D03*
X362262Y1070178D03*
X364111Y1066974D03*
X369662Y1070178D03*
X367811Y1066974D03*
X356711Y1079791D03*
X364111D03*
X362262Y1076587D03*
X360411Y1073383D03*
X371511D03*
X364111D03*
X367811D03*
X356711Y1086200D03*
X358562Y1082995D03*
X362262Y1095813D03*
X369662D03*
X362262Y1089404D03*
X364111Y1086200D03*
X369662Y1089404D03*
X367811Y1086200D03*
X360411Y1092608D03*
X367811D03*
X364111D03*
X371511D03*
X364111Y1099017D03*
X367811D03*
X358561Y1108630D03*
X360412Y1111834D03*
X364112Y1105426D03*
X369661Y1108630D03*
X362261D03*
X365961D03*
X367812Y1111834D03*
X358561Y1121447D03*
X360412Y1124651D03*
X364111D03*
X367811D03*
X371511D03*
X356712D03*
X362262Y1127856D03*
X365962Y1121447D03*
X369662Y1127856D03*
X365961Y1115039D03*
X358561D03*
X369661D03*
X358561Y1134264D03*
X362261Y1140973D03*
X365962Y1134264D03*
X369661Y1140973D03*
X356712Y1137469D03*
X360412D03*
X364112D03*
X367812D03*
X371512D03*
X387727Y844971D03*
X376627D03*
X380327D03*
X384027D03*
X385879Y841467D03*
X372927Y844971D03*
X374778Y848176D03*
X378479Y841467D03*
X382178Y848176D03*
X378478Y867401D03*
X385878D03*
X387729Y857789D03*
X372929D03*
X378478Y854584D03*
X380329Y857789D03*
X384029D03*
X374778Y860993D03*
X376629Y857789D03*
X382178Y860993D03*
X385878Y854584D03*
X387729Y870606D03*
X372929D03*
X380329D03*
X374778Y873810D03*
X376629Y870606D03*
X382178Y873810D03*
X384029Y870606D03*
X372929Y883423D03*
X378478Y880219D03*
X380329Y883423D03*
X385878Y880219D03*
X387729Y883423D03*
X376629D03*
X384029D03*
X374778Y899445D03*
X382178D03*
Y893036D03*
X374778D03*
X385878D03*
X372929Y896240D03*
X380329D03*
X376629D03*
X384029D03*
X374778Y886627D03*
X382178D03*
X376629Y902649D03*
X380329D03*
X374778Y912262D03*
X376629Y909057D03*
X382178Y912262D03*
X380329Y909057D03*
X387729D03*
Y902649D03*
X372929Y915466D03*
X385878Y905853D03*
X380329Y915466D03*
X376629D03*
X384029D03*
X374778Y931488D03*
X376629Y928283D03*
X382178Y931488D03*
X380329Y928283D03*
X387729Y921875D03*
X376629D03*
X374778Y918670D03*
X380329Y921875D03*
X382178Y918670D03*
X387729Y928283D03*
X385878Y925079D03*
X380329Y941100D03*
X382178Y937896D03*
X376629Y947509D03*
X380329D03*
X376629Y941100D03*
X374778Y937896D03*
X372929Y934691D03*
X380329D03*
X376629D03*
X384029D03*
X387729Y947509D03*
Y941100D03*
X385878Y944304D03*
X376629Y960326D03*
X374778Y957122D03*
X380329Y960326D03*
X382178Y957122D03*
X374778Y950713D03*
X382178D03*
X372929Y953917D03*
X380329D03*
X376629D03*
X384029D03*
X387729Y960326D03*
Y966735D03*
X380329D03*
X376629D03*
X385878Y963530D03*
Y982756D03*
X387729Y979552D03*
X376629D03*
X380329D03*
X374778Y976347D03*
X382178D03*
X372929Y973143D03*
X374778Y969939D03*
X382178D03*
X384029Y973143D03*
X373362Y1006093D03*
X380762D03*
X377062D03*
X384462D03*
X375211Y1002888D03*
X377062Y999684D03*
X382611Y1002888D03*
X380762Y999684D03*
X377062Y1012501D03*
X375211Y1009297D03*
X380762Y1012501D03*
X382611Y1009297D03*
X377062Y1031727D03*
X375211Y1028523D03*
X380762Y1031727D03*
X382611Y1028523D03*
X375211Y1022114D03*
X377062Y1018910D03*
X382611Y1022114D03*
X380762Y1018910D03*
X377062Y1025318D03*
X384462D03*
X373360D03*
X380760D03*
X386311Y1015705D03*
X375211Y1047749D03*
X382611D03*
X375211Y1041340D03*
X377062Y1038136D03*
X382611Y1041340D03*
X380762Y1038136D03*
X373362Y1044544D03*
X380762D03*
X377062D03*
X384462D03*
X386311Y1034931D03*
X375211Y1060565D03*
X377062Y1057361D03*
X382611Y1060565D03*
X380762Y1057361D03*
X377062Y1050952D03*
X380762D03*
X373362Y1063770D03*
X384462D03*
X377062D03*
X380762D03*
X386311Y1054157D03*
X380762Y1070178D03*
X382611Y1066974D03*
X377062Y1070178D03*
X375211Y1066974D03*
Y1079791D03*
X377062Y1076587D03*
X382611Y1079791D03*
X380762Y1076587D03*
X386311Y1073383D03*
X377062Y1089404D03*
X375211Y1086200D03*
X380762Y1089404D03*
X382611Y1086200D03*
X373362Y1082995D03*
X386311Y1092608D03*
X384462Y1082995D03*
X377062D03*
X380762D03*
X386311Y1105426D03*
X382611Y1111834D03*
X375211Y1105426D03*
X377062Y1108630D03*
X380762Y1102221D03*
X378911Y1111834D03*
X384462Y1108630D03*
X386311Y1111834D03*
X378912Y1105426D03*
X375211Y1111834D03*
X382611Y1105426D03*
X375211Y1124651D03*
X378911D03*
X382611D03*
X386311D03*
X373362Y1121447D03*
X377062Y1127856D03*
X380762Y1121447D03*
X384462Y1127856D03*
X380762Y1115039D03*
X373362Y1134264D03*
X377061Y1140973D03*
X380762Y1134264D03*
X384461Y1140973D03*
X375212Y1137469D03*
X378912D03*
X382612D03*
X386312D03*
X391427Y844971D03*
X395127D03*
X398827D03*
X400679Y841467D03*
X389578Y848176D03*
X393279Y841467D03*
X396978Y848176D03*
X402527Y844971D03*
X400678Y867401D03*
X393278D03*
Y854584D03*
X395129Y857789D03*
X400678Y854584D03*
X402529Y857789D03*
X389578Y860993D03*
X391429Y857789D03*
X396978Y860993D03*
X398829Y857789D03*
X391429Y870606D03*
X395129D03*
X402529D03*
X389578Y873810D03*
X396978D03*
X398829Y870606D03*
X393278Y880219D03*
X395129Y883423D03*
X400678Y880219D03*
X402529Y883423D03*
X391429D03*
X398829D03*
X389578Y899445D03*
X393278D03*
X396978Y886627D03*
X389578D03*
Y912262D03*
X393278D03*
X395129Y909057D03*
Y902649D03*
X393278Y905853D03*
X389578D03*
X396978D03*
X393278Y931488D03*
X395129Y928283D03*
X389578Y918670D03*
X395129Y921875D03*
X393278Y918670D03*
X389578Y931488D03*
X393278Y925079D03*
X389578D03*
X396978D03*
X395129Y947509D03*
X389578Y937896D03*
X395129Y941100D03*
X393278Y937896D03*
Y944304D03*
X389578D03*
X396978D03*
X389578Y957122D03*
X395129Y960326D03*
X393278Y957122D03*
X395129Y966735D03*
X389578Y950713D03*
X393278D03*
X396978Y963530D03*
X393278D03*
X389578D03*
X398829Y973143D03*
X400678Y976347D03*
X402529Y979552D03*
Y973143D03*
X393278Y982756D03*
X389578D03*
X396978D03*
X393278Y976347D03*
X395129Y979552D03*
X389579Y976347D03*
X389578Y969939D03*
X393278D03*
X390011Y1002888D03*
X388162Y999684D03*
X393711Y1002888D03*
X395562Y999684D03*
X388162Y1012501D03*
X395562D03*
X390011Y1009297D03*
X393711D03*
X397411Y1015705D03*
X388162Y1031727D03*
X390011Y1028523D03*
X395562Y1031727D03*
X393711Y1028523D03*
X390011Y1022114D03*
X388162Y1018910D03*
X393711Y1022114D03*
X395562Y1018910D03*
X390011Y1041340D03*
X388162Y1038136D03*
X393711Y1041340D03*
X395562Y1038136D03*
X390011Y1047749D03*
X393711D03*
Y1034931D03*
X390011D03*
X397411D03*
X390011Y1060565D03*
X388162Y1057361D03*
X393711Y1060565D03*
X395562Y1057361D03*
X388162Y1050952D03*
X395562D03*
X393711Y1054157D03*
X390011D03*
X397411D03*
X390011Y1079791D03*
X388162Y1076587D03*
X393711Y1079791D03*
X395562Y1076587D03*
X388162Y1070178D03*
X390011Y1066974D03*
X395562Y1070178D03*
X393711Y1066974D03*
Y1073383D03*
X390011D03*
X397411D03*
X395562Y1095813D03*
X388162Y1089404D03*
X390011Y1086200D03*
X395562Y1089404D03*
X393711Y1086200D03*
X388162Y1095813D03*
X393711Y1092608D03*
X390011D03*
X397411D03*
X402962Y1082995D03*
X402961Y1089404D03*
X393711Y1099017D03*
X390011D03*
X401111D03*
X391862Y1108630D03*
X393711Y1111834D03*
X397411Y1105426D03*
X402962Y1108630D03*
Y1102221D03*
X395562Y1108630D03*
X399262D03*
X401111Y1111834D03*
X390011Y1124651D03*
X395562Y1121447D03*
X397411Y1124651D03*
X401111D03*
X391862Y1127856D03*
X393711Y1124651D03*
X399262Y1127856D03*
X402962Y1121447D03*
X388162D03*
X399262Y1115039D03*
X391862D03*
X402962D03*
X391861Y1140973D03*
X395562Y1134264D03*
X399261Y1140973D03*
X402962Y1134264D03*
X388162D03*
X390012Y1137469D03*
X393712D03*
X397412D03*
X401112D03*
X406227Y844971D03*
X409927D03*
X413627D03*
X417327D03*
X404378Y848176D03*
X408079Y841467D03*
X411778Y848176D03*
X415479Y841467D03*
X419178Y848176D03*
X408078Y867401D03*
X415478D03*
X408078Y854584D03*
X409929Y857789D03*
X415478Y854584D03*
X417329Y857789D03*
X404378Y860993D03*
X406229Y857789D03*
X411778Y860993D03*
X413629Y857789D03*
X419178Y860993D03*
X404378Y873810D03*
X406229Y870606D03*
X408078Y880219D03*
X409929Y883423D03*
X406229D03*
X419178Y873810D03*
X417329Y870606D03*
X411778Y873810D03*
X413629Y870606D03*
X417329Y883423D03*
X415478Y880219D03*
X413629Y883423D03*
X404378Y886627D03*
X411778D03*
X419178D03*
X408511Y1079791D03*
X406662Y1089404D03*
X410362D03*
X404811Y1086200D03*
X419611D03*
X414062Y1082995D03*
X410362D03*
X406662D03*
X408511Y1092608D03*
X414062Y1089404D03*
X419611Y1092608D03*
X412211Y1086200D03*
X404811Y1099017D03*
X408511Y1105426D03*
X412211Y1111834D03*
X415911D03*
X414062Y1102221D03*
X417762Y1108630D03*
X419611Y1105426D03*
X408511Y1099017D03*
X410362Y1108630D03*
X408511Y1111834D03*
X412211Y1105426D03*
X419611Y1111834D03*
X415911Y1105426D03*
X404811Y1124651D03*
X408511D03*
X406662Y1127856D03*
X410362Y1121447D03*
X414062Y1115039D03*
X406661Y1140973D03*
X410362Y1134264D03*
X404812Y1137469D03*
X408512D03*
X421027Y844971D03*
X424727D03*
X428427D03*
X433978Y848176D03*
X435829Y844671D03*
X422879Y841467D03*
X426578Y848176D03*
X430278D03*
Y867401D03*
X422878D03*
Y854584D03*
X424729Y857789D03*
X430278Y854584D03*
X433979Y860993D03*
X421029Y857789D03*
X426578Y860993D03*
X428429Y857789D03*
X432129D03*
X435829D03*
X432129Y870606D03*
X426578Y873810D03*
X424729Y870606D03*
X433979Y873810D03*
X428429Y870606D03*
X421029D03*
X435829D03*
X432129Y883423D03*
X430278Y880219D03*
X424729Y883423D03*
X422878Y880219D03*
X428429Y883423D03*
X421029D03*
X435829D03*
X433978Y886627D03*
X426578D03*
X428861Y1076587D03*
X430711Y1079791D03*
X421462Y1089404D03*
X423311Y1092608D03*
X427011D03*
X430710Y1086200D03*
X425162Y1082995D03*
Y1095813D03*
X430711Y1092608D03*
X423311Y1086200D03*
X428861Y1089404D03*
X427012Y1086200D03*
X450628Y844971D03*
X446927Y844671D03*
X452479Y841467D03*
X448778Y848176D03*
X443227Y844671D03*
X437678Y848176D03*
X452478Y867401D03*
X445078D03*
X437678D03*
X437679Y854584D03*
X452478D03*
X450629Y857789D03*
X445078Y854584D03*
X443229Y857789D03*
X448779Y860993D03*
X446929Y857789D03*
X441378Y860993D03*
X448779Y873810D03*
X446929Y870606D03*
X441378Y873810D03*
X439529Y870606D03*
X450629D03*
X443229D03*
X452479Y880219D03*
X446929Y883423D03*
X445078Y880219D03*
X439529Y883423D03*
X437678Y880219D03*
X450629Y883423D03*
X443229D03*
X448778Y886627D03*
X441378D03*
X467279Y841467D03*
X463578Y848176D03*
X459879Y841467D03*
X458027Y844971D03*
X454327D03*
X469127D03*
X465427D03*
X461727D03*
X456178Y848176D03*
X467278Y867401D03*
X459878D03*
X467278Y854584D03*
X465429Y857789D03*
X459878Y854584D03*
X458029Y857789D03*
X469129D03*
X463578Y860993D03*
X461729Y857789D03*
X456178Y860993D03*
X454329Y857789D03*
X469129Y870606D03*
X463578Y873810D03*
X461729Y870606D03*
X456178Y873810D03*
X454329Y870606D03*
X465429D03*
X458029D03*
X469129Y883423D03*
X467278Y880219D03*
X461729Y883423D03*
X459878Y880219D03*
X454329Y883423D03*
X465429D03*
X458029D03*
X463578Y886627D03*
X456178D03*
X483927Y844971D03*
X480227D03*
X476527D03*
X470978Y848176D03*
X482079Y841467D03*
X478378Y848176D03*
X474679Y841467D03*
X472827Y844971D03*
X474678Y867401D03*
X482078D03*
Y854584D03*
X480229Y857789D03*
X474678Y854584D03*
X472829Y857789D03*
X483929D03*
X478378Y860993D03*
X476529Y857789D03*
X470978Y860993D03*
X480229Y870606D03*
X476529D03*
X478378Y873810D03*
X483929Y870606D03*
X474678Y880219D03*
X476529Y883423D03*
X482078Y880219D03*
X483929Y883423D03*
X472829D03*
X480229D03*
X482078Y893036D03*
X483929Y896240D03*
X470978Y886627D03*
X478378D03*
X483929Y915466D03*
Y934691D03*
Y953917D03*
Y973143D03*
X484362Y1006093D03*
Y1025318D03*
Y1044544D03*
Y1063770D03*
Y1082995D03*
Y1121447D03*
X480662Y1127856D03*
X476962Y1121447D03*
X473262Y1127856D03*
X469562Y1121447D03*
X482511Y1124651D03*
X478811D03*
X475111D03*
X471411D03*
X484362Y1134264D03*
X482512Y1137469D03*
X476962Y1134264D03*
X475112Y1137469D03*
X480661Y1140973D03*
X478812Y1137469D03*
X473261Y1140973D03*
X493178Y848176D03*
X489478Y841467D03*
X487627Y844971D03*
X500578Y848176D03*
X496878Y841467D03*
X495027Y844971D03*
X491327D03*
X485778Y848176D03*
X498727Y844971D03*
X489478Y867401D03*
X496878D03*
X489478Y854584D03*
X487629Y857789D03*
X500578Y860993D03*
X498729Y857789D03*
X495029D03*
X491329D03*
X485778Y860993D03*
X496878Y854584D03*
X493178Y860993D03*
X487629Y870606D03*
X495029D03*
X485778Y873810D03*
X491329Y870606D03*
X493178Y873810D03*
X498729Y870606D03*
X500578Y873810D03*
X489478Y880219D03*
X491329Y883423D03*
X496878Y880219D03*
X498729Y883423D03*
X487629D03*
X495029D03*
X500578Y899445D03*
X485778D03*
X493178D03*
Y893036D03*
X496878D03*
X485778D03*
X491329Y896240D03*
X487629D03*
X495029D03*
X485778Y886627D03*
X493178D03*
X500578D03*
X485778Y912262D03*
X487629Y909057D03*
X493178Y912262D03*
X491329Y909057D03*
X500578Y912262D03*
X498729Y909057D03*
Y902649D03*
X487629D03*
X491329D03*
X487629Y915466D03*
X500578Y905853D03*
X495029Y915466D03*
X496878Y905853D03*
X491329Y915466D03*
X500578Y931488D03*
X498729Y921875D03*
X500578Y918670D03*
X498729Y928283D03*
X496878Y925079D03*
X500578D03*
X491329Y921875D03*
X493178Y918670D03*
X485778Y931488D03*
X491329Y928283D03*
X493178Y931488D03*
X487629Y928283D03*
Y921875D03*
X485778Y918670D03*
X498729Y947509D03*
Y941100D03*
X500578Y937896D03*
X496878Y944304D03*
X500578D03*
X487629Y947509D03*
X491329D03*
X487629Y941100D03*
X485778Y937896D03*
X491329Y941100D03*
X493178Y937896D03*
X487629Y934691D03*
X495029D03*
X491329D03*
X500578Y950713D03*
X487629Y966735D03*
X491329D03*
X498729D03*
X496878Y963530D03*
X485778Y950713D03*
X493178D03*
X491329Y960326D03*
X493178Y957122D03*
X487629Y960326D03*
X485778Y957122D03*
X500578D03*
X498729Y960326D03*
X495029Y953917D03*
X487629D03*
X491329D03*
X487629Y979552D03*
X485778Y976347D03*
X491329Y979552D03*
X493178Y976347D03*
X500578Y982756D03*
X496878D03*
X498729Y979552D03*
X500578Y976347D03*
X495029Y973143D03*
X487629D03*
X491329D03*
X485778Y969939D03*
X493178D03*
X500578D03*
X501011Y1002888D03*
X499162Y999684D03*
Y1012501D03*
X501011Y1009297D03*
X495462Y1006093D03*
X486211Y1002888D03*
X493611D03*
X488062Y999684D03*
X491762D03*
X491761Y1012501D03*
X493611Y1009297D03*
X488062Y1012501D03*
X486211Y1009297D03*
X497311Y1015705D03*
X499162Y1031727D03*
X501011Y1028523D03*
Y1022114D03*
X499162Y1018910D03*
X488062Y1031727D03*
X486211Y1028523D03*
X491762Y1031727D03*
X493611Y1028523D03*
X486211Y1022114D03*
X488062Y1018910D03*
X493611Y1022114D03*
X491762Y1018910D03*
X488062Y1025318D03*
X495462D03*
X491762D03*
X501011Y1041340D03*
X499162Y1038136D03*
X501011Y1047749D03*
Y1034931D03*
X497311D03*
X486211Y1047749D03*
X493611D03*
X486211Y1041340D03*
X488062Y1038136D03*
X493611Y1041340D03*
X491762Y1038136D03*
X488062Y1044544D03*
X495462D03*
X491762D03*
X501011Y1060565D03*
X499162Y1057361D03*
Y1050952D03*
X501011Y1054157D03*
X497311D03*
X486211Y1060565D03*
X488062Y1057361D03*
X493611Y1060565D03*
X491762Y1057361D03*
X488062Y1050952D03*
X491762D03*
X488062Y1063770D03*
X495462D03*
X491762D03*
X499162Y1070178D03*
X501011Y1066974D03*
Y1079791D03*
X499162Y1076587D03*
X497311Y1073383D03*
X501011D03*
X486211Y1079791D03*
X488062Y1076587D03*
X493611Y1079791D03*
X491762Y1076587D03*
X488062Y1070178D03*
X486211Y1066974D03*
X491762Y1070178D03*
X493611Y1066974D03*
X491762Y1089404D03*
X493611Y1086200D03*
X499162Y1089404D03*
X501011Y1086200D03*
X488062Y1089404D03*
X486211Y1086200D03*
X497311Y1092608D03*
X495462Y1082995D03*
X501011Y1092608D03*
X488062Y1082995D03*
X491762D03*
X488062Y1127856D03*
X499162Y1121447D03*
X495462Y1127856D03*
X491762Y1121447D03*
X489911Y1124651D03*
X486211D03*
X501011D03*
X497311D03*
X493611D03*
X493612Y1137469D03*
X488061Y1140973D03*
X501012Y1137469D03*
X495461Y1140973D03*
X491762Y1134264D03*
X489912Y1137469D03*
X486212D03*
X499162Y1134264D03*
X497312Y1137469D03*
X517227Y844971D03*
X511679Y841467D03*
X509827Y844971D03*
X504279Y841467D03*
X515378Y848176D03*
X513527Y844971D03*
X507978Y848176D03*
X506127Y844971D03*
X502427D03*
X511678Y867401D03*
X504278D03*
X517229Y857789D03*
X513529D03*
X509829D03*
X506129D03*
X515378Y860993D03*
X511678Y854584D03*
X507978Y860993D03*
X504278Y854584D03*
X502429Y857789D03*
X517229Y870606D03*
X502429D03*
X509829D03*
X513529D03*
X515378Y873810D03*
X506129Y870606D03*
X507978Y873810D03*
X511678Y880219D03*
X513529Y883423D03*
X504278Y880219D03*
X506129Y883423D03*
X509829D03*
X517229D03*
X502429D03*
X511678Y899445D03*
Y893036D03*
X507978D03*
X509829Y896240D03*
X517229D03*
X513529D03*
X504278Y899445D03*
X515378Y886627D03*
X507978D03*
X513529Y902649D03*
X517229D03*
X511678Y912262D03*
X513529Y909057D03*
X517229D03*
X513529Y915466D03*
X509829D03*
X517229D03*
X504278Y912262D03*
X506129Y909057D03*
Y902649D03*
X507978Y905853D03*
X504278D03*
X511678Y931488D03*
X513529Y928283D03*
X517229D03*
X506129D03*
Y921875D03*
X504278Y918670D03*
X513529Y921875D03*
X511678Y918670D03*
X517229Y921875D03*
X504278Y931488D03*
Y925079D03*
X507978D03*
X513529Y941100D03*
X511678Y937896D03*
X517229Y941100D03*
X513529Y934691D03*
X509829D03*
X517229D03*
X513529Y947509D03*
X517229D03*
X506129D03*
Y941100D03*
X504278Y937896D03*
X507978Y944304D03*
X504278D03*
X511678Y950713D03*
X513529Y960326D03*
X511678Y957122D03*
X517229Y960326D03*
Y966735D03*
X513529D03*
X504278Y950713D03*
X513529Y953917D03*
X517229D03*
X509829D03*
X506129Y966735D03*
X504278Y957122D03*
X506129Y960326D03*
X507978Y963530D03*
Y982756D03*
X504278D03*
Y976347D03*
X506129Y979552D03*
X513529D03*
X517229D03*
X511678Y976347D03*
X509829Y973143D03*
X511678Y969939D03*
X504278D03*
X517662Y1006093D03*
X513962D03*
X510262D03*
X517662Y1012501D03*
X504711Y1002888D03*
X506561Y999684D03*
X513962Y1012501D03*
X512111Y1009297D03*
X506562Y1012501D03*
X504711Y1009297D03*
X517661Y999684D03*
X512111Y1002888D03*
X513962Y999684D03*
Y1031727D03*
X512111Y1028523D03*
X517662Y1031727D03*
X512111Y1022114D03*
X513962Y1018910D03*
X517662D03*
X513962Y1025318D03*
X510262D03*
X517662D03*
X508411Y1015705D03*
X506562Y1031727D03*
X504711Y1028523D03*
Y1022114D03*
X506562Y1018910D03*
X504711Y1041340D03*
X506562Y1038136D03*
X512111Y1047749D03*
Y1041340D03*
X513962Y1038136D03*
X517662D03*
X504711Y1047749D03*
X510262Y1044544D03*
X508411Y1034931D03*
X513962Y1044544D03*
X517662D03*
X504711Y1034931D03*
X512111Y1060565D03*
X513962Y1057361D03*
X517662D03*
X510262Y1063770D03*
X513962D03*
X517662D03*
X513962Y1050952D03*
X517662D03*
X504711Y1060565D03*
X506562Y1057361D03*
Y1050952D03*
X508411Y1054157D03*
X504711D03*
X517662Y1070178D03*
X513962D03*
X512111Y1066974D03*
X504711Y1079791D03*
X506562Y1076587D03*
Y1070178D03*
X504711Y1066974D03*
X512111Y1079791D03*
X513962Y1076587D03*
X517662D03*
X508411Y1073383D03*
X504711D03*
X513962Y1089404D03*
X512111Y1086200D03*
X517662Y1089404D03*
X513962Y1082995D03*
X510262D03*
X517662D03*
X510262Y1095813D03*
X506561D03*
X506562Y1089404D03*
X504711Y1086200D03*
X508411Y1092608D03*
X504711D03*
X517662Y1102221D03*
X515811Y1099017D03*
X517662Y1127856D03*
X513962Y1121447D03*
X510262Y1127856D03*
X506562Y1121447D03*
X502862Y1127856D03*
X515811Y1124651D03*
X512111D03*
X508411D03*
X504711D03*
X517661Y1140973D03*
X513962Y1134264D03*
X512112Y1137469D03*
X506562Y1134264D03*
X504712Y1137469D03*
X515812D03*
X510261Y1140973D03*
X508412Y1137469D03*
X502861Y1140973D03*
X532028Y844671D03*
X526478Y848176D03*
X524627Y844971D03*
X519079Y841467D03*
X533878Y848176D03*
X530178D03*
X522778D03*
X520927Y844971D03*
X532029Y864197D03*
X533879Y854584D03*
X519078Y867401D03*
X526479D03*
X528329Y857789D03*
X522778Y860993D03*
X520929Y857789D03*
X526478Y854584D03*
X524629Y857789D03*
X519078Y854584D03*
X524629Y870606D03*
X532029D03*
X520929D03*
X522778Y873810D03*
X528329Y870606D03*
X530178Y873810D03*
X519078Y880219D03*
X520929Y883423D03*
X526479Y880219D03*
X528329Y883423D03*
X524629D03*
X526479Y899445D03*
X530178D03*
X519078D03*
Y893036D03*
X522778D03*
X520929Y896240D03*
X522778Y886627D03*
X530179D03*
Y912262D03*
X532029Y909057D03*
X524629Y902649D03*
X532029D03*
X526479Y912262D03*
X524629Y909057D03*
X526479Y905853D03*
X533879D03*
X522778D03*
X530179D03*
X519078Y912262D03*
X520929Y915466D03*
X526479Y931488D03*
X524629Y928283D03*
X530179Y931488D03*
X532029Y928283D03*
X524629Y921875D03*
X526479Y918670D03*
X532029Y921875D03*
X530179Y918670D03*
X526479Y925079D03*
X533879D03*
X522778D03*
X530179D03*
X519078Y931488D03*
Y918670D03*
X524629Y941100D03*
X526479Y937896D03*
X532029Y941100D03*
X530179Y937896D03*
X524629Y947509D03*
X532029D03*
X519078Y937896D03*
X533879Y944304D03*
X520929Y934691D03*
X526479Y944304D03*
X530178D03*
X522778D03*
X524629Y966735D03*
X532029D03*
X522778Y963530D03*
X526479Y950713D03*
X530178D03*
X532029Y960326D03*
X530178Y957122D03*
X524629Y960326D03*
X526479Y957122D03*
X533879Y963530D03*
X519078Y950713D03*
Y957122D03*
X520929Y953917D03*
X526479Y969939D03*
X530179D03*
X519078Y976347D03*
Y969939D03*
X520929Y973143D03*
X521362Y1006093D03*
X525062Y1012501D03*
X532461D03*
X526911Y1009297D03*
X530611D03*
X519511D03*
X519513Y1002888D03*
X530611D03*
X532461Y999684D03*
X526911Y1002888D03*
X525062Y999684D03*
X523211Y1015705D03*
X534311D03*
X525062Y1031727D03*
X526911Y1028523D03*
X532461Y1031727D03*
X530611Y1028523D03*
Y1022114D03*
X532461Y1018910D03*
X526911Y1022114D03*
X525062Y1018910D03*
X519511Y1028523D03*
Y1022114D03*
X521362Y1025318D03*
X526911Y1041340D03*
X525062Y1038136D03*
X530611Y1041340D03*
X532461Y1038136D03*
X526911Y1047749D03*
X530611D03*
X526911Y1034931D03*
X534311D03*
X523211D03*
X530611D03*
X519511Y1047749D03*
Y1041340D03*
X521362Y1044544D03*
X519511Y1060565D03*
X526911D03*
X525062Y1057361D03*
X530611Y1060565D03*
X532462Y1057361D03*
X525061Y1050952D03*
X532462Y1050953D03*
X523211Y1054157D03*
X521362Y1063770D03*
X534311Y1054157D03*
X526911D03*
X530611D03*
Y1079791D03*
X532462Y1076587D03*
X525062Y1070178D03*
X526911Y1066974D03*
X532462Y1070178D03*
X530611Y1066974D03*
X526911Y1079791D03*
X525062Y1076587D03*
X523211Y1073383D03*
X534311D03*
X526911D03*
X530611D03*
X519511Y1066974D03*
Y1079791D03*
X521362Y1095813D03*
X532461D03*
X525062D03*
Y1089404D03*
X526911Y1086200D03*
X532462Y1089404D03*
X530611Y1086200D03*
X526911Y1092608D03*
X534310D03*
X523211D03*
X530611D03*
X519511Y1086200D03*
X521362Y1082995D03*
X530611Y1099017D03*
X526911Y1124651D03*
X521362Y1121447D03*
X525062Y1127856D03*
X523211Y1124651D03*
X519511D03*
X532462Y1134264D03*
X525061Y1140973D03*
X523212Y1137469D03*
X534312D03*
X526912D03*
X521362Y1134264D03*
X519512Y1137469D03*
X543129Y851380D03*
X539429D03*
X535729Y864197D03*
X543128D03*
X546828D03*
X535729Y857789D03*
X543130D03*
X539429D03*
X541279Y860993D03*
Y854584D03*
X539429Y883423D03*
X537578Y880219D03*
X543129Y883423D03*
X544979Y880219D03*
X537578Y873810D03*
X539429Y870606D03*
X544979Y873810D03*
X543129Y870606D03*
X539428Y877014D03*
X546828D03*
X535729D03*
X543129D03*
X620799Y883924D03*
Y890617D03*
Y897310D03*
Y900656D03*
Y914042D03*
Y907349D03*
Y960892D03*
Y957546D03*
Y1185105D03*
Y1178412D03*
Y1191798D03*
Y1208530D03*
Y1201837D03*
Y1195144D03*
X636941Y880577D03*
Y887270D03*
Y897310D03*
Y893963D03*
Y910696D03*
Y904003D03*
Y1175066D03*
Y1181759D03*
Y1191798D03*
Y1188451D03*
Y1205184D03*
Y1198491D03*
X650499Y960892D03*
Y957546D03*
X680299Y780184D03*
Y773491D03*
Y786877D03*
Y803609D03*
Y796916D03*
Y790223D03*
Y816995D03*
Y810302D03*
Y833727D03*
Y823688D03*
Y827034D03*
Y847113D03*
Y840420D03*
Y853806D03*
Y860499D03*
Y863845D03*
Y883924D03*
Y877231D03*
Y870538D03*
Y890617D03*
Y897310D03*
Y900656D03*
Y914042D03*
Y907349D03*
Y927428D03*
Y920735D03*
Y934121D03*
Y944160D03*
Y937467D03*
Y960892D03*
Y950853D03*
Y957546D03*
Y980971D03*
Y974278D03*
Y967585D03*
Y994357D03*
Y987664D03*
X679999Y1027822D03*
X680299Y1021129D03*
X679999Y1047900D03*
Y1041207D03*
Y1034514D03*
Y1054593D03*
X680299Y1074672D03*
Y1067979D03*
Y1091404D03*
Y1081365D03*
Y1084711D03*
Y1098097D03*
Y1111483D03*
Y1104790D03*
Y1128215D03*
Y1118176D03*
Y1121522D03*
Y1141601D03*
Y1134908D03*
Y1148294D03*
Y1154987D03*
Y1158333D03*
Y1171719D03*
Y1165026D03*
Y1185105D03*
Y1178412D03*
Y1191798D03*
Y1208530D03*
Y1201837D03*
Y1195144D03*
Y1221916D03*
Y1215223D03*
Y1238648D03*
Y1228609D03*
Y1231955D03*
Y1245341D03*
X696441Y770144D03*
Y776837D03*
Y786877D03*
Y783530D03*
Y800263D03*
Y793570D03*
Y813648D03*
Y806955D03*
Y820341D03*
Y830381D03*
Y823688D03*
Y850459D03*
Y843766D03*
Y837074D03*
Y867192D03*
Y860499D03*
Y857152D03*
Y873885D03*
Y880577D03*
Y887270D03*
Y897310D03*
Y893963D03*
Y917389D03*
Y910696D03*
Y904003D03*
Y924081D03*
Y934121D03*
Y930774D03*
Y947507D03*
Y940814D03*
Y964239D03*
Y977625D03*
Y970932D03*
Y991011D03*
Y984318D03*
Y1021129D03*
Y1024475D03*
Y1031168D03*
X696141Y1044554D03*
Y1037861D03*
X696441Y1051247D03*
Y1071325D03*
Y1064633D03*
Y1078018D03*
Y1094751D03*
Y1088058D03*
Y1081365D03*
Y1108136D03*
Y1101444D03*
Y1124869D03*
Y1118176D03*
Y1114829D03*
Y1144947D03*
Y1138255D03*
Y1131562D03*
Y1161680D03*
Y1154987D03*
Y1151640D03*
Y1175066D03*
Y1168373D03*
Y1181758D03*
Y1191798D03*
Y1188451D03*
Y1205184D03*
Y1198491D03*
Y1218569D03*
Y1211877D03*
Y1225262D03*
Y1241995D03*
Y1235302D03*
Y1228609D03*
X709899Y960892D03*
Y957546D03*
X709999Y967585D03*
Y1054593D03*
X726141Y964239D03*
Y1021129D03*
Y1024475D03*
Y1051247D03*
X739699Y780184D03*
Y773491D03*
Y786877D03*
Y803609D03*
Y796916D03*
Y790223D03*
Y816995D03*
Y810302D03*
Y833727D03*
Y823688D03*
Y827034D03*
Y847113D03*
Y840420D03*
Y853806D03*
Y860499D03*
Y863845D03*
Y883924D03*
Y877231D03*
Y870538D03*
Y890617D03*
Y897310D03*
Y900656D03*
Y914042D03*
Y907349D03*
Y927428D03*
Y920735D03*
Y934121D03*
Y944160D03*
Y937467D03*
Y960892D03*
Y950853D03*
Y957546D03*
Y980971D03*
Y974278D03*
Y967585D03*
Y994357D03*
Y987664D03*
Y1027822D03*
Y1021129D03*
Y1047900D03*
Y1041207D03*
Y1034514D03*
Y1054593D03*
Y1074672D03*
Y1067979D03*
Y1091404D03*
Y1081365D03*
Y1084711D03*
Y1098097D03*
Y1111483D03*
Y1104790D03*
Y1128215D03*
Y1118176D03*
Y1121522D03*
Y1141601D03*
Y1134908D03*
Y1148294D03*
Y1154987D03*
Y1158333D03*
Y1171719D03*
Y1165026D03*
Y1185105D03*
Y1178412D03*
Y1191798D03*
Y1208530D03*
Y1201837D03*
Y1195144D03*
Y1221916D03*
Y1215223D03*
Y1238648D03*
Y1228609D03*
Y1231955D03*
Y1245341D03*
X755841Y770144D03*
Y776837D03*
Y786877D03*
Y783530D03*
Y800263D03*
Y793570D03*
Y813648D03*
Y806955D03*
Y820341D03*
Y830381D03*
Y823688D03*
Y850459D03*
Y843766D03*
Y837074D03*
Y867192D03*
Y860499D03*
Y857152D03*
Y873885D03*
Y880577D03*
Y887270D03*
Y897310D03*
Y893963D03*
Y917389D03*
Y910696D03*
Y904003D03*
Y924081D03*
Y934121D03*
Y930774D03*
Y947507D03*
Y940814D03*
Y964239D03*
Y977625D03*
X755741Y970932D03*
X755841Y991011D03*
Y984318D03*
Y1021129D03*
Y1024475D03*
Y1031168D03*
X755541Y1044554D03*
Y1037861D03*
X755841Y1051247D03*
X755676Y1071326D03*
X755741Y1064633D03*
X755841Y1078018D03*
Y1094751D03*
Y1088058D03*
Y1081365D03*
X755676Y1108137D03*
X755841Y1101444D03*
Y1124869D03*
Y1118176D03*
Y1114829D03*
Y1144947D03*
Y1138255D03*
Y1131562D03*
Y1161680D03*
Y1154987D03*
Y1151640D03*
Y1175066D03*
Y1168373D03*
X755676Y1181759D03*
X755841Y1191798D03*
X755676Y1188452D03*
X755841Y1205184D03*
Y1198491D03*
Y1218569D03*
Y1211877D03*
Y1225262D03*
Y1241995D03*
Y1235302D03*
Y1228609D03*
X769399Y960892D03*
Y957546D03*
Y967585D03*
Y1054593D03*
X785541Y964239D03*
Y1021129D03*
Y1024475D03*
Y1051247D03*
X799099Y780184D03*
Y773491D03*
Y786877D03*
Y803609D03*
Y796916D03*
Y790223D03*
Y816995D03*
Y810302D03*
Y833727D03*
Y823688D03*
Y827034D03*
Y847113D03*
Y840420D03*
Y853806D03*
Y860499D03*
Y863845D03*
Y883924D03*
Y877231D03*
Y870538D03*
Y890617D03*
Y897310D03*
Y900656D03*
Y914042D03*
Y907349D03*
Y927428D03*
Y920735D03*
Y934121D03*
Y944160D03*
Y937467D03*
Y960892D03*
Y950853D03*
Y957546D03*
Y980971D03*
Y974278D03*
Y967585D03*
Y994357D03*
Y987664D03*
Y1027822D03*
Y1021129D03*
Y1047900D03*
Y1041207D03*
Y1034515D03*
Y1054593D03*
Y1074672D03*
Y1067979D03*
Y1091404D03*
Y1081365D03*
Y1084711D03*
Y1098097D03*
Y1111483D03*
Y1104790D03*
Y1128215D03*
Y1118176D03*
Y1121522D03*
Y1141601D03*
Y1134908D03*
Y1148294D03*
Y1154987D03*
Y1158333D03*
Y1171719D03*
Y1165026D03*
Y1185105D03*
Y1178412D03*
Y1191798D03*
Y1208530D03*
Y1201837D03*
Y1195144D03*
Y1221916D03*
Y1215223D03*
Y1238648D03*
Y1228609D03*
Y1231955D03*
Y1245341D03*
X815241Y770144D03*
Y776837D03*
Y786877D03*
Y783530D03*
Y800263D03*
Y793570D03*
Y813648D03*
Y806955D03*
Y820341D03*
Y830381D03*
Y823688D03*
Y850459D03*
Y843766D03*
Y837074D03*
Y867192D03*
Y860499D03*
Y857152D03*
Y873885D03*
Y880577D03*
Y887270D03*
Y897310D03*
Y893963D03*
Y917389D03*
Y910696D03*
Y904003D03*
Y924081D03*
Y934121D03*
Y930774D03*
Y947507D03*
Y940814D03*
Y964239D03*
Y977625D03*
Y970932D03*
Y991011D03*
Y984318D03*
Y1021129D03*
Y1024475D03*
Y1031168D03*
Y1044554D03*
Y1037861D03*
X814941Y1051247D03*
X815241Y1071325D03*
Y1064633D03*
Y1078018D03*
Y1094751D03*
Y1088058D03*
Y1081365D03*
Y1108136D03*
Y1101444D03*
Y1124869D03*
Y1118176D03*
Y1114829D03*
Y1144947D03*
Y1138255D03*
Y1131562D03*
Y1161680D03*
Y1154987D03*
Y1151640D03*
Y1175066D03*
Y1168373D03*
Y1181758D03*
Y1191798D03*
Y1188451D03*
Y1205184D03*
Y1198491D03*
Y1218570D03*
Y1211877D03*
Y1225263D03*
Y1241995D03*
Y1235302D03*
Y1228609D03*
X828799Y960892D03*
Y957546D03*
Y967585D03*
Y1054593D03*
X844941Y964239D03*
Y1021129D03*
Y1024475D03*
Y1051247D03*
X1012541Y960892D03*
Y957546D03*
Y967585D03*
Y1054593D03*
X1028683Y964239D03*
Y1021129D03*
Y1024475D03*
Y1051247D03*
X1042241Y780184D03*
Y773491D03*
Y786877D03*
Y803609D03*
Y796916D03*
Y790223D03*
Y816995D03*
Y810302D03*
Y833727D03*
Y823688D03*
Y827034D03*
Y847113D03*
Y840420D03*
Y853806D03*
Y860499D03*
Y863845D03*
Y883924D03*
Y877231D03*
Y870538D03*
Y890617D03*
Y897310D03*
Y900656D03*
Y914042D03*
Y907349D03*
Y927428D03*
Y920735D03*
Y934121D03*
Y944160D03*
Y937467D03*
Y960892D03*
Y950853D03*
Y957546D03*
Y980971D03*
Y974278D03*
Y967585D03*
Y994357D03*
Y987664D03*
Y1027822D03*
Y1021129D03*
Y1047900D03*
Y1041207D03*
Y1034515D03*
Y1054593D03*
Y1074672D03*
Y1067979D03*
Y1091404D03*
Y1081365D03*
Y1084711D03*
Y1098097D03*
Y1111483D03*
Y1104790D03*
Y1128215D03*
Y1118176D03*
Y1121522D03*
Y1141601D03*
Y1134908D03*
Y1148294D03*
Y1154987D03*
Y1158333D03*
Y1171719D03*
Y1165026D03*
Y1185105D03*
Y1178412D03*
Y1191798D03*
Y1208530D03*
Y1201837D03*
Y1195144D03*
Y1221916D03*
Y1215223D03*
Y1238648D03*
Y1228609D03*
Y1231955D03*
Y1245341D03*
X1058383Y770144D03*
Y776837D03*
Y786877D03*
Y783530D03*
Y800263D03*
Y793570D03*
Y813648D03*
Y806955D03*
Y820341D03*
Y830381D03*
Y823688D03*
Y850459D03*
Y843766D03*
Y837074D03*
Y867192D03*
Y860499D03*
Y857152D03*
Y873885D03*
Y880577D03*
Y887270D03*
Y897310D03*
Y893963D03*
Y917389D03*
Y910696D03*
Y904003D03*
Y924081D03*
Y934121D03*
Y930774D03*
Y947507D03*
Y940814D03*
Y964239D03*
Y977625D03*
Y970932D03*
Y991011D03*
Y984318D03*
Y1021129D03*
Y1024475D03*
Y1031168D03*
Y1044554D03*
Y1037861D03*
Y1051247D03*
Y1071326D03*
Y1064633D03*
Y1078018D03*
Y1094751D03*
Y1088058D03*
Y1081365D03*
Y1108137D03*
Y1101444D03*
Y1124869D03*
Y1118176D03*
Y1114829D03*
Y1144948D03*
Y1138255D03*
Y1131562D03*
Y1161680D03*
Y1154987D03*
Y1151641D03*
Y1175066D03*
Y1168373D03*
Y1181759D03*
Y1191798D03*
Y1188452D03*
Y1205184D03*
Y1198491D03*
Y1218570D03*
Y1211877D03*
Y1225263D03*
Y1241995D03*
Y1235302D03*
Y1228609D03*
X1071941Y960892D03*
Y957546D03*
Y967585D03*
Y1054593D03*
X1101641Y780184D03*
Y773491D03*
Y786877D03*
Y803609D03*
Y796916D03*
Y790223D03*
Y816995D03*
Y810302D03*
Y833727D03*
Y823688D03*
Y827034D03*
Y847113D03*
Y840420D03*
Y853806D03*
Y860499D03*
Y863845D03*
Y883924D03*
Y877231D03*
Y870538D03*
Y890617D03*
Y897310D03*
Y900656D03*
Y914042D03*
Y907349D03*
Y927428D03*
Y920735D03*
Y934121D03*
Y944160D03*
Y937467D03*
Y960892D03*
Y950853D03*
X1088083Y964239D03*
X1101641Y957546D03*
Y980971D03*
Y974278D03*
Y967585D03*
Y994357D03*
Y987664D03*
X1088083Y1021129D03*
Y1024475D03*
X1101641Y1027822D03*
Y1021129D03*
Y1047900D03*
Y1041207D03*
Y1034515D03*
X1088083Y1051247D03*
X1101641Y1054593D03*
Y1074672D03*
Y1067979D03*
Y1091404D03*
Y1081365D03*
Y1084711D03*
Y1098097D03*
Y1111483D03*
Y1104790D03*
Y1128215D03*
Y1118176D03*
Y1121522D03*
Y1141601D03*
Y1134908D03*
Y1148294D03*
Y1154987D03*
Y1158333D03*
Y1171719D03*
Y1165026D03*
Y1185105D03*
Y1178412D03*
Y1191798D03*
Y1208530D03*
Y1201837D03*
Y1195144D03*
Y1221916D03*
Y1215223D03*
Y1238648D03*
Y1228609D03*
Y1231955D03*
Y1245341D03*
X1117783Y770144D03*
Y776837D03*
Y786877D03*
Y783530D03*
Y800263D03*
Y793570D03*
Y813648D03*
Y806955D03*
Y820341D03*
Y830381D03*
Y823688D03*
Y850459D03*
Y843766D03*
Y837074D03*
Y867192D03*
Y860499D03*
Y857152D03*
Y873885D03*
Y880577D03*
Y887270D03*
Y897310D03*
Y893963D03*
Y917389D03*
Y910696D03*
Y904003D03*
Y924081D03*
Y934121D03*
Y930774D03*
Y947507D03*
Y940814D03*
Y964239D03*
Y977625D03*
Y970932D03*
Y991011D03*
Y984318D03*
Y1021129D03*
Y1024475D03*
Y1031168D03*
Y1044554D03*
Y1037861D03*
Y1051247D03*
Y1071326D03*
Y1064633D03*
Y1078018D03*
Y1094751D03*
Y1088058D03*
Y1081365D03*
Y1108137D03*
Y1101444D03*
Y1124869D03*
Y1118176D03*
Y1114829D03*
Y1144948D03*
Y1138255D03*
Y1131562D03*
Y1161680D03*
Y1154987D03*
Y1151641D03*
Y1175066D03*
Y1168373D03*
Y1181759D03*
Y1191798D03*
Y1188452D03*
Y1205184D03*
Y1198491D03*
Y1218570D03*
Y1211877D03*
Y1225263D03*
Y1241995D03*
Y1235302D03*
Y1228609D03*
X1131341Y960892D03*
Y957546D03*
Y967585D03*
Y1054593D03*
X1147483Y964239D03*
Y1021129D03*
Y1024475D03*
Y1051247D03*
X1161041Y780184D03*
Y773491D03*
Y786877D03*
Y803609D03*
Y796916D03*
Y790223D03*
Y816995D03*
Y810302D03*
Y833727D03*
Y823688D03*
Y827034D03*
Y847113D03*
Y840420D03*
Y853806D03*
Y860499D03*
Y863845D03*
Y883924D03*
Y877231D03*
Y870538D03*
Y890617D03*
Y897310D03*
Y900656D03*
Y914042D03*
Y907349D03*
Y927428D03*
Y920735D03*
Y934121D03*
Y944160D03*
Y937467D03*
Y960892D03*
Y950853D03*
Y957546D03*
Y980971D03*
Y974278D03*
Y967585D03*
Y994357D03*
Y987664D03*
Y1027822D03*
Y1021129D03*
Y1047900D03*
Y1041207D03*
Y1034515D03*
Y1054593D03*
Y1074672D03*
Y1067979D03*
Y1091404D03*
Y1081365D03*
Y1084711D03*
Y1098097D03*
Y1111483D03*
Y1104790D03*
Y1128215D03*
Y1118176D03*
Y1121522D03*
Y1141601D03*
Y1134908D03*
Y1148294D03*
Y1154987D03*
Y1158333D03*
Y1171719D03*
Y1165026D03*
Y1185105D03*
Y1178412D03*
Y1191798D03*
Y1208530D03*
Y1201837D03*
Y1195144D03*
Y1221916D03*
Y1215223D03*
Y1238648D03*
Y1228609D03*
Y1231955D03*
Y1245341D03*
X1177183Y770144D03*
Y776837D03*
Y786877D03*
Y783530D03*
Y800263D03*
Y793570D03*
Y813648D03*
Y806955D03*
Y820341D03*
Y830381D03*
Y823688D03*
Y850459D03*
Y843766D03*
Y837074D03*
Y867192D03*
Y860499D03*
Y857152D03*
Y873885D03*
Y880577D03*
Y887270D03*
Y897310D03*
Y893963D03*
Y917389D03*
Y910696D03*
Y904003D03*
Y924081D03*
Y934121D03*
Y930774D03*
Y947507D03*
Y940814D03*
Y964239D03*
Y977625D03*
Y970932D03*
Y991011D03*
Y984318D03*
X1177283Y1021129D03*
Y1024475D03*
Y1031168D03*
Y1044554D03*
Y1037861D03*
Y1051247D03*
Y1071326D03*
Y1064633D03*
Y1078018D03*
Y1094752D03*
Y1088059D03*
Y1081366D03*
Y1108137D03*
Y1101444D03*
X1177183Y1124869D03*
X1177283Y1118177D03*
Y1114830D03*
Y1144948D03*
Y1138255D03*
X1177183Y1131562D03*
X1177283Y1161680D03*
Y1154988D03*
Y1151641D03*
Y1175066D03*
Y1168373D03*
Y1181759D03*
Y1191799D03*
Y1188452D03*
Y1205184D03*
Y1198491D03*
Y1218570D03*
Y1211877D03*
Y1225263D03*
X1177250Y1241995D03*
X1177283Y1235302D03*
Y1228609D03*
X1190741Y960892D03*
Y957546D03*
X1220441Y883924D03*
Y890617D03*
Y897310D03*
Y900656D03*
Y914042D03*
Y907349D03*
Y960892D03*
Y957546D03*
Y1185105D03*
Y1178412D03*
Y1191798D03*
Y1208530D03*
Y1201837D03*
Y1195144D03*
X1236583Y880577D03*
Y887270D03*
Y897310D03*
Y893963D03*
Y910696D03*
Y904003D03*
Y1175066D03*
Y1181759D03*
Y1191798D03*
Y1188452D03*
Y1205184D03*
Y1198491D03*
X1313921Y880219D03*
X1312070Y883423D03*
X1313921Y893036D03*
X1312070Y889832D03*
X1310221Y886627D03*
X1313921D03*
X1312503Y1121447D03*
X1326869Y851380D03*
X1330569Y844971D03*
X1325020Y848176D03*
X1328720D03*
X1326871Y857789D03*
X1328720Y860993D03*
X1330571Y857789D03*
X1317621Y880219D03*
X1319471Y883423D03*
X1326871Y870606D03*
X1330571D03*
X1328720Y873810D03*
X1330571Y883423D03*
X1325020Y899445D03*
Y893036D03*
X1326871Y889832D03*
X1330571D03*
X1317620Y893036D03*
X1319470Y889832D03*
X1323171Y896240D03*
X1330571D03*
X1317621Y886627D03*
X1326871Y896240D03*
X1321321Y886627D03*
X1325020Y912262D03*
X1326871Y909057D03*
X1330571D03*
X1326871Y902649D03*
X1330571D03*
X1323171Y915466D03*
X1330571D03*
X1326871D03*
X1325021Y931488D03*
X1326871Y928283D03*
X1330571D03*
Y921875D03*
X1326871D03*
X1325020Y918670D03*
X1326871Y941100D03*
X1325020Y937896D03*
X1330571Y941100D03*
X1323171Y934691D03*
X1330571D03*
X1326871D03*
Y947509D03*
X1330571D03*
X1325020Y950713D03*
X1326871Y960326D03*
X1325020Y957122D03*
X1330571Y960326D03*
X1326871Y966735D03*
X1330571D03*
X1326871Y953917D03*
X1330571D03*
X1323172D03*
X1326871Y979552D03*
X1330571D03*
X1325020Y976347D03*
X1323171Y973143D03*
X1325020Y969939D03*
X1323603Y1006093D03*
X1325453Y1002888D03*
X1327303Y999684D03*
X1331003D03*
X1327303Y1012501D03*
X1325453Y1009297D03*
X1331003Y1012501D03*
X1327304Y1031727D03*
X1325453Y1028523D03*
X1331003Y1031727D03*
X1325453Y1022114D03*
X1327303Y1018910D03*
X1331003D03*
X1323603Y1025318D03*
X1331004D03*
X1327304D03*
X1325453Y1047749D03*
Y1041340D03*
X1327303Y1038136D03*
X1331003D03*
X1323603Y1044544D03*
X1331003D03*
X1327303D03*
X1325453Y1060565D03*
X1327303Y1057361D03*
X1331003D03*
X1323603Y1063770D03*
X1327303D03*
X1331003D03*
X1327303Y1050952D03*
X1331003D03*
Y1070178D03*
X1327304D03*
X1325453Y1066974D03*
Y1079791D03*
X1327303Y1076587D03*
X1331003D03*
X1327303Y1089404D03*
X1325453Y1086200D03*
X1331003Y1089404D03*
X1323603Y1082995D03*
X1331003D03*
X1327303D03*
X1329153Y1105426D03*
X1325454Y1111834D03*
X1327303Y1102221D03*
X1321753Y1111834D03*
X1318054D03*
X1318053Y1105426D03*
X1327304Y1108630D03*
X1329154Y1111834D03*
X1331003Y1102221D03*
X1319904Y1108630D03*
X1321753Y1105426D03*
X1329153Y1124651D03*
X1331003Y1127856D03*
X1323603Y1121447D03*
X1319903Y1127856D03*
X1316203D03*
X1318054Y1118243D03*
X1321753Y1124651D03*
X1323603Y1127856D03*
X1319903Y1121447D03*
X1316203D03*
X1323603Y1115039D03*
X1325452Y1137469D03*
X1327303Y1134264D03*
X1318053Y1131060D03*
X1346137Y175949D03*
X1342937Y177799D03*
X1346137Y179649D03*
X1332421Y841467D03*
X1337969Y844971D03*
X1339821Y841467D03*
X1345369Y844971D03*
X1347221Y841467D03*
X1334269Y844971D03*
X1336120Y848176D03*
X1341669Y844971D03*
X1343520Y848176D03*
X1347220Y867401D03*
X1332420D03*
X1339820D03*
X1332420Y854584D03*
X1334271Y857789D03*
X1337971D03*
X1341671D03*
X1345371D03*
X1336120Y860993D03*
X1339820Y854584D03*
X1343520Y860993D03*
X1347220Y854584D03*
X1334271Y870606D03*
X1337971D03*
X1341671D03*
X1336120Y873810D03*
X1343520D03*
X1345371Y870606D03*
X1332420Y880219D03*
X1334271Y883423D03*
X1339820Y880219D03*
X1341671Y883423D03*
X1347220Y880219D03*
X1337971Y883423D03*
X1345371D03*
X1332420Y899445D03*
Y893036D03*
X1334271Y896240D03*
X1339820Y899445D03*
X1343520D03*
X1347220Y893036D03*
X1336120Y886627D03*
X1343520D03*
X1332420Y912262D03*
X1334271Y915466D03*
X1339820Y912262D03*
X1337971Y909057D03*
X1343520Y912262D03*
X1345371Y909057D03*
X1337971Y902649D03*
X1345371D03*
X1336120Y905853D03*
X1343520D03*
X1339820D03*
X1347220D03*
X1332420Y931488D03*
X1339820D03*
X1332420Y918670D03*
X1337971Y928283D03*
X1343520Y931488D03*
X1345371Y928283D03*
X1337971Y921875D03*
X1339820Y918670D03*
X1345371Y921875D03*
X1343520Y918670D03*
X1336120Y925079D03*
X1343520D03*
X1339820D03*
X1347220D03*
X1332420Y937896D03*
X1334271Y934691D03*
X1337971Y941100D03*
X1339820Y937896D03*
X1345371Y941100D03*
X1343520Y937896D03*
X1337971Y947509D03*
X1345371D03*
X1343520Y944304D03*
X1336120D03*
X1347220D03*
X1339820D03*
X1332420Y950713D03*
Y957122D03*
X1334271Y953917D03*
X1337971Y966735D03*
X1345371D03*
X1336120Y963530D03*
X1339820Y950713D03*
X1343520D03*
X1337971Y960326D03*
X1339820Y957122D03*
X1345371Y960326D03*
X1343520Y957122D03*
X1347220Y963530D03*
X1336120Y982756D03*
X1343520D03*
X1339820D03*
X1347220D03*
X1345371Y979552D03*
X1343520Y976347D03*
X1337971Y979552D03*
X1339820Y976347D03*
X1332420D03*
Y969939D03*
X1334271Y973143D03*
X1339820Y969939D03*
X1343520D03*
X1334704Y1006093D03*
X1332853Y1002888D03*
Y1009297D03*
X1338404Y1012501D03*
X1345804D03*
X1340253Y1009297D03*
X1343953D03*
X1340253Y1002888D03*
X1338404Y999684D03*
X1347653Y1002888D03*
X1345804Y999684D03*
X1332853Y1028523D03*
Y1022114D03*
X1338404Y1031727D03*
X1340253Y1028523D03*
X1345804Y1031727D03*
X1343953Y1028523D03*
X1334704Y1025318D03*
X1336553Y1015705D03*
X1347653D03*
X1340253Y1022114D03*
X1338404Y1018910D03*
X1343953Y1022114D03*
X1345804Y1018910D03*
X1332853Y1047749D03*
Y1041340D03*
X1340253D03*
X1338404Y1038136D03*
X1343953Y1041340D03*
X1345804Y1038136D03*
X1336553Y1034931D03*
X1347653D03*
X1340253D03*
X1334704Y1044544D03*
X1343953Y1034931D03*
X1340253Y1047749D03*
X1343953D03*
X1332853Y1060565D03*
X1334704Y1063770D03*
X1340253Y1060565D03*
X1338404Y1057361D03*
X1343953Y1060565D03*
X1345804Y1057361D03*
X1338404Y1050952D03*
X1345804D03*
X1336553Y1054157D03*
X1347653D03*
X1340253D03*
X1343953D03*
X1332853Y1066974D03*
X1343953Y1079791D03*
X1345804Y1076587D03*
X1338404Y1070178D03*
X1340253Y1066974D03*
X1345804Y1070178D03*
X1343953Y1066974D03*
X1332853Y1079791D03*
X1340253D03*
X1338404Y1076587D03*
X1336553Y1073383D03*
X1347653D03*
X1340253D03*
X1343953D03*
X1332853Y1086200D03*
X1334704Y1082995D03*
X1338404Y1095813D03*
X1345804D03*
X1338404Y1089404D03*
X1340253Y1086200D03*
X1345804Y1089404D03*
X1343953Y1086200D03*
X1336553Y1092608D03*
X1343953D03*
X1340253D03*
X1347653D03*
X1340253Y1099017D03*
X1343953D03*
X1345803Y1108630D03*
X1340254Y1105426D03*
X1336554Y1111834D03*
X1334703Y1108630D03*
X1343954Y1111834D03*
X1342103Y1108630D03*
X1338403D03*
X1334703Y1121447D03*
X1336554Y1124651D03*
X1340253D03*
X1343953D03*
X1347653D03*
X1332854D03*
X1338404Y1127856D03*
X1342104Y1121447D03*
X1345804Y1127856D03*
X1342103Y1115039D03*
X1345803D03*
X1334703D03*
Y1134264D03*
X1338403Y1140973D03*
X1342104Y1134264D03*
X1345803Y1140973D03*
X1332854Y1137469D03*
X1336554D03*
X1340254D03*
X1343954D03*
X1347654D03*
X1352557Y168548D03*
X1355762Y166698D03*
X1352557Y172248D03*
X1349351Y177798D03*
Y170398D03*
Y174098D03*
X1352557Y175948D03*
X1349351Y181498D03*
X1355761Y185198D03*
X1349351D03*
X1355761Y174098D03*
Y181498D03*
X1352557Y183348D03*
X1352561Y198148D03*
X1355771Y196298D03*
X1355765Y199999D03*
Y203699D03*
X1363869Y844971D03*
X1352769D03*
X1356469D03*
X1360169D03*
X1362021Y841467D03*
X1349069Y844971D03*
X1350920Y848176D03*
X1354621Y841467D03*
X1358320Y848176D03*
X1354620Y867401D03*
X1362020D03*
X1349071Y857789D03*
X1354620Y854584D03*
X1356471Y857789D03*
X1360171D03*
X1363871D03*
X1350920Y860993D03*
X1352771Y857789D03*
X1358320Y860993D03*
X1362020Y854584D03*
X1363871Y870606D03*
X1349071D03*
X1356471D03*
X1350920Y873810D03*
X1352771Y870606D03*
X1358320Y873810D03*
X1360171Y870606D03*
X1349071Y883423D03*
X1354620Y880219D03*
X1356471Y883423D03*
X1362020Y880219D03*
X1363871Y883423D03*
X1352771D03*
X1360171D03*
X1350920Y899445D03*
X1358320D03*
Y893036D03*
X1350920D03*
X1362020D03*
X1349071Y896240D03*
X1356471D03*
X1352771D03*
X1360171D03*
X1350920Y886627D03*
X1358320D03*
X1352771Y902649D03*
X1356471D03*
X1350920Y912262D03*
X1352771Y909057D03*
X1358320Y912262D03*
X1356471Y909057D03*
X1363871D03*
Y902649D03*
X1349071Y915466D03*
X1362020Y905853D03*
X1356471Y915466D03*
X1352771D03*
X1360171D03*
X1350920Y931488D03*
X1352771Y928283D03*
X1358320Y931488D03*
X1356471Y928283D03*
X1363871Y921875D03*
X1352771D03*
X1350920Y918670D03*
X1356471Y921875D03*
X1358320Y918670D03*
X1363871Y928283D03*
X1362020Y925079D03*
X1356471Y941100D03*
X1358320Y937896D03*
X1352771Y947509D03*
X1356471D03*
X1352771Y941100D03*
X1350920Y937896D03*
X1349071Y934691D03*
X1356471D03*
X1352771D03*
X1360171D03*
X1363871Y947509D03*
Y941100D03*
X1362020Y944304D03*
X1352771Y960326D03*
X1350920Y957122D03*
X1356471Y960326D03*
X1358320Y957122D03*
X1350920Y950713D03*
X1358320D03*
X1349071Y953917D03*
X1356471D03*
X1352771D03*
X1360171D03*
X1363871Y960326D03*
Y966735D03*
X1356471D03*
X1352771D03*
X1362020Y963530D03*
Y982756D03*
X1363871Y979552D03*
X1352771D03*
X1356471D03*
X1350920Y976347D03*
X1358320D03*
X1349071Y973143D03*
X1350920Y969939D03*
X1358320D03*
X1360171Y973143D03*
X1349504Y1006093D03*
X1356904D03*
X1353204D03*
X1360604D03*
X1351353Y1002888D03*
X1353204Y999684D03*
X1358753Y1002888D03*
X1356904Y999684D03*
X1353204Y1012501D03*
X1351353Y1009297D03*
X1356904Y1012501D03*
X1358753Y1009297D03*
X1353204Y1031727D03*
X1351353Y1028523D03*
X1356904Y1031727D03*
X1358753Y1028523D03*
X1351353Y1022114D03*
X1353204Y1018910D03*
X1358753Y1022114D03*
X1356904Y1018910D03*
X1353204Y1025318D03*
X1360604D03*
X1349502D03*
X1356902D03*
X1362453Y1015705D03*
X1351353Y1047749D03*
X1358753D03*
X1351353Y1041340D03*
X1353204Y1038136D03*
X1358753Y1041340D03*
X1356904Y1038136D03*
X1349504Y1044544D03*
X1356904D03*
X1353204D03*
X1360604D03*
X1362453Y1034931D03*
X1351353Y1060565D03*
X1353204Y1057361D03*
X1358753Y1060565D03*
X1356904Y1057361D03*
X1353204Y1050952D03*
X1356904D03*
X1349504Y1063770D03*
X1360604D03*
X1353204D03*
X1356904D03*
X1362453Y1054157D03*
X1356904Y1070178D03*
X1358753Y1066974D03*
X1353204Y1070178D03*
X1351353Y1066974D03*
Y1079791D03*
X1353204Y1076587D03*
X1358753Y1079791D03*
X1356904Y1076587D03*
X1362453Y1073383D03*
X1353204Y1089404D03*
X1351353Y1086200D03*
X1356904Y1089404D03*
X1358753Y1086200D03*
X1349504Y1082995D03*
X1362453Y1092608D03*
X1360604Y1082995D03*
X1353204D03*
X1356904D03*
X1362453Y1111834D03*
Y1105426D03*
X1358753D03*
X1351353Y1111834D03*
Y1105426D03*
X1358753Y1111834D03*
X1360604Y1108630D03*
X1355053Y1111834D03*
X1356904Y1102221D03*
X1353204Y1108630D03*
X1355054Y1105426D03*
X1351353Y1124651D03*
X1355053D03*
X1358753D03*
X1362453D03*
X1349504Y1121447D03*
X1353204Y1127856D03*
X1356904Y1121447D03*
X1360604Y1127856D03*
X1356904Y1115039D03*
X1349504Y1134264D03*
X1353203Y1140973D03*
X1356904Y1134264D03*
X1360603Y1140973D03*
X1351354Y1137469D03*
X1355054D03*
X1358754D03*
X1362454D03*
X1367569Y844971D03*
X1369421Y841467D03*
X1373120Y848176D03*
X1376821Y841467D03*
X1365720Y848176D03*
X1371269Y844971D03*
X1374969D03*
X1378669D03*
X1376820Y867401D03*
X1369420D03*
X1365720Y860993D03*
X1367571Y857789D03*
X1373120Y860993D03*
X1374971Y857789D03*
X1369420Y854584D03*
X1371271Y857789D03*
X1376820Y854584D03*
X1378671Y857789D03*
X1367571Y870606D03*
X1371271D03*
X1378671D03*
X1365720Y873810D03*
X1373120D03*
X1374971Y870606D03*
X1369420Y880219D03*
X1371271Y883423D03*
X1376820Y880219D03*
X1378671Y883423D03*
X1367571D03*
X1374971D03*
X1365720Y899445D03*
X1369420D03*
X1373120Y886627D03*
X1365720D03*
Y912262D03*
X1369420D03*
X1371271Y909057D03*
Y902649D03*
X1369420Y905853D03*
X1365720D03*
X1373120D03*
X1369420Y931488D03*
X1371271Y928283D03*
X1365720Y918670D03*
X1371271Y921875D03*
X1369420Y918670D03*
X1365720Y931488D03*
X1369420Y925079D03*
X1365720D03*
X1373120D03*
X1371271Y947509D03*
X1365720Y937896D03*
X1371271Y941100D03*
X1369420Y937896D03*
Y944304D03*
X1365720D03*
X1373120D03*
X1365720Y957122D03*
X1371271Y960326D03*
X1369420Y957122D03*
X1371271Y966735D03*
X1365720Y950713D03*
X1369420D03*
X1373120Y963530D03*
X1369420D03*
X1365720D03*
X1374971Y973143D03*
X1376820Y976347D03*
X1378671Y979552D03*
Y973143D03*
X1369420Y982756D03*
X1365720D03*
X1373120D03*
X1369420Y976347D03*
X1371271Y979552D03*
X1365721Y976347D03*
X1365720Y969939D03*
X1369420D03*
X1366153Y1002888D03*
X1364304Y999684D03*
X1369853Y1002888D03*
X1371704Y999684D03*
X1364304Y1012501D03*
X1371704D03*
X1366153Y1009297D03*
X1369853D03*
X1373553Y1015705D03*
X1364304Y1031727D03*
X1366153Y1028523D03*
X1371704Y1031727D03*
X1369853Y1028523D03*
X1366153Y1022114D03*
X1364304Y1018910D03*
X1369853Y1022114D03*
X1371704Y1018910D03*
X1366153Y1041340D03*
X1364304Y1038136D03*
X1369853Y1041340D03*
X1371704Y1038136D03*
X1366153Y1047749D03*
X1369853D03*
Y1034931D03*
X1366153D03*
X1373553D03*
X1366153Y1060565D03*
X1364304Y1057361D03*
X1369853Y1060565D03*
X1371704Y1057361D03*
X1364304Y1050952D03*
X1371704D03*
X1369853Y1054157D03*
X1366153D03*
X1373553D03*
X1366153Y1079791D03*
X1364304Y1076587D03*
X1369853Y1079791D03*
X1371704Y1076587D03*
X1364304Y1070178D03*
X1366153Y1066974D03*
X1371704Y1070178D03*
X1369853Y1066974D03*
Y1073383D03*
X1366153D03*
X1373553D03*
X1371704Y1095813D03*
X1364304Y1089404D03*
X1366153Y1086200D03*
X1371704Y1089404D03*
X1369853Y1086200D03*
X1364304Y1095813D03*
X1369853Y1092608D03*
X1366153D03*
X1373553D03*
X1379104Y1082995D03*
X1379103Y1089404D03*
X1369853Y1099017D03*
X1366153D03*
X1369853Y1111834D03*
X1368004Y1108630D03*
X1377253Y1099017D03*
X1379104Y1108630D03*
X1373553Y1105426D03*
X1371704Y1108630D03*
X1379104Y1102221D03*
X1377253Y1111834D03*
X1375404Y1108630D03*
X1366153Y1124651D03*
X1371704Y1121447D03*
X1373553Y1124651D03*
X1377253D03*
X1368004Y1127856D03*
X1369853Y1124651D03*
X1375404Y1127856D03*
X1379104Y1121447D03*
X1364304D03*
X1375404Y1115039D03*
X1368004D03*
X1379104D03*
X1368003Y1140973D03*
X1371704Y1134264D03*
X1375403Y1140973D03*
X1379104Y1134264D03*
X1364304D03*
X1366154Y1137469D03*
X1369854D03*
X1373554D03*
X1377254D03*
X1380520Y848176D03*
X1386069Y844971D03*
X1389769D03*
X1393469D03*
X1382369D03*
X1384221Y841467D03*
X1387920Y848176D03*
X1391621Y841467D03*
X1395320Y848176D03*
X1384220Y867401D03*
X1391620D03*
X1380520Y860993D03*
X1382371Y857789D03*
X1387920Y860993D03*
X1389771Y857789D03*
X1395320Y860993D03*
X1384220Y854584D03*
X1386071Y857789D03*
X1391620Y854584D03*
X1393471Y857789D03*
X1380520Y873810D03*
X1382371Y870606D03*
X1384220Y880219D03*
X1386071Y883423D03*
X1382371D03*
X1395320Y873810D03*
X1393471Y870606D03*
X1387920Y873810D03*
X1389771Y870606D03*
X1393471Y883423D03*
X1391620Y880219D03*
X1389771Y883423D03*
X1386071Y896240D03*
X1389771D03*
X1393471D03*
X1387920Y899445D03*
X1391620Y893036D03*
X1395320Y899445D03*
X1380520Y886627D03*
X1387920D03*
X1395320D03*
X1384653Y1079791D03*
X1388353Y1086200D03*
X1386504Y1082995D03*
X1390204Y1089404D03*
X1382804D03*
X1390204Y1082995D03*
X1382804D03*
X1395753Y1086200D03*
Y1092608D03*
X1380953Y1086200D03*
X1386504Y1089404D03*
X1384653Y1092608D03*
X1380953Y1099017D03*
X1395753Y1105426D03*
X1393904Y1108630D03*
X1390204Y1102221D03*
X1392053Y1111834D03*
X1388353D03*
X1384653Y1105426D03*
Y1099017D03*
X1392053Y1105426D03*
X1395753Y1111834D03*
X1388353Y1105426D03*
X1384653Y1111834D03*
X1386504Y1108630D03*
X1380953Y1124651D03*
X1384653D03*
X1382804Y1127856D03*
X1386504Y1121447D03*
X1390204Y1115039D03*
X1382803Y1140973D03*
X1386504Y1134264D03*
X1380954Y1137469D03*
X1384654D03*
X1397169Y844971D03*
X1399021Y841467D03*
X1402720Y848176D03*
X1406420D03*
X1411969Y844971D03*
X1400869D03*
X1404569D03*
X1410120Y848176D03*
X1406420Y867401D03*
X1399020D03*
X1397171Y857789D03*
X1402720Y860993D03*
X1404571Y857789D03*
X1410121Y860993D03*
X1411971Y857789D03*
X1399020Y854584D03*
X1400871Y857789D03*
X1406420Y854584D03*
X1408271Y857789D03*
Y870606D03*
X1402720Y873810D03*
X1400871Y870606D03*
X1410121Y873810D03*
X1404571Y870606D03*
X1397171D03*
X1411971D03*
X1408271Y883423D03*
X1406420Y880219D03*
X1400871Y883423D03*
X1399020Y880219D03*
X1404571Y883423D03*
X1397171D03*
X1411971D03*
X1397171Y896240D03*
X1402720Y899445D03*
X1404571Y896240D03*
X1410120Y899445D03*
X1399020Y893036D03*
X1400871Y896240D03*
X1406420Y893036D03*
X1408271Y896240D03*
X1411971D03*
X1410120Y886627D03*
X1402720D03*
X1405003Y1076587D03*
X1406853Y1079791D03*
X1401304Y1082995D03*
X1405003Y1089404D03*
X1399453Y1086200D03*
X1406853Y1092608D03*
X1399453D03*
X1397604Y1089404D03*
X1403154Y1086200D03*
X1406852D03*
X1403153Y1092608D03*
X1401304Y1095813D03*
X1413820Y848176D03*
X1428620Y867401D03*
X1421220D03*
X1413820D03*
X1424921Y860993D03*
X1421220Y854584D03*
X1417520Y860993D03*
X1428620Y854584D03*
X1426771Y857789D03*
X1423071D03*
X1419371D03*
X1413821Y854584D03*
X1424921Y873810D03*
X1423071Y870606D03*
X1417520Y873810D03*
X1415671Y870606D03*
X1426771D03*
X1419371D03*
X1428621Y880219D03*
X1423071Y883423D03*
X1421220Y880219D03*
X1415671Y883423D03*
X1413820Y880219D03*
X1426771Y883423D03*
X1419371D03*
X1413820Y893036D03*
X1421220Y899445D03*
X1419371Y896240D03*
X1424920Y899445D03*
X1426772Y896240D03*
X1417520Y899445D03*
X1421220Y893036D03*
X1423071Y896240D03*
X1428621Y893036D03*
X1424920Y886627D03*
X1417520D03*
X1443420Y867401D03*
X1436020D03*
X1445271Y857789D03*
X1439720Y860993D03*
X1437871Y857789D03*
X1432320Y860993D03*
X1430471Y857789D03*
X1443420Y854584D03*
X1441571Y857789D03*
X1436020Y854584D03*
X1434171Y857789D03*
X1445271Y870606D03*
X1439720Y873810D03*
X1437871Y870606D03*
X1432320Y873810D03*
X1430471Y870606D03*
X1441571D03*
X1434171D03*
X1445271Y883423D03*
X1443420Y880219D03*
X1437871Y883423D03*
X1436020Y880219D03*
X1430471Y883423D03*
X1441571D03*
X1434171D03*
X1430471Y896240D03*
X1436020Y893036D03*
X1437871Y896240D03*
X1441571D03*
X1432320Y899445D03*
X1434171Y896240D03*
X1439720Y899445D03*
X1443420Y893036D03*
X1439720Y886627D03*
X1432320D03*
X1450820Y867401D03*
X1458220D03*
X1460071Y857789D03*
X1454520Y860993D03*
X1452671Y857789D03*
X1447120Y860993D03*
X1458220Y854584D03*
X1456371Y857789D03*
X1450820Y854584D03*
X1448971Y857789D03*
X1456371Y870606D03*
X1452671D03*
X1454520Y873810D03*
X1460071Y870606D03*
X1450820Y880219D03*
X1452671Y883423D03*
X1458220Y880219D03*
X1460071Y883423D03*
X1448971D03*
X1456371D03*
X1458220Y893036D03*
X1460071Y896240D03*
X1447120Y886627D03*
X1454520D03*
X1460071Y915466D03*
Y934691D03*
Y953917D03*
Y973143D03*
X1460504Y1006093D03*
Y1025318D03*
Y1044544D03*
Y1063770D03*
Y1082995D03*
Y1121447D03*
X1456804Y1127856D03*
X1453104Y1121447D03*
X1449404Y1127856D03*
X1445704Y1121447D03*
X1458653Y1124651D03*
X1454953D03*
X1451253D03*
X1447553D03*
X1460504Y1134264D03*
X1458654Y1137469D03*
X1453104Y1134264D03*
X1451254Y1137469D03*
X1456803Y1140973D03*
X1454954Y1137469D03*
X1449403Y1140973D03*
X1465620Y867401D03*
X1473020D03*
X1467471Y857789D03*
X1461920Y860993D03*
X1476720D03*
X1474871Y857789D03*
X1471171D03*
X1465620Y854584D03*
X1463771Y857789D03*
X1473020Y854584D03*
X1469320Y860993D03*
X1463771Y870606D03*
X1471171D03*
X1461920Y873810D03*
X1467471Y870606D03*
X1469320Y873810D03*
X1474871Y870606D03*
X1476720Y873810D03*
X1465620Y880219D03*
X1467471Y883423D03*
X1473020Y880219D03*
X1474871Y883423D03*
X1463771D03*
X1471171D03*
X1476720Y899445D03*
X1461920D03*
X1469320D03*
Y893036D03*
X1473020D03*
X1461920D03*
X1467471Y896240D03*
X1463771D03*
X1471171D03*
X1461920Y886627D03*
X1469320D03*
X1476720D03*
X1461920Y912262D03*
X1463771Y909057D03*
X1469320Y912262D03*
X1467471Y909057D03*
X1476720Y912262D03*
X1474871Y909057D03*
Y902649D03*
X1463771D03*
X1467471D03*
X1463771Y915466D03*
X1476720Y905853D03*
X1471171Y915466D03*
X1473020Y905853D03*
X1467471Y915466D03*
X1476720Y931488D03*
X1474871Y921875D03*
X1476720Y918670D03*
X1474871Y928283D03*
X1473020Y925079D03*
X1476720D03*
X1467471Y921875D03*
X1469320Y918670D03*
X1461920Y931488D03*
X1467471Y928283D03*
X1469320Y931488D03*
X1463771Y928283D03*
Y921875D03*
X1461920Y918670D03*
X1474871Y947509D03*
Y941100D03*
X1476720Y937896D03*
X1473020Y944304D03*
X1476720D03*
X1463771Y947509D03*
X1467471D03*
X1463771Y941100D03*
X1461920Y937896D03*
X1467471Y941100D03*
X1469320Y937896D03*
X1463771Y934691D03*
X1471171D03*
X1467471D03*
X1476720Y950713D03*
X1463771Y966735D03*
X1467471D03*
X1474871D03*
X1473020Y963530D03*
X1461920Y950713D03*
X1469320D03*
X1467471Y960326D03*
X1469320Y957122D03*
X1463771Y960326D03*
X1461920Y957122D03*
X1476720D03*
X1474871Y960326D03*
X1471171Y953917D03*
X1463771D03*
X1467471D03*
X1463771Y979552D03*
X1461920Y976347D03*
X1467471Y979552D03*
X1469320Y976347D03*
X1476720Y982756D03*
X1473020D03*
X1474871Y979552D03*
X1476720Y976347D03*
X1471171Y973143D03*
X1463771D03*
X1467471D03*
X1461920Y969939D03*
X1469320D03*
X1476720D03*
X1477153Y1002888D03*
X1475304Y999684D03*
Y1012501D03*
X1477153Y1009297D03*
X1471604Y1006093D03*
X1462353Y1002888D03*
X1469753D03*
X1464204Y999684D03*
X1467904D03*
X1467903Y1012501D03*
X1469753Y1009297D03*
X1464204Y1012501D03*
X1462353Y1009297D03*
X1473453Y1015705D03*
X1475304Y1031727D03*
X1477153Y1028523D03*
Y1022114D03*
X1475304Y1018910D03*
X1464204Y1031727D03*
X1462353Y1028523D03*
X1467904Y1031727D03*
X1469753Y1028523D03*
X1462353Y1022114D03*
X1464204Y1018910D03*
X1469753Y1022114D03*
X1467904Y1018910D03*
X1464204Y1025318D03*
X1471604D03*
X1467904D03*
X1477153Y1041340D03*
X1475304Y1038136D03*
X1477153Y1047749D03*
Y1034931D03*
X1473453D03*
X1462353Y1047749D03*
X1469753D03*
X1462353Y1041340D03*
X1464204Y1038136D03*
X1469753Y1041340D03*
X1467904Y1038136D03*
X1464204Y1044544D03*
X1471604D03*
X1467904D03*
X1477153Y1060565D03*
X1475304Y1057361D03*
Y1050952D03*
X1477153Y1054157D03*
X1473453D03*
X1462353Y1060565D03*
X1464204Y1057361D03*
X1469753Y1060565D03*
X1467904Y1057361D03*
X1464204Y1050952D03*
X1467904D03*
X1464204Y1063770D03*
X1471604D03*
X1467904D03*
X1475304Y1070178D03*
X1477153Y1066974D03*
Y1079791D03*
X1475304Y1076587D03*
X1473453Y1073383D03*
X1477153D03*
X1462353Y1079791D03*
X1464204Y1076587D03*
X1469753Y1079791D03*
X1467904Y1076587D03*
X1464204Y1070178D03*
X1462353Y1066974D03*
X1467904Y1070178D03*
X1469753Y1066974D03*
X1467904Y1089404D03*
X1469753Y1086200D03*
X1475304Y1089404D03*
X1477153Y1086200D03*
X1464204Y1089404D03*
X1462353Y1086200D03*
X1473453Y1092608D03*
X1471604Y1082995D03*
X1477153Y1092608D03*
X1464204Y1082995D03*
X1467904D03*
X1464204Y1127856D03*
X1475304Y1121447D03*
X1471604Y1127856D03*
X1467904Y1121447D03*
X1466053Y1124651D03*
X1462353D03*
X1477153D03*
X1473453D03*
X1469753D03*
X1469754Y1137469D03*
X1464203Y1140973D03*
X1477154Y1137469D03*
X1471603Y1140973D03*
X1467904Y1134264D03*
X1466054Y1137469D03*
X1462354D03*
X1475304Y1134264D03*
X1473454Y1137469D03*
X1487820Y867401D03*
X1480420D03*
X1491520Y860993D03*
X1489671Y857789D03*
X1484120Y860993D03*
X1482271Y857789D03*
X1493371D03*
X1487820Y854584D03*
X1485971Y857789D03*
X1480420Y854584D03*
X1478571Y857789D03*
X1493371Y870606D03*
X1478571D03*
X1485971D03*
X1489671D03*
X1491520Y873810D03*
X1482271Y870606D03*
X1484120Y873810D03*
X1487820Y880219D03*
X1489671Y883423D03*
X1480420Y880219D03*
X1482271Y883423D03*
X1485971D03*
X1493371D03*
X1478571D03*
X1487820Y899445D03*
Y893036D03*
X1484120D03*
X1485971Y896240D03*
X1493371D03*
X1489671D03*
X1480420Y899445D03*
X1491520Y886627D03*
X1484120D03*
X1489671Y902649D03*
X1493371D03*
X1487820Y912262D03*
X1489671Y909057D03*
X1493371D03*
X1489671Y915466D03*
X1485971D03*
X1493371D03*
X1480420Y912262D03*
X1482271Y909057D03*
Y902649D03*
X1484120Y905853D03*
X1480420D03*
X1487820Y931488D03*
X1489671Y928283D03*
X1493371D03*
X1482271D03*
Y921875D03*
X1480420Y918670D03*
X1489671Y921875D03*
X1487820Y918670D03*
X1493371Y921875D03*
X1480420Y931488D03*
Y925079D03*
X1484120D03*
X1489671Y941100D03*
X1487820Y937896D03*
X1493371Y941100D03*
X1489671Y934691D03*
X1485971D03*
X1493371D03*
X1489671Y947509D03*
X1493371D03*
X1482271D03*
Y941100D03*
X1480420Y937896D03*
X1484120Y944304D03*
X1480420D03*
X1487820Y950713D03*
X1489671Y960326D03*
X1487820Y957122D03*
X1493371Y960326D03*
Y966735D03*
X1489671D03*
X1480420Y950713D03*
X1489671Y953917D03*
X1493371D03*
X1485971D03*
X1482271Y966735D03*
X1480420Y957122D03*
X1482271Y960326D03*
X1484120Y963530D03*
Y982756D03*
X1480420D03*
Y976347D03*
X1482271Y979552D03*
X1489671D03*
X1493371D03*
X1487820Y976347D03*
X1485971Y973143D03*
X1487820Y969939D03*
X1480420D03*
X1493804Y1006093D03*
X1490104D03*
X1486404D03*
X1493804Y1012501D03*
X1480853Y1002888D03*
X1482703Y999684D03*
X1490104Y1012501D03*
X1488253Y1009297D03*
X1482704Y1012501D03*
X1480853Y1009297D03*
X1493803Y999684D03*
X1488253Y1002888D03*
X1490104Y999684D03*
Y1031727D03*
X1488253Y1028523D03*
X1493804Y1031727D03*
X1488253Y1022114D03*
X1490104Y1018910D03*
X1493804D03*
X1490104Y1025318D03*
X1486404D03*
X1493804D03*
X1484553Y1015705D03*
X1482704Y1031727D03*
X1480853Y1028523D03*
Y1022114D03*
X1482704Y1018910D03*
X1480853Y1041340D03*
X1482704Y1038136D03*
X1488253Y1047749D03*
Y1041340D03*
X1490104Y1038136D03*
X1493804D03*
X1480853Y1047749D03*
X1486404Y1044544D03*
X1484553Y1034931D03*
X1490104Y1044544D03*
X1493804D03*
X1480853Y1034931D03*
X1488253Y1060565D03*
X1490104Y1057361D03*
X1493804D03*
X1486404Y1063770D03*
X1490104D03*
X1493804D03*
X1490104Y1050952D03*
X1493804D03*
X1480853Y1060565D03*
X1482704Y1057361D03*
Y1050952D03*
X1484553Y1054157D03*
X1480853D03*
X1493804Y1070178D03*
X1490104D03*
X1488253Y1066974D03*
X1480853Y1079791D03*
X1482704Y1076587D03*
Y1070178D03*
X1480853Y1066974D03*
X1488253Y1079791D03*
X1490104Y1076587D03*
X1493804D03*
X1484553Y1073383D03*
X1480853D03*
X1490104Y1089404D03*
X1488253Y1086200D03*
X1493804Y1089404D03*
X1490104Y1082995D03*
X1486404D03*
X1493804D03*
X1486404Y1095813D03*
X1482703D03*
X1482704Y1089404D03*
X1480853Y1086200D03*
X1484553Y1092608D03*
X1480853D03*
X1493804Y1102221D03*
X1491953Y1099017D03*
X1493804Y1127856D03*
X1490104Y1121447D03*
X1486404Y1127856D03*
X1482704Y1121447D03*
X1479004Y1127856D03*
X1491953Y1124651D03*
X1488253D03*
X1484553D03*
X1480853D03*
X1493803Y1140973D03*
X1490104Y1134264D03*
X1488254Y1137469D03*
X1482704Y1134264D03*
X1480854Y1137469D03*
X1491954D03*
X1486403Y1140973D03*
X1484554Y1137469D03*
X1479003Y1140973D03*
X1508171Y864197D03*
X1510021Y854584D03*
X1495220Y867401D03*
X1502621D03*
X1504471Y857789D03*
X1498920Y860993D03*
X1497071Y857789D03*
X1502620Y854584D03*
X1500771Y857789D03*
X1495220Y854584D03*
X1500771Y870606D03*
X1508171D03*
X1497071D03*
X1498920Y873810D03*
X1504471Y870606D03*
X1506321Y873810D03*
X1495220Y880219D03*
X1497071Y883423D03*
X1502621Y880219D03*
X1504471Y883423D03*
X1500771D03*
X1502621Y899445D03*
X1506320D03*
X1495220D03*
Y893036D03*
X1498920D03*
X1497071Y896240D03*
X1498920Y886627D03*
X1506321D03*
Y912262D03*
X1508171Y909057D03*
X1500771Y902649D03*
X1508171D03*
X1502621Y912262D03*
X1500771Y909057D03*
X1502621Y905853D03*
X1510021D03*
X1498920D03*
X1506321D03*
X1495220Y912262D03*
X1497071Y915466D03*
X1502621Y931488D03*
X1500771Y928283D03*
X1506321Y931488D03*
X1508171Y928283D03*
X1500771Y921875D03*
X1502621Y918670D03*
X1508171Y921875D03*
X1506321Y918670D03*
X1502621Y925079D03*
X1510021D03*
X1498920D03*
X1506321D03*
X1495220Y931488D03*
Y918670D03*
X1500771Y941100D03*
X1502621Y937896D03*
X1508171Y941100D03*
X1506321Y937896D03*
X1500771Y947509D03*
X1508171D03*
X1495220Y937896D03*
X1510021Y944304D03*
X1497071Y934691D03*
X1502621Y944304D03*
X1506320D03*
X1498920D03*
X1500771Y966735D03*
X1508171D03*
X1498920Y963530D03*
X1502621Y950713D03*
X1506320D03*
X1508171Y960326D03*
X1506320Y957122D03*
X1500771Y960326D03*
X1502621Y957122D03*
X1510021Y963530D03*
X1495220Y950713D03*
Y957122D03*
X1497071Y953917D03*
X1502621Y969939D03*
X1506321D03*
X1495220Y976347D03*
Y969939D03*
X1497071Y973143D03*
X1497504Y1006093D03*
X1501204Y1012501D03*
X1508603D03*
X1503053Y1009297D03*
X1506753D03*
X1495653D03*
X1495655Y1002888D03*
X1506753D03*
X1508603Y999684D03*
X1503053Y1002888D03*
X1501204Y999684D03*
X1499353Y1015705D03*
X1510453D03*
X1501204Y1031727D03*
X1503053Y1028523D03*
X1508603Y1031727D03*
X1506753Y1028523D03*
Y1022114D03*
X1508603Y1018910D03*
X1503053Y1022114D03*
X1501204Y1018910D03*
X1495653Y1028523D03*
Y1022114D03*
X1497504Y1025318D03*
X1503053Y1041340D03*
X1501204Y1038136D03*
X1506753Y1041340D03*
X1508603Y1038136D03*
X1503053Y1047749D03*
X1506753D03*
X1503053Y1034931D03*
X1510453D03*
X1499353D03*
X1506753D03*
X1495653Y1047749D03*
Y1041340D03*
X1497504Y1044544D03*
X1495653Y1060565D03*
X1503053D03*
X1501204Y1057361D03*
X1506753Y1060565D03*
X1508604Y1057361D03*
X1501203Y1050952D03*
X1508604Y1050953D03*
X1499353Y1054157D03*
X1497504Y1063770D03*
X1510453Y1054157D03*
X1503053D03*
X1506753D03*
Y1079791D03*
X1508604Y1076587D03*
X1501204Y1070178D03*
X1503053Y1066974D03*
X1508604Y1070178D03*
X1506753Y1066974D03*
X1503053Y1079791D03*
X1501204Y1076587D03*
X1499353Y1073383D03*
X1510453D03*
X1503053D03*
X1506753D03*
X1495653Y1066974D03*
Y1079791D03*
X1497504Y1095813D03*
X1508603D03*
X1501204D03*
Y1089404D03*
X1503053Y1086200D03*
X1508604Y1089404D03*
X1506753Y1086200D03*
X1503053Y1092608D03*
X1510452D03*
X1499353D03*
X1506753D03*
X1495653Y1086200D03*
X1497504Y1082995D03*
X1506753Y1099017D03*
X1503053Y1124651D03*
X1497504Y1121447D03*
X1501204Y1127856D03*
X1499353Y1124651D03*
X1495653D03*
X1508604Y1134264D03*
X1501203Y1140973D03*
X1499354Y1137469D03*
X1510454D03*
X1503054D03*
X1497504Y1134264D03*
X1495654Y1137469D03*
X1519271Y851380D03*
X1515571D03*
X1511871Y864197D03*
X1519270D03*
X1522970D03*
X1511871Y857789D03*
X1519271D03*
X1515571D03*
X1517421Y860993D03*
Y854584D03*
X1515571Y883423D03*
X1513720Y880219D03*
X1519271Y883423D03*
X1521121Y880219D03*
X1513720Y873810D03*
X1515571Y870606D03*
X1521121Y873810D03*
X1519271Y870606D03*
X1515570Y877014D03*
X1522970D03*
X1511871D03*
X1519271D03*
X1596941Y883924D03*
Y890617D03*
Y897310D03*
Y900656D03*
Y914042D03*
Y907349D03*
Y960892D03*
Y957546D03*
Y1185105D03*
Y1178412D03*
Y1191798D03*
Y1208530D03*
Y1201837D03*
Y1195144D03*
X1613083Y880577D03*
Y887270D03*
Y897310D03*
Y893963D03*
Y910696D03*
Y904003D03*
Y1175066D03*
Y1181759D03*
Y1191798D03*
Y1188451D03*
Y1205184D03*
Y1198491D03*
X1626641Y960892D03*
Y957546D03*
X1656441Y780184D03*
Y773491D03*
Y786877D03*
Y803609D03*
Y796916D03*
Y790223D03*
Y816995D03*
Y810302D03*
Y833727D03*
Y823688D03*
Y827034D03*
Y847113D03*
Y840420D03*
Y853806D03*
Y860499D03*
Y863845D03*
Y883924D03*
Y877231D03*
Y870538D03*
Y890617D03*
Y897310D03*
Y900656D03*
Y914042D03*
Y907349D03*
Y927428D03*
Y920735D03*
Y934121D03*
Y944160D03*
Y937467D03*
Y960892D03*
Y950853D03*
Y957546D03*
Y980971D03*
Y974278D03*
Y967585D03*
Y994357D03*
Y987664D03*
X1656141Y1027822D03*
X1656441Y1021129D03*
X1656141Y1047900D03*
Y1041207D03*
Y1034514D03*
Y1054593D03*
X1656441Y1074672D03*
Y1067979D03*
Y1091404D03*
Y1081365D03*
Y1084711D03*
Y1098097D03*
Y1111483D03*
Y1104790D03*
Y1128215D03*
Y1118176D03*
Y1121522D03*
Y1141601D03*
Y1134908D03*
Y1148294D03*
Y1154987D03*
Y1158333D03*
Y1171719D03*
Y1165026D03*
Y1185105D03*
Y1178412D03*
Y1191798D03*
Y1208530D03*
Y1201837D03*
Y1195144D03*
Y1221916D03*
Y1215223D03*
Y1238648D03*
Y1228609D03*
Y1231955D03*
Y1245341D03*
X1672583Y770144D03*
Y776837D03*
Y786877D03*
Y783530D03*
Y800263D03*
Y793570D03*
Y813648D03*
Y806955D03*
Y820341D03*
Y830381D03*
Y823688D03*
Y850459D03*
Y843766D03*
Y837074D03*
Y867192D03*
Y860499D03*
Y857152D03*
Y873885D03*
Y880577D03*
Y887270D03*
Y897310D03*
Y893963D03*
Y917389D03*
Y910696D03*
Y904003D03*
Y924081D03*
Y934121D03*
Y930774D03*
Y947507D03*
Y940814D03*
Y964239D03*
Y977625D03*
Y970932D03*
Y991011D03*
Y984318D03*
Y1021129D03*
Y1024475D03*
Y1031168D03*
X1672283Y1044554D03*
Y1037861D03*
X1672583Y1051247D03*
Y1071325D03*
Y1064633D03*
Y1078018D03*
Y1094751D03*
Y1088058D03*
Y1081365D03*
Y1108136D03*
Y1101444D03*
Y1124869D03*
Y1118176D03*
Y1114829D03*
Y1144947D03*
Y1138255D03*
Y1131562D03*
Y1161680D03*
Y1154987D03*
Y1151640D03*
Y1175066D03*
Y1168373D03*
Y1181758D03*
Y1191798D03*
Y1188451D03*
Y1205184D03*
Y1198491D03*
Y1218569D03*
Y1211877D03*
Y1225262D03*
Y1241995D03*
Y1235302D03*
Y1228609D03*
X1686041Y960892D03*
Y957546D03*
X1686141Y967585D03*
Y1054593D03*
X1702283Y964239D03*
Y1021129D03*
Y1024475D03*
Y1051247D03*
X1715841Y780184D03*
Y773491D03*
Y786877D03*
Y803609D03*
Y796916D03*
Y790223D03*
Y816995D03*
Y810302D03*
Y833727D03*
Y823688D03*
Y827034D03*
Y847113D03*
Y840420D03*
Y853806D03*
Y860499D03*
Y863845D03*
Y883924D03*
Y877231D03*
Y870538D03*
Y890617D03*
Y897310D03*
Y900656D03*
Y914042D03*
Y907349D03*
Y927428D03*
Y920735D03*
Y934121D03*
Y944160D03*
Y937467D03*
Y960892D03*
Y950853D03*
Y957546D03*
Y980971D03*
Y974278D03*
Y967585D03*
Y994357D03*
Y987664D03*
Y1027822D03*
Y1021129D03*
Y1047900D03*
Y1041207D03*
Y1034514D03*
Y1054593D03*
Y1074672D03*
Y1067979D03*
Y1091404D03*
Y1081365D03*
Y1084711D03*
Y1098097D03*
Y1111483D03*
Y1104790D03*
Y1128215D03*
Y1118176D03*
Y1121522D03*
Y1141601D03*
Y1134908D03*
Y1148294D03*
Y1154987D03*
Y1158333D03*
Y1171719D03*
Y1165026D03*
Y1185105D03*
Y1178412D03*
Y1191798D03*
Y1208530D03*
Y1201837D03*
Y1195144D03*
Y1221916D03*
Y1215223D03*
Y1238648D03*
Y1228609D03*
Y1231955D03*
Y1245341D03*
X1731983Y770144D03*
Y776837D03*
Y786877D03*
Y783530D03*
Y800263D03*
Y793570D03*
Y813648D03*
Y806955D03*
Y820341D03*
Y830381D03*
Y823688D03*
Y850459D03*
Y843766D03*
Y837074D03*
Y867192D03*
Y860499D03*
Y857152D03*
Y873885D03*
Y880577D03*
Y887270D03*
Y897310D03*
Y893963D03*
Y917389D03*
Y910696D03*
Y904003D03*
Y924081D03*
Y934121D03*
Y930774D03*
Y947507D03*
Y940814D03*
Y964239D03*
Y977625D03*
X1731883Y970932D03*
X1731983Y991011D03*
Y984318D03*
Y1021129D03*
Y1024475D03*
Y1031168D03*
X1731683Y1044554D03*
Y1037861D03*
X1731983Y1051247D03*
X1731818Y1071326D03*
X1731883Y1064633D03*
X1731983Y1078018D03*
Y1094751D03*
Y1088058D03*
Y1081365D03*
X1731818Y1108137D03*
X1731983Y1101444D03*
Y1124869D03*
Y1118176D03*
Y1114829D03*
Y1144947D03*
Y1138255D03*
Y1131562D03*
Y1161680D03*
Y1154987D03*
Y1151640D03*
Y1175066D03*
Y1168373D03*
X1731818Y1181759D03*
X1731983Y1191798D03*
X1731818Y1188452D03*
X1731983Y1205184D03*
Y1198491D03*
Y1218569D03*
Y1211877D03*
Y1225262D03*
Y1241995D03*
Y1235302D03*
Y1228609D03*
X1745541Y960892D03*
Y957546D03*
Y967585D03*
Y1054593D03*
X1761683Y964239D03*
Y1021129D03*
Y1024475D03*
Y1051247D03*
X1775241Y780184D03*
Y773491D03*
Y786877D03*
Y803609D03*
Y796916D03*
Y790223D03*
Y816995D03*
Y810302D03*
Y833727D03*
Y823688D03*
Y827034D03*
Y847113D03*
Y840420D03*
Y853806D03*
Y860499D03*
Y863845D03*
Y883924D03*
Y877231D03*
Y870538D03*
Y890617D03*
Y897310D03*
Y900656D03*
Y914042D03*
Y907349D03*
Y927428D03*
Y920735D03*
Y934121D03*
Y944160D03*
Y937467D03*
Y960892D03*
Y950853D03*
Y957546D03*
Y980971D03*
Y974278D03*
Y967585D03*
Y994357D03*
Y987664D03*
Y1027822D03*
Y1021129D03*
Y1047900D03*
Y1041207D03*
Y1034515D03*
Y1054593D03*
Y1074672D03*
Y1067979D03*
Y1091404D03*
Y1081365D03*
Y1084711D03*
Y1098097D03*
Y1111483D03*
Y1104790D03*
Y1128215D03*
Y1118176D03*
Y1121522D03*
Y1141601D03*
Y1134908D03*
Y1148294D03*
Y1154987D03*
Y1158333D03*
Y1171719D03*
Y1165026D03*
Y1185105D03*
Y1178412D03*
Y1191798D03*
Y1208530D03*
Y1201837D03*
Y1195144D03*
Y1221916D03*
Y1215223D03*
Y1238648D03*
Y1228609D03*
Y1231955D03*
Y1245341D03*
X1791383Y770144D03*
Y776837D03*
Y786877D03*
Y783530D03*
Y800263D03*
Y793570D03*
Y813648D03*
Y806955D03*
Y820341D03*
Y830381D03*
Y823688D03*
Y850459D03*
Y843766D03*
Y837074D03*
Y867192D03*
Y860499D03*
Y857152D03*
Y873885D03*
Y880577D03*
Y887270D03*
Y897310D03*
Y893963D03*
Y917389D03*
Y910696D03*
Y904003D03*
Y924081D03*
Y934121D03*
Y930774D03*
Y947507D03*
Y940814D03*
Y964239D03*
Y977625D03*
Y970932D03*
Y991011D03*
Y984318D03*
Y1021129D03*
Y1024475D03*
Y1031168D03*
Y1044554D03*
Y1037861D03*
X1791083Y1051247D03*
X1791383Y1071325D03*
Y1064633D03*
Y1078018D03*
Y1094751D03*
Y1088058D03*
Y1081365D03*
Y1108136D03*
Y1101444D03*
Y1124869D03*
Y1118176D03*
Y1114829D03*
Y1144947D03*
Y1138255D03*
Y1131562D03*
Y1161680D03*
Y1154987D03*
Y1151640D03*
Y1175066D03*
Y1168373D03*
Y1181758D03*
Y1191798D03*
Y1188451D03*
Y1205184D03*
Y1198491D03*
Y1218570D03*
Y1211877D03*
Y1225263D03*
Y1241995D03*
Y1235302D03*
Y1228609D03*
X1804941Y960892D03*
Y957546D03*
Y967585D03*
Y1054593D03*
X1821083Y964239D03*
Y1021129D03*
Y1024475D03*
Y1051247D03*
G54D49*
X676508Y145866D03*
G54D35*
X238780Y1643661D03*
X230906Y1649173D03*
X238780Y1653110D03*
Y1657834D03*
X230906Y1653897D03*
Y1663346D03*
X238780Y1667283D03*
Y1672007D03*
X230906Y1668070D03*
Y1734212D03*
X254528Y1643661D03*
X246654Y1649173D03*
X254528Y1653110D03*
Y1657834D03*
X246654Y1653897D03*
Y1663346D03*
X254528Y1667283D03*
Y1672007D03*
X246654Y1668070D03*
Y1734212D03*
X270276Y1643661D03*
X262402Y1649173D03*
Y1653897D03*
Y1663346D03*
X270276Y1667283D03*
Y1672007D03*
X262402Y1668070D03*
Y1734212D03*
X286024Y1643661D03*
X278150Y1649173D03*
Y1653897D03*
Y1663346D03*
Y1668070D03*
Y1734212D03*
X305709Y1672007D03*
X297835Y1734212D03*
X321457Y1672007D03*
X313583Y1734212D03*
X337205Y1672007D03*
X329331Y1734212D03*
X352953Y1672007D03*
X345079Y1734212D03*
X495079D03*
X502953Y1672007D03*
X510827Y1734212D03*
X518701Y1672007D03*
X534449D03*
X526575Y1734212D03*
X550197Y1672007D03*
X542323Y1734212D03*
X562008D03*
X569882Y1672007D03*
X577756Y1734212D03*
X585630Y1672007D03*
X593504Y1734212D03*
X601378Y1672007D03*
X609252Y1734212D03*
X617126Y1672007D03*
X1246654D03*
X1238780Y1734212D03*
X1262402Y1672007D03*
X1254528Y1734212D03*
X1278150Y1672007D03*
X1270276Y1734212D03*
X1293898Y1672007D03*
X1286024Y1734212D03*
X1313583Y1672007D03*
X1305709Y1734212D03*
X1329331Y1672007D03*
X1321457Y1734212D03*
X1345079Y1672007D03*
X1337205Y1734212D03*
X1360827Y1672007D03*
X1352953Y1734212D03*
X1510827Y1672007D03*
X1502953Y1734212D03*
X1526575Y1672007D03*
X1518701Y1734212D03*
X1542323Y1672007D03*
X1534449Y1734212D03*
X1558071Y1672007D03*
X1550197Y1734212D03*
X1569882D03*
X1577756Y1672007D03*
X1585630Y1734212D03*
X1593504Y1672007D03*
X1601378Y1734212D03*
X1609252Y1672007D03*
X1617126Y1734212D03*
X1625000Y1672007D03*
G54D76*
X1886720Y1001463D03*
X1876720D03*
X1875836Y1303980D03*
X1885836D03*
X1886211Y1364167D03*
X1876211D03*
X1876165Y1669023D03*
X1886165D03*
X1897608Y1001506D03*
X1898086Y1305044D03*
X1897682Y1364479D03*
X1897402Y1670072D03*
X1907608Y1001506D03*
X1908086Y1305044D03*
X1907682Y1364479D03*
X1907402Y1670072D03*
X1935200Y1362732D03*
X1925200D03*
X1924695Y1670036D03*
X1934695D03*
X1946178Y1362781D03*
X1945484Y1670313D03*
X1967697Y1362790D03*
X1956178Y1362781D03*
X1966555Y1669946D03*
X1955484Y1670313D03*
X1977697Y1362790D03*
X1976555Y1669946D03*
X1988618Y1363081D03*
X1998618D03*
X1998147Y1669691D03*
X1988147D03*
G54D26*
X61157Y69340D03*
X61470Y84622D03*
X62812Y412708D03*
X62813Y415750D03*
X78269Y26474D03*
X74869D03*
X64557Y69340D03*
X72157Y75340D03*
X75557D03*
X64870Y84622D03*
X78120Y1515436D03*
Y1518836D03*
X76369Y1507456D03*
X75922Y1558974D03*
Y1562374D03*
X77618Y1572504D03*
X74218D03*
X85374Y19538D03*
X81974D03*
X92442Y26474D03*
X89042D03*
X86557Y69340D03*
X83157D03*
X94157Y75340D03*
X90998Y1518937D03*
Y1515537D03*
X89264Y1507611D03*
X92664D03*
X79769Y1507456D03*
X99547Y19538D03*
X110320D03*
X96147D03*
X106615Y26474D03*
X103215D03*
X108557Y69340D03*
X105157D03*
X97557Y75340D03*
X102251Y1576504D03*
X105651D03*
X113720Y19538D03*
X127894D03*
X124494D03*
X120789Y26474D03*
X117389D03*
X127157Y69340D03*
X116157Y75340D03*
X119557D03*
X130557Y69340D03*
X138157Y75340D03*
X141557D03*
X160360Y19538D03*
X156655Y26474D03*
X153255D03*
X152557Y69340D03*
X149157D03*
X145538Y1517374D03*
X148938D03*
X146312Y1569525D03*
X149712D03*
X163760Y19538D03*
X174533D03*
X170828Y26474D03*
X167428D03*
X175761Y69340D03*
X172361D03*
X161361Y75340D03*
X164761D03*
X164710Y1518014D03*
X168110D03*
X167266Y1569968D03*
X170666D03*
X177933Y19538D03*
X183361Y75340D03*
X186761D03*
X188897Y1578182D03*
X192297D03*
X188897Y1590094D03*
X192297D03*
X207894Y19538D03*
X204494D03*
X200789Y26474D03*
X197389D03*
X197761Y69340D03*
X194361D03*
X205495Y75340D03*
X208895D03*
X200957Y1578182D03*
X204357D03*
X200957Y1590094D03*
X204357D03*
X194197Y1614292D03*
X197597D03*
X206257D03*
X194197Y1602380D03*
X197597D03*
X206257D03*
X222067Y19538D03*
X218667D03*
X214962Y26474D03*
X211562D03*
X219895Y69340D03*
X216495D03*
X225077Y1578182D03*
X213017D03*
X216417D03*
X225077Y1590094D03*
X213017D03*
X216417D03*
X209657Y1614292D03*
X218317D03*
X221717D03*
X209657Y1602380D03*
X218317D03*
X221717D03*
X227495Y75340D03*
X230895D03*
X237137Y1578182D03*
X240537D03*
X228477D03*
X237137Y1590094D03*
X240537D03*
X228477D03*
X230377Y1614292D03*
X233777D03*
X230377Y1602380D03*
X233777D03*
X249197Y1578182D03*
X252597D03*
X249197Y1590094D03*
X252597D03*
X242437Y1614292D03*
X254497D03*
X245837D03*
X242437Y1602380D03*
X254497D03*
X245837D03*
X273317Y1578182D03*
X261257D03*
X264657D03*
X273317Y1590094D03*
X261257D03*
X264657D03*
X266557Y1614292D03*
X257897D03*
X269957D03*
X266557Y1602380D03*
X257897D03*
X269957D03*
X285377Y1578182D03*
X288777D03*
X276717D03*
X285377Y1590094D03*
X288777D03*
X276717D03*
X278617Y1614292D03*
X282017D03*
X278617Y1602380D03*
X282017D03*
X297437Y1578182D03*
X300837D03*
X297437Y1590094D03*
X300837D03*
X290677Y1614292D03*
X302737D03*
X294077D03*
X306137D03*
X290677Y1602380D03*
X302737D03*
X294077D03*
X306137D03*
X321557Y1578182D03*
X309497D03*
X312897D03*
X321557Y1590094D03*
X309497D03*
X312897D03*
X314797Y1614292D03*
X318197D03*
X314797Y1602380D03*
X318197D03*
X333617Y1578182D03*
X337017D03*
X324957D03*
X333617Y1590094D03*
X337017D03*
X324957D03*
X330257Y1614292D03*
X338917D03*
X326857D03*
X330257Y1602380D03*
X338917D03*
X326857D03*
X345677Y1578182D03*
X349077D03*
X345677Y1590094D03*
X349077D03*
X350977Y1614292D03*
X342317D03*
X354377D03*
X350977Y1602380D03*
X342317D03*
X354377D03*
X369797Y1578182D03*
X357737D03*
X361137D03*
X369797Y1590094D03*
X357737D03*
X361137D03*
X363037Y1614292D03*
X366437D03*
X363037Y1602380D03*
X366437D03*
X373197Y1578182D03*
Y1590094D03*
X375097Y1614292D03*
X378497D03*
X375097Y1602380D03*
X378497D03*
X402590Y1618952D03*
X419780Y1602802D03*
X405990Y1618952D03*
X423180Y1602802D03*
X476451Y1578182D03*
X485111D03*
X473051D03*
X476451Y1590094D03*
X485111D03*
X473051D03*
X478351Y1614292D03*
X481751D03*
X478351Y1602380D03*
X481751D03*
X500571Y1578182D03*
X488511D03*
X497171D03*
X500571Y1590094D03*
X488511D03*
X497171D03*
X490411Y1614292D03*
X493811D03*
X490411Y1602380D03*
X493811D03*
X512631Y1578182D03*
X509231D03*
X512631Y1590094D03*
X509231D03*
X514531Y1614292D03*
X502471D03*
X517931D03*
X505871D03*
X514531Y1602380D03*
X502471D03*
X517931D03*
X505871D03*
X519764Y40328D03*
X523164D03*
X519742Y71436D03*
X523142D03*
X524691Y1578182D03*
X533351D03*
X521291D03*
X524691Y1590094D03*
X533351D03*
X521291D03*
X526591Y1614292D03*
X529991D03*
X526591Y1602380D03*
X529991D03*
X536751Y1578182D03*
X548811D03*
X545411D03*
X536751Y1590094D03*
X548811D03*
X545411D03*
X538651Y1614292D03*
X542051D03*
X538651Y1602380D03*
X542051D03*
X555175Y71436D03*
X558575D03*
X560871Y1578182D03*
X557471D03*
X560871Y1590094D03*
X557471D03*
X562771Y1614292D03*
X550711D03*
X566171D03*
X554111D03*
X562771Y1602380D03*
X550711D03*
X566171D03*
X554111D03*
X572931Y1578182D03*
X581591D03*
X569531D03*
X572931Y1590094D03*
X581591D03*
X569531D03*
X574831Y1614292D03*
X578231D03*
X574831Y1602380D03*
X578231D03*
X597051Y1578182D03*
X584991D03*
X593651D03*
X597051Y1590094D03*
X584991D03*
X593651D03*
X598951Y1614292D03*
X586891D03*
X590291D03*
X598951Y1602380D03*
X586891D03*
X590291D03*
X613970Y188752D03*
X609111Y1578182D03*
X605711D03*
X609111Y1590094D03*
X605711D03*
X611011Y1614292D03*
X614411D03*
X602351D03*
X611011Y1602380D03*
X614411D03*
X602351D03*
X617370Y188752D03*
X630040D03*
X626640D03*
X621171Y1578182D03*
X629831D03*
X617771D03*
X621171Y1590094D03*
X629831D03*
X617771D03*
X623071Y1614292D03*
X626471D03*
X623071Y1602380D03*
X626471D03*
X645291Y1578182D03*
X633231D03*
X641891D03*
X645291Y1590094D03*
X633231D03*
X641891D03*
X647191Y1614292D03*
X635131D03*
X638531D03*
X647191Y1602380D03*
X635131D03*
X638531D03*
X656439Y47264D03*
X659839D03*
X657351Y1578182D03*
X653951D03*
X657351Y1590094D03*
X653951D03*
X662651Y1614292D03*
X659251D03*
X650591D03*
X662651Y1602380D03*
X659251D03*
X650591D03*
X704770Y182999D03*
Y179599D03*
Y194810D03*
Y191410D03*
Y218432D03*
Y206621D03*
Y215032D03*
Y203221D03*
X723041Y-13200D03*
Y-9800D03*
X716698Y185687D03*
Y173687D03*
Y177087D03*
Y197187D03*
Y200587D03*
Y189087D03*
Y209021D03*
Y212421D03*
X840001Y20200D03*
Y16800D03*
X902350Y208294D03*
X907470Y211980D03*
X902350Y204894D03*
X907470Y215380D03*
X902350Y219068D03*
X907470Y226154D03*
X902350Y222468D03*
X907470Y229554D03*
X953970Y208275D03*
X947496Y215397D03*
X953970Y204875D03*
X947496Y211997D03*
X957156Y227163D03*
X947496Y226135D03*
X957156Y230563D03*
X947496Y229535D03*
X980899Y-13200D03*
Y-9800D03*
Y20200D03*
Y16800D03*
X1032433Y-23211D03*
Y-19811D03*
Y-3211D03*
Y189D03*
X1156770Y638192D03*
X1153370D03*
X1161860Y642112D03*
X1165260D03*
X1173220Y636052D03*
X1169820D03*
X1183360Y642062D03*
X1186760D03*
X1196772Y1578182D03*
X1200172D03*
X1196772Y1590094D03*
X1200172D03*
X1212232Y1578182D03*
X1208832D03*
X1212232Y1590094D03*
X1208832D03*
X1214132Y1614292D03*
X1202072D03*
X1217532D03*
X1205472D03*
X1214132Y1602380D03*
X1202072D03*
X1217532D03*
X1205472D03*
X1220892Y1578182D03*
X1232952D03*
X1224292D03*
X1220892Y1590094D03*
X1232952D03*
X1224292D03*
X1226192Y1614292D03*
X1229592D03*
X1226192Y1602380D03*
X1229592D03*
X1245012Y1578182D03*
X1236352D03*
X1248412D03*
X1245012Y1590094D03*
X1236352D03*
X1248412D03*
X1238252Y1614292D03*
X1241652D03*
X1238252Y1602380D03*
X1241652D03*
X1257072Y1578182D03*
X1260472D03*
X1257072Y1590094D03*
X1260472D03*
X1262372Y1614292D03*
X1250312D03*
X1265772D03*
X1253712D03*
X1262372Y1602380D03*
X1250312D03*
X1265772D03*
X1253712D03*
X1269132Y1578182D03*
X1281192D03*
X1272532D03*
X1269132Y1590094D03*
X1281192D03*
X1272532D03*
X1274432Y1614292D03*
X1277832D03*
X1274432Y1602380D03*
X1277832D03*
X1290291Y-23211D03*
Y-19811D03*
Y-3211D03*
Y189D03*
X1293252Y1578182D03*
X1284592D03*
X1296652D03*
X1293252Y1590094D03*
X1284592D03*
X1296652D03*
X1298552Y1614292D03*
X1286492D03*
X1289892D03*
X1298552Y1602380D03*
X1286492D03*
X1289892D03*
X1305312Y1578182D03*
X1308712D03*
X1305312Y1590094D03*
X1308712D03*
X1310612Y1614292D03*
X1314012D03*
X1301952D03*
X1310612Y1602380D03*
X1314012D03*
X1301952D03*
X1317372Y1578182D03*
X1320772D03*
X1329432D03*
X1317372Y1590094D03*
X1320772D03*
X1329432D03*
X1322672Y1614292D03*
X1326072D03*
X1322672Y1602380D03*
X1326072D03*
X1341752Y-19811D03*
Y-23211D03*
Y189D03*
Y-3211D03*
X1344684Y280259D03*
X1332832Y1578182D03*
X1341492D03*
X1344892D03*
X1332832Y1590094D03*
X1341492D03*
X1344892D03*
X1346792Y1614292D03*
X1334732D03*
X1338132D03*
X1346792Y1602380D03*
X1334732D03*
X1338132D03*
X1348084Y280259D03*
X1358624Y284644D03*
X1355224D03*
X1353552Y1578182D03*
X1356952D03*
X1353552Y1590094D03*
X1356952D03*
X1358852Y1614292D03*
X1362252D03*
X1350192D03*
X1358852Y1602380D03*
X1362252D03*
X1350192D03*
X1380522Y260236D03*
Y263636D03*
X1368524Y282744D03*
X1365124D03*
X1378306Y657608D03*
X1374668Y659708D03*
X1378306Y669608D03*
X1374668Y671708D03*
Y683708D03*
X1378306Y681608D03*
X1374668Y695708D03*
X1378306Y693608D03*
Y705608D03*
X1374668Y707708D03*
Y719708D03*
X1378306Y717608D03*
X1365612Y1578182D03*
X1377672D03*
X1369012D03*
X1365612Y1590094D03*
X1377672D03*
X1369012D03*
X1370912Y1614292D03*
X1374312D03*
X1370912Y1602380D03*
X1374312D03*
X1384002Y197668D03*
X1389256D03*
X1380602D03*
X1392656D03*
X1380638Y245694D03*
X1386630Y238651D03*
X1380638Y249094D03*
X1386630Y242051D03*
X1388754Y253803D03*
Y257203D03*
X1386273Y268670D03*
Y272070D03*
X1393206Y664708D03*
X1389568Y662608D03*
X1393206Y679208D03*
X1389568Y677108D03*
X1393206Y693708D03*
X1389568Y691608D03*
Y706108D03*
X1393206Y708208D03*
X1393199Y722708D03*
X1389561Y720608D03*
X1385338Y735098D03*
X1388976Y737198D03*
X1381072Y1578182D03*
Y1590094D03*
X1382972Y1614292D03*
X1386372D03*
X1382972Y1602380D03*
X1386372D03*
X1401341Y177159D03*
X1404829Y184263D03*
X1404741Y177159D03*
X1408229Y184263D03*
X1412284Y171696D03*
X1398006Y197668D03*
X1406786D03*
X1401406D03*
X1410186D03*
X1407420Y220018D03*
X1410820D03*
X1404385Y240929D03*
X1400985D03*
X1413950Y184263D03*
X1423110D03*
X1417350D03*
X1426510D03*
X1415684Y171696D03*
X1436060Y220018D03*
X1432660D03*
X1457176Y656992D03*
X1460814Y654892D03*
Y666892D03*
X1457176Y668992D03*
X1460814Y678892D03*
X1457176Y680992D03*
X1460814Y690892D03*
X1457176Y704992D03*
Y692992D03*
X1460814Y702892D03*
X1457176Y716992D03*
X1460814Y714892D03*
X1472076Y657392D03*
Y671892D03*
X1475714Y659492D03*
Y673992D03*
X1472076Y686392D03*
X1475714Y688492D03*
X1472076Y700892D03*
X1475714Y702992D03*
X1472076Y715392D03*
X1475714Y717492D03*
X1468876Y728392D03*
X1472514Y730492D03*
X1477755Y1578182D03*
X1462295D03*
X1474355D03*
X1465695D03*
X1477755Y1590094D03*
X1462295D03*
X1474355D03*
X1465695D03*
X1467595Y1614292D03*
X1470995D03*
X1467595Y1602380D03*
X1470995D03*
X1482650Y-19811D03*
Y-23211D03*
Y189D03*
Y-3211D03*
X1489815Y1578182D03*
X1486415D03*
X1489815Y1590094D03*
X1486415D03*
X1491715Y1614292D03*
X1479655D03*
X1483055D03*
X1491715Y1602380D03*
X1479655D03*
X1483055D03*
X1501875Y1578182D03*
X1498475D03*
X1501875Y1590094D03*
X1498475D03*
X1503775Y1614292D03*
X1507175D03*
X1495115D03*
X1503775Y1602380D03*
X1507175D03*
X1495115D03*
X1525995Y1578182D03*
X1513935D03*
X1522595D03*
X1510535D03*
X1525995Y1590094D03*
X1513935D03*
X1522595D03*
X1510535D03*
X1515835Y1614292D03*
X1519235D03*
X1515835Y1602380D03*
X1519235D03*
X1538996Y69297D03*
X1535596D03*
X1538055Y1578182D03*
X1534655D03*
X1538055Y1590094D03*
X1534655D03*
X1527895Y1614292D03*
X1539955D03*
X1531295D03*
X1527895Y1602380D03*
X1539955D03*
X1531295D03*
X1556413Y19495D03*
X1549308Y26431D03*
X1552708D03*
X1557596Y69297D03*
X1546596Y75297D03*
X1549996D03*
X1550115Y1578182D03*
X1558775D03*
X1546715D03*
X1550115Y1590094D03*
X1558775D03*
X1546715D03*
X1552015Y1614292D03*
X1555415D03*
X1543355D03*
X1552015Y1602380D03*
X1555415D03*
X1543355D03*
X1570586Y19495D03*
X1573986D03*
X1559813D03*
X1563481Y26431D03*
X1566881D03*
X1560996Y69297D03*
X1568596Y75297D03*
X1571996D03*
X1574235Y1578182D03*
X1562175D03*
X1570835D03*
X1574235Y1590094D03*
X1562175D03*
X1570835D03*
X1564075Y1614292D03*
X1567475D03*
X1564075Y1602380D03*
X1567475D03*
X1584759Y19495D03*
X1588159D03*
X1577654Y26431D03*
X1591828D03*
X1581054D03*
X1582996Y69297D03*
X1579596D03*
X1590596Y75297D03*
X1586295Y1578182D03*
X1582895D03*
X1586295Y1590094D03*
X1582895D03*
X1588195Y1614292D03*
X1576135D03*
X1591595D03*
X1579535D03*
X1588195Y1602380D03*
X1576135D03*
X1591595D03*
X1579535D03*
X1598933Y19495D03*
X1602333D03*
X1595228Y26431D03*
X1604996Y69297D03*
X1601596D03*
X1593996Y75297D03*
X1598355Y1578182D03*
X1607015D03*
X1594955D03*
X1598355Y1590094D03*
X1607015D03*
X1594955D03*
X1600255Y1614292D03*
X1603655D03*
X1600255Y1602380D03*
X1603655D03*
X1623596Y69297D03*
X1612596Y75297D03*
X1615996D03*
X1622475Y1578182D03*
X1610415D03*
X1619075D03*
X1622475Y1590094D03*
X1610415D03*
X1619075D03*
X1612315Y1614292D03*
X1615715D03*
X1612315Y1602380D03*
X1615715D03*
X1634799Y19495D03*
X1638199D03*
X1627694Y26431D03*
X1631094D03*
X1626996Y69297D03*
X1635800Y75297D03*
X1639200D03*
X1634535Y1578182D03*
X1631135D03*
X1634535Y1590094D03*
X1631135D03*
X1636435Y1614292D03*
X1624375D03*
X1639835D03*
X1627775D03*
X1636435Y1602380D03*
X1624375D03*
X1639835D03*
X1627775D03*
X1648972Y19495D03*
X1652372D03*
X1641867Y26431D03*
X1645267D03*
X1650200Y69297D03*
X1646800D03*
X1646595Y1578182D03*
X1643195D03*
X1646595Y1590094D03*
X1643195D03*
X1651895Y1614292D03*
X1648495D03*
X1651895Y1602380D03*
X1648495D03*
X1671828Y26431D03*
X1672200Y69297D03*
X1668800D03*
X1657800Y75297D03*
X1661200D03*
X1678933Y19495D03*
X1682333D03*
X1686001Y26431D03*
X1689401D03*
X1675228D03*
X1679934Y75297D03*
X1683334D03*
X1696506Y19495D03*
X1693106D03*
X1694334Y69297D03*
X1690934D03*
X1705334Y75297D03*
X1701934D03*
G54D41*
X338042Y849978D03*
X331284Y978814D03*
X338211Y1118243D03*
Y1131060D03*
X345178Y854584D03*
X348879Y860993D03*
Y873810D03*
X347029Y877014D03*
X348878Y880219D03*
X343761Y999684D03*
X349311Y1105426D03*
X351162Y1127856D03*
X353011Y1118243D03*
X354861Y1121447D03*
X347461Y1134264D03*
X354861D03*
X356278Y848176D03*
X371078D03*
X363678D03*
X356278Y860993D03*
X371078D03*
X363678D03*
X371078Y873810D03*
X356278D03*
X363678D03*
X363679Y893036D03*
X367379D03*
X363678Y886627D03*
X371078D03*
X367811Y1002888D03*
Y1105426D03*
X369661Y1102221D03*
X358562D03*
X360412Y1105426D03*
X369662Y1121447D03*
X362261D03*
X369662Y1134264D03*
X362262D03*
X385878Y848176D03*
X378478D03*
Y860993D03*
X385878D03*
X378478Y873810D03*
X385878D03*
X378478Y886627D03*
X385878D03*
X375211Y1099017D03*
X380762Y1095813D03*
X382611Y1099017D03*
X384462Y1121447D03*
X377062D03*
X384462Y1134264D03*
X377062D03*
X400678Y848176D03*
X393278D03*
X400678Y860993D03*
X393278D03*
Y873810D03*
X400678D03*
X402529Y896240D03*
X400678Y899445D03*
X393279Y893036D03*
X396979D03*
X398829Y896240D03*
X400678Y893036D03*
X393278Y886627D03*
X400678D03*
X404378Y899445D03*
X400678Y905853D03*
X402529Y915466D03*
Y909057D03*
X406229Y915466D03*
X400678Y912262D03*
X402529Y902649D03*
X400678Y931488D03*
X402529Y928283D03*
Y921875D03*
X398829Y934691D03*
X402529D03*
Y941100D03*
X400679Y944304D03*
X402529Y947509D03*
Y966735D03*
Y960326D03*
X398829Y953917D03*
X402529D03*
X400680Y950713D03*
X399262Y1006093D03*
X402962D03*
X399262Y999684D03*
X402962D03*
X401111Y1009297D03*
X402962Y1012501D03*
Y1031727D03*
X401111Y1028523D03*
Y1022114D03*
X402960Y1018910D03*
X402962Y1025318D03*
X399262D03*
X401111Y1015705D03*
Y1047749D03*
X399262Y1044544D03*
X402962D03*
X401111Y1041340D03*
X402962Y1038136D03*
X406662Y1057361D03*
X402962D03*
Y1063770D03*
X401113Y1060565D03*
X399262Y1063770D03*
X401111Y1054157D03*
X402962Y1050952D03*
Y1076587D03*
Y1070178D03*
X401112Y1066974D03*
X399262Y1082995D03*
X391862Y1102221D03*
X393711Y1105426D03*
X391862Y1121447D03*
X399262D03*
X391862Y1134264D03*
X399262D03*
X408078Y848176D03*
X415478D03*
Y860993D03*
X408078D03*
X415478Y873810D03*
X408078D03*
X404378Y893036D03*
X415478Y886627D03*
X408078D03*
X406229Y896240D03*
X408078Y899445D03*
X415478D03*
X409929Y896240D03*
X415478Y893036D03*
X417329Y896240D03*
X422878Y893036D03*
X411778Y899445D03*
X413629Y896240D03*
X419178Y899445D03*
X422878Y912262D03*
X417329Y909057D03*
X406229D03*
X413629D03*
Y915466D03*
X411778Y905853D03*
X408078D03*
Y912262D03*
X406229Y902649D03*
X415478Y905853D03*
X411778Y912262D03*
X415478D03*
X417329Y915466D03*
X411779Y918670D03*
X406229Y921875D03*
X408078Y918670D03*
X408569Y929108D03*
X406308Y928626D03*
X417329Y921875D03*
X411872Y925264D03*
X415479Y918670D03*
X407589Y942164D03*
X405289D03*
X409889D03*
X415185Y956620D03*
X411685D03*
X409385D03*
X417685D03*
X404785Y971100D03*
X407085D03*
X409385D03*
X411685D03*
X420205D03*
X412365Y985610D03*
X410065D03*
X420145Y985550D03*
X409385Y1014540D03*
X407085D03*
X411685D03*
X412385Y1000080D03*
X410085D03*
X420215Y1000040D03*
X420405Y1014470D03*
X414461Y1028855D03*
X411961D03*
X416961D03*
X419461D03*
X415911Y1047749D03*
X419611D03*
X406662Y1044544D03*
X410362D03*
X408511Y1047749D03*
X414062Y1044544D03*
X404811Y1041340D03*
X412211D03*
X415911D03*
X419611D03*
X406662Y1050952D03*
X414060D03*
X417762Y1057361D03*
X421462Y1050952D03*
X419611Y1054157D03*
X406662Y1063770D03*
X408511Y1060565D03*
X410362Y1063770D03*
X412211Y1054157D03*
X404811D03*
X414062Y1057361D03*
X410362D03*
X417762Y1063770D03*
X414062D03*
X419611Y1060565D03*
Y1079791D03*
X408511Y1073383D03*
X406662Y1070178D03*
X404811Y1073383D03*
X417762Y1076587D03*
X408511Y1066974D03*
X415911Y1079791D03*
X412211Y1073383D03*
X415911D03*
X414062Y1070178D03*
X417762D03*
X412211Y1066974D03*
X419611D03*
X419612Y1099017D03*
X404811Y1092608D03*
X417762Y1095813D03*
X414061D03*
X415912Y1124651D03*
X419612D03*
Y1118243D03*
X417761Y1121447D03*
Y1127856D03*
X406661Y1121447D03*
X414062Y1127856D03*
X406662Y1134264D03*
X415912Y1137469D03*
Y1131060D03*
X414061Y1140973D03*
X419612Y1137469D03*
Y1131060D03*
X417761Y1134264D03*
Y1140973D03*
X412212Y1137469D03*
X422878Y848176D03*
X430278Y860993D03*
X422878D03*
Y873810D03*
X430278D03*
X422878Y886627D03*
X430278D03*
Y899445D03*
X422878D03*
X424729Y896240D03*
X430278Y893036D03*
X432129Y896240D03*
X437678Y893036D03*
X421029Y896240D03*
X426578Y899445D03*
X428429Y896240D03*
X433978Y899445D03*
X435829Y896240D03*
X424729Y915466D03*
X426578Y912262D03*
X430278D03*
X432129Y915466D03*
X421029Y909057D03*
X435829D03*
Y915466D03*
X432128Y909057D03*
X433978Y905853D03*
X424728Y909057D03*
X422878Y905853D03*
X430278D03*
X426578D03*
X421029Y915466D03*
X433979Y912262D03*
X430278Y918670D03*
X432129Y921875D03*
X433979Y918670D03*
X435829Y921875D03*
X424927Y927255D03*
X423176Y929465D03*
X422427Y927255D03*
X425676Y929465D03*
X424729Y921875D03*
X422878Y918670D03*
X421029Y921875D03*
X426578Y918670D03*
X430279Y925079D03*
X432130Y928283D03*
X430279Y931487D03*
X432130Y934692D03*
X435830Y928283D03*
X427875Y941930D03*
Y944230D03*
X430280Y944305D03*
X432130Y941101D03*
X435830D03*
X432129Y947510D03*
X435830D03*
Y934692D03*
X427875Y956373D03*
Y954073D03*
X422685Y956620D03*
X425185D03*
X430280Y957123D03*
X432129Y960327D03*
Y953918D03*
X430280Y950714D03*
X435830Y960327D03*
Y953918D03*
X432129Y966736D03*
X430280Y963531D03*
X435830Y966736D03*
X430268Y976348D03*
X432129Y973144D03*
X430280Y969940D03*
X427875Y971267D03*
X422685Y971100D03*
X427875Y968967D03*
X435830Y973144D03*
X430280Y982757D03*
X432129Y979553D03*
X427875Y983111D03*
X435830Y979553D03*
X422685Y985580D03*
X427875Y985411D03*
Y997521D03*
X430712Y1009298D03*
X427875Y1012152D03*
X430712Y1002889D03*
X427875Y999821D03*
X422685Y1000060D03*
X436263Y1006094D03*
Y999685D03*
X432562Y1006094D03*
Y999685D03*
X427875Y1014452D03*
X423015Y1014470D03*
X436263Y1012502D03*
X432562D03*
X421961Y1028855D03*
X430712Y1022115D03*
Y1015706D03*
X427875Y1026704D03*
X430712Y1028524D03*
X436263Y1018911D03*
X432562D03*
Y1025319D03*
X436263D03*
X427875Y1029004D03*
Y1031304D03*
X436263Y1031728D03*
X432562D03*
X427011Y1047749D03*
X427012Y1041340D03*
X423312D03*
X425162Y1044544D03*
X423285Y1036884D03*
X430711Y1041340D03*
X430712Y1034932D03*
X427875Y1033604D03*
X423285Y1032284D03*
Y1034584D03*
X436262Y1038137D03*
X436261Y1044544D03*
X432562Y1038137D03*
X434412Y1041340D03*
X432561Y1044544D03*
X434412Y1047749D03*
X421462Y1044544D03*
X427011Y1054157D03*
X430711D03*
X428861Y1057361D03*
X432561D03*
X421462D03*
X425162Y1050952D03*
X423311Y1054157D03*
X428862Y1050952D03*
X436262Y1057361D03*
Y1050952D03*
Y1063770D03*
X425162D03*
X423311Y1060565D03*
X427011D03*
X428861Y1063770D03*
X430711Y1060565D03*
X423311Y1073383D03*
X432560Y1070178D03*
X421462Y1076587D03*
X423311Y1079791D03*
X436262Y1070178D03*
Y1076587D03*
X421462Y1070178D03*
X425162D03*
X428862D03*
X430711Y1066974D03*
X436262Y1082995D03*
Y1089404D03*
X436261Y1095813D03*
X421462Y1102221D03*
X423311Y1099017D03*
X428861Y1108630D03*
X427012Y1105426D03*
X425162Y1108630D03*
X430711Y1105426D03*
Y1099017D03*
X428861Y1102221D03*
X436262Y1108630D03*
Y1102221D03*
X432561Y1108630D03*
Y1102221D03*
X434412Y1099017D03*
X430711Y1111834D03*
X427012D03*
X430711Y1124651D03*
X428861Y1121447D03*
X427012Y1124651D03*
X425162Y1121447D03*
X421461D03*
X430711Y1118243D03*
X428861Y1115039D03*
X427012Y1118243D03*
X425162Y1115039D03*
X436262Y1121447D03*
Y1115039D03*
X432561Y1121447D03*
Y1115039D03*
X428861Y1127856D03*
X425162D03*
X421461D03*
X436262D03*
X432561D03*
X430711Y1137769D03*
X427012Y1137569D03*
X430711Y1131060D03*
X428861Y1134264D03*
X427012Y1131060D03*
X425162Y1134264D03*
X421461D03*
X428861Y1140973D03*
X425161D03*
X421461D03*
X436261Y1134264D03*
X432561D03*
X445078Y860993D03*
X452479D03*
X437679Y873810D03*
X452479D03*
X445078D03*
X452478Y886627D03*
X445078D03*
X452478Y899445D03*
X441378D03*
X445078Y893036D03*
X446929Y896240D03*
X452479Y893036D03*
X445078Y899445D03*
X443229Y896240D03*
X448778Y899445D03*
X450630Y896240D03*
X443229Y909057D03*
X439529Y915466D03*
X445079Y905853D03*
X441379D03*
X450630Y909057D03*
X452479Y905853D03*
X448779D03*
X448780Y912262D03*
X441380D03*
X439529Y909057D03*
X445080Y912262D03*
X443229Y915466D03*
X450629D03*
X452478Y912262D03*
X448779Y918670D03*
X454329Y915466D03*
X439529Y921875D03*
X441378Y918670D03*
X450629Y921875D03*
X445078Y918670D03*
X443229Y921875D03*
X452478Y918670D03*
X446930Y934692D03*
X443230Y928283D03*
X448780Y931487D03*
X437679D03*
X450630Y928283D03*
X448780Y925079D03*
X445079Y931487D03*
X439530Y934692D03*
X445079Y925079D03*
X439530Y928283D03*
X437679Y925079D03*
X437680Y944305D03*
X441380D03*
X443230Y941101D03*
X445079Y944305D03*
X439530Y941101D03*
X450630D03*
X448780Y944305D03*
X443229Y947510D03*
X439529D03*
X450630D03*
X443230Y934692D03*
X445079Y957123D03*
X437680D03*
X441380D03*
X439529Y960327D03*
X443229D03*
Y953918D03*
X439529D03*
X437680Y950714D03*
X441380D03*
X445079D03*
X448780Y957123D03*
X450630Y953918D03*
Y960327D03*
X448780Y950714D03*
X445079Y963531D03*
X437680D03*
X441380D03*
X439529Y966736D03*
X443229D03*
X448780Y963531D03*
X450630Y966736D03*
X445079Y976348D03*
Y969940D03*
X439529Y973144D03*
X443229D03*
X437680Y976348D03*
X441380D03*
X437680Y969940D03*
X441380D03*
X450630Y973144D03*
X448780Y976348D03*
Y969940D03*
X445079Y982757D03*
X437680D03*
X441380D03*
X439529Y979553D03*
X443229D03*
X448780Y982757D03*
X450630Y979553D03*
X439962Y1006094D03*
X443662D03*
X445511Y1009298D03*
X438113D03*
X441813D03*
X445512Y1002889D03*
X438113D03*
X441813D03*
X439962Y999685D03*
X443662D03*
X451062Y1006094D03*
X449213Y1009298D03*
Y1002889D03*
X451062Y999685D03*
X439962Y1012502D03*
X443662D03*
X451062D03*
X445511Y1022115D03*
X438113D03*
X441813D03*
X445512Y1015706D03*
X438113D03*
X439962Y1018911D03*
X441813Y1015706D03*
X443662Y1018911D03*
Y1025319D03*
X439962D03*
X445511Y1028524D03*
X441813D03*
X438113D03*
X449213Y1022115D03*
X451062Y1018911D03*
X449213Y1015706D03*
X451062Y1025319D03*
X449213Y1028524D03*
X439962Y1031728D03*
X443662D03*
X451062D03*
X452911Y1047749D03*
X439962Y1038137D03*
X443662D03*
X438112Y1041340D03*
X439961Y1044544D03*
X441812Y1041340D03*
X443661Y1044544D03*
X447361D03*
X445511Y1041340D03*
X445512Y1034932D03*
X438113D03*
X441813D03*
X451062Y1038137D03*
X449211Y1041340D03*
X449213Y1034932D03*
X445510Y1047749D03*
X441812D03*
X438112D03*
X449211Y1054157D03*
X449213Y1060565D03*
X438112D03*
Y1054157D03*
X439961Y1057361D03*
X441812Y1054157D03*
Y1060565D03*
X443661Y1057361D03*
X445511Y1060565D03*
Y1054157D03*
X439961Y1050952D03*
X443661D03*
X439961Y1063770D03*
X443661D03*
X451061D03*
X452911Y1054157D03*
X451062Y1050952D03*
X454762D03*
Y1057361D03*
X451062D03*
X451061Y1076587D03*
X452911Y1073383D03*
X439961Y1076587D03*
Y1070178D03*
X441812Y1073383D03*
X438112D03*
X443661Y1070178D03*
Y1076587D03*
X445511Y1073383D03*
X441812Y1066974D03*
X438112D03*
X445511D03*
X441812Y1079791D03*
X438112D03*
X445511D03*
X452911Y1066974D03*
X449211D03*
X451062Y1070178D03*
X452911Y1086200D03*
X443661Y1082995D03*
X439961D03*
X441812Y1086200D03*
X445511D03*
X439961Y1089404D03*
X441812Y1092608D03*
X438112D03*
X443661Y1089404D03*
X445511Y1092608D03*
X447361Y1089404D03*
X438112Y1086200D03*
X449211Y1092608D03*
X439961Y1095813D03*
X443661D03*
X447361D03*
X451060Y1082995D03*
X441812Y1105426D03*
X438112D03*
X439961Y1108630D03*
X443661D03*
X445511Y1105426D03*
X439961Y1102221D03*
X441812Y1099017D03*
X438112D03*
X443661Y1102221D03*
X445511Y1099017D03*
X452912Y1105426D03*
X451061Y1108630D03*
X449212Y1105426D03*
X451061Y1102221D03*
X449212Y1099017D03*
X441812Y1111834D03*
X438112D03*
X445511D03*
X452912D03*
X449212D03*
X438112Y1124651D03*
X439961Y1121447D03*
X441812Y1124651D03*
X445511D03*
X443661Y1121447D03*
X438112Y1118243D03*
X441812D03*
X439961Y1115039D03*
X445511Y1118243D03*
X443661Y1115039D03*
X452912Y1124651D03*
Y1118243D03*
X451061Y1121447D03*
X449212Y1124651D03*
Y1118243D03*
X451061Y1115039D03*
X439961Y1127856D03*
X443661D03*
X451061D03*
X441812Y1137769D03*
X438112D03*
X445511D03*
X443661Y1134264D03*
X441812Y1131060D03*
X439961Y1134264D03*
X438112Y1131060D03*
X445511D03*
X452912Y1137769D03*
Y1131060D03*
X449212Y1137769D03*
Y1131060D03*
X451061Y1134264D03*
X459878Y848176D03*
X467278D03*
X459878Y860993D03*
X467278D03*
Y873810D03*
X459878D03*
Y886627D03*
X467278D03*
X459878Y899445D03*
X467278D03*
X454329Y896240D03*
X459878Y893036D03*
X461729Y896240D03*
X467278Y893036D03*
X456178Y899445D03*
X458029Y896240D03*
X463578Y899445D03*
X465429Y896240D03*
X470978Y899445D03*
X463578Y905853D03*
X470980Y912262D03*
X469129Y902649D03*
X454329Y909057D03*
X470978Y918670D03*
X467278Y912262D03*
X469129Y915466D03*
X458029Y909057D03*
X459878Y905853D03*
X461729Y915466D03*
X467278Y905853D03*
X461729Y909057D03*
X458029Y915466D03*
X459878Y918670D03*
X463578Y912262D03*
X459878D03*
X469129Y909057D03*
X467278Y918670D03*
X454329Y921875D03*
X468236Y928349D03*
X465936D03*
X463636D03*
X461336D03*
X459036D03*
X469129Y921875D03*
X463578Y918670D03*
X465429Y921875D03*
X458029D03*
X469251Y942246D03*
X453585Y942238D03*
Y939938D03*
Y944538D03*
X453403Y956999D03*
X461424Y956620D03*
X458404D03*
X453403Y959299D03*
X468904Y956620D03*
Y971100D03*
X458404D03*
X461424Y971140D03*
X453403Y973099D03*
Y970799D03*
Y986899D03*
X461424Y985580D03*
X458404D03*
X453403Y984599D03*
X468904Y985580D03*
X453403Y998399D03*
Y1012199D03*
X458404Y1000080D03*
X461424D03*
X453403Y1000699D03*
X468904Y1000080D03*
X458404Y1014540D03*
X461295Y1014510D03*
X453403Y1014499D03*
X465680Y1028855D03*
X463180D03*
X460680D03*
X458180D03*
X457942Y1031909D03*
X467711Y1047750D03*
X460311D03*
X471411Y1041340D03*
X467711D03*
X454762Y1044544D03*
Y1038136D03*
X460971Y1037069D03*
X463271D03*
X458671D03*
X457942Y1034409D03*
X456611Y1041340D03*
X464011D03*
X462162Y1044544D03*
X458462D03*
X464011Y1054157D03*
X465860Y1050952D03*
X456611Y1060565D03*
X462161Y1057361D03*
Y1063770D03*
X460312Y1054157D03*
X458462Y1057361D03*
X467712Y1054157D03*
Y1060565D03*
X454761Y1063770D03*
X464012Y1060565D03*
X458460Y1050952D03*
X460311Y1060565D03*
Y1073383D03*
X458460Y1070178D03*
X460311Y1066974D03*
X464011D03*
X465860Y1070178D03*
X469560D03*
X464012Y1079791D03*
X460312D03*
X462162Y1076587D03*
X456611Y1066974D03*
X465862Y1076587D03*
X464011Y1073383D03*
X458462Y1076587D03*
X465862Y1082995D03*
X462162D03*
X462161Y1095812D03*
X458461D03*
X465861Y1089403D03*
X456612Y1092607D03*
X454761Y1089403D03*
X460311Y1086200D03*
X454760Y1082995D03*
X465861Y1095812D03*
X464012Y1092607D03*
X454761Y1095812D03*
X458461Y1089403D03*
X462161D03*
X467711Y1099017D03*
X462162Y1102221D03*
X458461Y1108630D03*
X456612Y1105426D03*
X454761Y1108630D03*
Y1102221D03*
X460312Y1111834D03*
X456611D03*
X460312Y1099016D03*
X464012Y1124651D03*
X462161Y1121447D03*
X460312Y1124651D03*
X456611D03*
X454761Y1121447D03*
X464011Y1118243D03*
X462161Y1115039D03*
X460312Y1118243D03*
X456611D03*
X454761Y1115039D03*
X462161Y1127856D03*
X454761D03*
X465861D03*
X464012Y1137469D03*
X460312D03*
X456612D03*
X464012Y1131060D03*
X462161Y1134264D03*
X460312Y1131060D03*
X456611D03*
X454761Y1134264D03*
X462161Y1140973D03*
X458461D03*
X454761D03*
X467712Y1137469D03*
X465861Y1134264D03*
X467712Y1131060D03*
X465861Y1140973D03*
X474678Y848176D03*
X482078D03*
X474678Y860993D03*
X482078D03*
X474678Y873810D03*
X482078D03*
X474678Y893036D03*
X472829Y896240D03*
X478378Y899445D03*
X474678Y886627D03*
X482078D03*
X476529Y896240D03*
Y915466D03*
X478380Y912262D03*
X478379Y918670D03*
X480229Y902649D03*
Y915466D03*
X472828D03*
X472829Y902649D03*
X480228Y909057D03*
X482078Y905853D03*
X476529Y902649D03*
X470978Y905853D03*
X478378D03*
X472829Y909057D03*
X476529D03*
X480229Y928283D03*
X478378Y931488D03*
Y925079D03*
X482078D03*
X472829Y921875D03*
X470536Y928349D03*
X478378Y937896D03*
X480229Y941100D03*
Y947509D03*
X471550Y942152D03*
X473851Y942246D03*
X478378Y963530D03*
X480228Y960326D03*
X478378Y950713D03*
X480229Y953917D03*
X478378Y957122D03*
X471404Y956620D03*
X480229Y966735D03*
X482078Y963529D03*
Y982756D03*
X478379Y969939D03*
X476285Y973826D03*
Y971526D03*
X471404Y971100D03*
X473904D03*
X480229Y979552D03*
X478378Y982756D03*
X480229Y973143D03*
X478378Y976347D03*
X471404Y985580D03*
X480662Y999684D03*
X478811Y1002888D03*
Y1009297D03*
X480662Y1012501D03*
X471404Y1000080D03*
X480662Y1031727D03*
X482511Y1015705D03*
X480661Y1018910D03*
X478811Y1022114D03*
Y1028523D03*
Y1015705D03*
X476325Y1031795D03*
Y1027195D03*
Y1029495D03*
X470724Y1028827D03*
X480662Y1025318D03*
X475111Y1047749D03*
X469562Y1044544D03*
X478811Y1034931D03*
X480662Y1038136D03*
X478811Y1041340D03*
X480662Y1044544D03*
X473262D03*
X476962D03*
X478811Y1047749D03*
X473261Y1057361D03*
X471412Y1060565D03*
X475112Y1054157D03*
X469562Y1063770D03*
X469561Y1057361D03*
X473262Y1063770D03*
X469561Y1050952D03*
X473262D03*
X482511Y1054157D03*
X480662Y1063770D03*
X480661Y1057361D03*
X478812Y1060565D03*
X476962Y1063770D03*
Y1057361D03*
X478812Y1054157D03*
X476961Y1050952D03*
X478811Y1066974D03*
X471411D03*
X476962Y1076587D03*
X480662D03*
Y1070178D03*
X476962D03*
X473262Y1076587D03*
X469562D03*
X471411Y1073383D03*
Y1079791D03*
X475111Y1073383D03*
X482511D03*
X473262Y1095813D03*
X469562Y1082995D03*
X480662Y1089404D03*
X478812Y1092607D03*
X475112D03*
X473261Y1089403D03*
X471412Y1086199D03*
X476961Y1082994D03*
X482512Y1092607D03*
X476961Y1095812D03*
X471412Y1092607D03*
X475112Y1086199D03*
X478812D03*
X480662Y1102221D03*
X473262Y1121447D03*
X480662D03*
Y1134264D03*
X469561D03*
X489478Y848176D03*
X496878D03*
X489478Y860993D03*
X496878D03*
Y873810D03*
X489478D03*
Y886627D03*
X496878D03*
X488062Y1095813D03*
X501012Y1105426D03*
Y1111833D03*
X488062Y1115039D03*
Y1121447D03*
X495462Y1134264D03*
X488062D03*
X511678Y848176D03*
X504278D03*
X511678Y860993D03*
X504278D03*
X511678Y873810D03*
X504278D03*
X511678Y886627D03*
X504278D03*
X502862Y1006093D03*
X510262Y1102221D03*
X502861Y1108629D03*
X512112Y1105426D03*
X508412Y1111833D03*
X506561Y1102220D03*
X504712Y1111833D03*
Y1105426D03*
X510261Y1108630D03*
X512112Y1111833D03*
X508412Y1105426D03*
X502862Y1115039D03*
X510262Y1121447D03*
X502862D03*
X517662D03*
X506561Y1115038D03*
X510262Y1134264D03*
X502862D03*
X517662D03*
X519078Y848176D03*
X526479Y860993D03*
X519078D03*
X526479Y873810D03*
X519078D03*
X530178Y893036D03*
X526479Y886627D03*
X519078D03*
X533879D03*
X528762Y1102221D03*
X525062D03*
X523212Y1099017D03*
X530611Y1105426D03*
X526911Y1118243D03*
X525062Y1121447D03*
X534311Y1118243D03*
X532461Y1121446D03*
X534311Y1124650D03*
X532461Y1127855D03*
X525062Y1134264D03*
X528761Y1140973D03*
X532461D03*
X541711Y1118243D03*
X538010Y1118242D03*
X543561Y1121446D03*
X539861Y1127855D03*
X536161D03*
Y1121446D03*
X539861D03*
X541711Y1124650D03*
X543561Y1127855D03*
X538012Y1131059D03*
X650599Y766798D03*
X918264Y506011D03*
X1030780Y1266532D03*
X1074480Y1263742D03*
X1181941Y766798D03*
X1297012Y157449D03*
X1293802Y159299D03*
Y166699D03*
X1293511Y179048D03*
X1296999Y183349D03*
X1297007Y172249D03*
X1296999Y175949D03*
X1293802Y170399D03*
X1294163Y175865D03*
X1296999Y179649D03*
Y194449D03*
Y198149D03*
Y190749D03*
Y187049D03*
Y201849D03*
X1293805Y211099D03*
X1293798Y205833D03*
X1296999Y216649D03*
X1293807Y218499D03*
Y214799D03*
X1296999Y212949D03*
Y205549D03*
X1294357Y224688D03*
X1296999Y224049D03*
X1293807Y222199D03*
X1300393Y235762D03*
X1303417Y164849D03*
X1300213Y162999D03*
X1300212Y166699D03*
X1306622D03*
X1309832Y157449D03*
X1306626Y162999D03*
Y159299D03*
X1313037Y162999D03*
X1309832Y164849D03*
X1313037Y159299D03*
X1303417Y157449D03*
X1300217Y159299D03*
X1313033Y166699D03*
X1300212Y170399D03*
X1306626D03*
X1303407Y183349D03*
X1309817Y175949D03*
X1300212Y174099D03*
X1313037Y170399D03*
X1306617Y185199D03*
X1309832Y172249D03*
X1313027Y181499D03*
Y185199D03*
X1303407Y175949D03*
Y179649D03*
X1306617Y177799D03*
X1309817Y179649D03*
X1300204Y181499D03*
X1309817Y194449D03*
X1306617Y188899D03*
X1303407Y194449D03*
X1306617Y196299D03*
X1300207D03*
X1303407Y190749D03*
Y187049D03*
X1300204Y188899D03*
X1313027Y192599D03*
X1309817Y190749D03*
X1313025Y188899D03*
X1309817Y198149D03*
X1303407D03*
X1300207Y203699D03*
Y207399D03*
X1309832Y209249D03*
X1313027Y203699D03*
X1300220Y218499D03*
X1309833Y220349D03*
X1303416Y205549D03*
X1306614Y203699D03*
X1306627Y214799D03*
X1316242Y209249D03*
X1300207Y211099D03*
X1303422Y220349D03*
X1300220Y222199D03*
X1313033D03*
X1303425Y224049D03*
X1300493Y238062D03*
X1314184Y849978D03*
X1307426Y978814D03*
X1314353Y1118243D03*
Y1131060D03*
X1319452Y162999D03*
X1316242Y168549D03*
X1319442Y159299D03*
X1316241Y157449D03*
X1316242Y164849D03*
X1322652D03*
X1329062D03*
X1326918Y161161D03*
X1329062Y157449D03*
X1322652D03*
X1325853Y174099D03*
X1331102Y179724D03*
Y182874D03*
Y186024D03*
X1325085Y176402D03*
X1324802Y179724D03*
Y186024D03*
Y182874D03*
X1315352Y186024D03*
Y179724D03*
X1319442Y174099D03*
X1332268D03*
X1324802Y195474D03*
X1327952D03*
X1318502D03*
X1321652D03*
X1327952Y201774D03*
X1321652D03*
X1331102Y189174D03*
X1315405Y189227D03*
X1329062Y212949D03*
X1325852Y211099D03*
X1319442D03*
X1324802Y204924D03*
X1327952D03*
X1318502D03*
X1315352D03*
X1322652Y209249D03*
X1325857Y218499D03*
X1322652Y216649D03*
X1329062Y220349D03*
X1325856Y222199D03*
X1322652Y224049D03*
Y220349D03*
X1321320Y854584D03*
X1325021Y860993D03*
X1325020Y873810D03*
X1323171Y877014D03*
X1325020Y880219D03*
X1319903Y999684D03*
X1325453Y1105426D03*
X1327304Y1127856D03*
X1329153Y1118243D03*
X1331003Y1121447D03*
Y1134264D03*
X1323603D03*
X1339727Y161149D03*
X1341992Y156897D03*
X1332268Y162999D03*
X1342903Y170399D03*
X1339727Y168549D03*
X1335472Y164849D03*
X1346140Y161149D03*
X1342937Y162999D03*
X1335472Y157449D03*
X1346140D03*
X1339727D03*
X1332268Y170399D03*
X1334252Y176574D03*
X1339727Y183349D03*
X1346137D03*
X1337901Y196035D03*
X1339727Y187049D03*
X1337345Y201831D03*
X1339727Y201849D03*
X1337402Y198624D03*
X1342937Y192599D03*
X1346137Y187049D03*
X1346147Y201849D03*
Y198149D03*
X1336527Y214799D03*
X1339727Y216649D03*
X1346147Y212949D03*
Y216649D03*
X1336527Y218499D03*
X1342937D03*
Y214799D03*
X1332262Y211099D03*
X1339686Y205478D03*
X1332262Y207399D03*
X1339727Y209249D03*
Y220349D03*
X1336527Y222199D03*
X1346147Y220349D03*
X1347220Y848176D03*
X1339820D03*
X1332420D03*
X1339820Y860993D03*
X1347220D03*
X1332420D03*
X1339820Y873810D03*
X1332420D03*
X1347220D03*
X1339821Y893036D03*
X1343521D03*
X1347220Y886627D03*
X1339820D03*
X1343953Y1002888D03*
X1334704Y1102221D03*
X1345803D03*
X1343953Y1105426D03*
X1336554D03*
X1345804Y1121447D03*
X1338403D03*
X1338404Y1134264D03*
X1345804D03*
X1352550Y157449D03*
X1355961Y155458D03*
X1349344Y162999D03*
X1348386Y156646D03*
X1352551Y161148D03*
X1349351Y192598D03*
X1352551Y187048D03*
X1355761Y188898D03*
X1349361Y199998D03*
X1352561Y201848D03*
X1355766Y214798D03*
X1349351Y218498D03*
X1352561Y216648D03*
X1355766Y218498D03*
X1352561Y220348D03*
X1355766Y222198D03*
X1360186Y226264D03*
X1362020Y848176D03*
X1354620D03*
X1362020Y860993D03*
X1354620D03*
Y873810D03*
X1362020D03*
X1354620Y886627D03*
X1362020D03*
X1351354Y1099017D03*
X1356904Y1095813D03*
X1358753Y1099017D03*
X1360604Y1121447D03*
X1353204D03*
Y1134264D03*
X1360604D03*
X1376820Y848176D03*
X1369420D03*
X1376820Y860993D03*
X1369420D03*
Y873810D03*
X1376820D03*
X1378671Y896240D03*
X1376820Y899445D03*
X1369421Y893036D03*
X1373121D03*
X1374971Y896240D03*
X1376820Y893036D03*
X1369420Y886627D03*
X1376820D03*
X1380520Y899445D03*
X1376820Y905853D03*
X1378671Y915466D03*
Y909057D03*
X1376820Y912262D03*
X1378671Y902649D03*
X1376820Y931488D03*
X1378671Y928283D03*
Y921875D03*
X1374971Y934691D03*
X1378671D03*
Y947509D03*
Y966735D03*
Y960326D03*
Y953917D03*
X1374971D03*
X1376822Y950713D03*
X1375404Y1006093D03*
X1379104D03*
X1375404Y999684D03*
X1379104D03*
X1377253Y1009297D03*
X1379104Y1012501D03*
Y1031727D03*
X1377253Y1028523D03*
X1375404Y1025318D03*
X1377253Y1022114D03*
X1379102Y1018910D03*
X1379104Y1025318D03*
X1377253Y1015705D03*
X1375404Y1044544D03*
X1377253Y1041340D03*
X1379104Y1044544D03*
Y1038136D03*
X1377253Y1047749D03*
X1379104Y1057361D03*
Y1063770D03*
X1377255Y1060565D03*
X1375404Y1063770D03*
X1377253Y1054157D03*
X1379104Y1050952D03*
X1380953Y1054157D03*
X1379104Y1076587D03*
Y1070178D03*
X1377254Y1066974D03*
X1375404Y1082995D03*
X1368004Y1102221D03*
X1369853Y1105426D03*
X1368004Y1121447D03*
X1375404D03*
X1368004Y1134264D03*
X1375404D03*
X1374847Y1153069D03*
X1391620Y848176D03*
X1384220D03*
Y860993D03*
X1391620D03*
Y873810D03*
X1384220D03*
X1380520Y893036D03*
X1382371Y896240D03*
X1384220Y886627D03*
X1391620D03*
Y899445D03*
X1384221Y899446D03*
X1393471Y909057D03*
X1382371D03*
X1389771D03*
Y915466D03*
X1399020Y905853D03*
X1382371Y915466D03*
X1384220Y918670D03*
X1387920Y905853D03*
X1384220D03*
Y912262D03*
X1382371Y902649D03*
X1391620Y905853D03*
X1387920Y912262D03*
X1391620D03*
X1393471Y915466D03*
X1391621Y918670D03*
X1382371Y921875D03*
X1382809Y927986D03*
X1385070Y928468D03*
X1393471Y921875D03*
X1391550Y925219D03*
X1387921Y918670D03*
X1386030Y942163D03*
X1383730D03*
X1381430D03*
X1392534Y942097D03*
X1394834D03*
X1393826Y956619D03*
X1387826D03*
X1391326D03*
X1385526D03*
X1380926Y971099D03*
X1383226D03*
X1387826D03*
X1385526D03*
X1396346D03*
X1396286Y985549D03*
X1388506Y985609D03*
X1386206D03*
X1385526Y1014539D03*
X1387826D03*
X1383226D03*
X1386226Y1000079D03*
X1396356Y1000039D03*
X1388526Y1000079D03*
X1396546Y1014469D03*
X1388102Y1028854D03*
X1390602D03*
X1393102D03*
X1395602D03*
X1380953Y1041340D03*
X1388353D03*
X1392053D03*
X1395753D03*
Y1047749D03*
X1392053D03*
X1382804Y1044544D03*
X1386504D03*
X1384653Y1047749D03*
X1390204Y1044544D03*
X1382804Y1050952D03*
Y1057361D03*
X1386504D03*
X1390204Y1050952D03*
X1393904Y1057361D03*
X1395753Y1054157D03*
X1382804Y1063770D03*
X1384653Y1060565D03*
X1386504Y1063770D03*
X1388353Y1054157D03*
X1390204Y1057361D03*
X1393904Y1063770D03*
X1390204D03*
X1395753Y1060565D03*
Y1079791D03*
X1384653Y1073383D03*
X1382804Y1070178D03*
X1380953Y1073383D03*
X1393904Y1076587D03*
X1392053Y1079791D03*
X1384653Y1066974D03*
X1388353Y1073383D03*
X1392053D03*
X1390204Y1070178D03*
X1393904D03*
X1388353Y1066974D03*
X1395753D03*
X1395754Y1099017D03*
X1380953Y1092608D03*
X1393904Y1095813D03*
X1390203D03*
X1392054Y1124651D03*
X1393903Y1121447D03*
Y1127856D03*
X1395754Y1118243D03*
Y1124651D03*
X1382803Y1121447D03*
X1390204Y1127856D03*
X1382804Y1134264D03*
X1390203Y1140973D03*
X1392054Y1131060D03*
Y1137469D03*
X1393903Y1134264D03*
Y1140973D03*
X1395754Y1131060D03*
Y1137469D03*
X1388354D03*
X1399020Y848176D03*
X1406420Y860993D03*
X1399020D03*
Y873810D03*
X1406420D03*
Y886627D03*
X1399020D03*
X1406420Y899445D03*
X1399020D03*
Y912262D03*
X1400871Y915466D03*
X1402720Y912262D03*
X1406420D03*
X1408271Y915466D03*
X1397171Y909057D03*
X1411971D03*
Y915466D03*
X1408270Y909057D03*
X1410120Y905853D03*
X1400870Y909057D03*
X1406420Y905853D03*
X1402720D03*
X1397171Y915466D03*
X1410121Y912262D03*
X1406420Y918670D03*
X1408271Y921875D03*
X1410121Y918670D03*
X1411971Y921875D03*
X1401528Y927155D03*
X1399028D03*
X1401817Y929464D03*
X1399317D03*
X1400871Y921875D03*
X1399020Y918670D03*
X1397171Y921875D03*
X1402720Y918670D03*
X1411971Y934691D03*
X1406420Y925079D03*
X1408271Y928283D03*
X1406420Y931488D03*
X1411971Y928283D03*
X1406421Y944304D03*
X1408271Y941100D03*
X1411971D03*
X1404016Y944229D03*
Y941929D03*
X1408270Y947509D03*
X1411971D03*
X1408271Y934691D03*
X1406421Y950713D03*
Y957122D03*
X1408270Y953917D03*
Y960326D03*
X1411971Y953917D03*
Y960326D03*
X1404016Y954072D03*
Y956372D03*
X1401326Y956619D03*
X1398826D03*
X1406421Y963530D03*
X1408270Y966735D03*
X1411971D03*
X1406421Y969939D03*
X1406409Y976347D03*
X1408270Y973143D03*
X1411971D03*
X1404016Y971266D03*
Y968966D03*
X1398826Y971099D03*
X1406421Y982756D03*
X1408270Y979552D03*
X1411971D03*
X1404016Y983110D03*
Y985410D03*
X1398826Y985579D03*
X1404016Y997520D03*
X1412404Y999684D03*
Y1006093D03*
Y1012501D03*
X1406853Y1002888D03*
Y1009297D03*
X1408703Y999684D03*
Y1006093D03*
Y1012501D03*
X1404016Y1012151D03*
Y999820D03*
X1398826Y1000059D03*
X1404016Y1014451D03*
X1399156Y1014469D03*
X1398102Y1028854D03*
X1406853Y1028523D03*
X1412404Y1018910D03*
X1406853Y1015705D03*
Y1022114D03*
X1408703Y1018910D03*
X1412404Y1025318D03*
X1408703D03*
X1404016Y1026703D03*
X1412404Y1031727D03*
X1408703D03*
X1404016Y1029003D03*
Y1031303D03*
X1403153Y1047749D03*
X1403154Y1041340D03*
X1399454D03*
X1401304Y1044544D03*
X1412403Y1038136D03*
Y1044544D03*
X1406853Y1034931D03*
Y1041340D03*
X1408703Y1038136D03*
Y1044544D03*
X1410554Y1041340D03*
X1404016Y1033603D03*
X1399426Y1036883D03*
Y1034583D03*
Y1032283D03*
X1410554Y1047749D03*
X1397604Y1044544D03*
X1403153Y1054157D03*
X1406853D03*
X1405003Y1057361D03*
X1408703D03*
Y1063770D03*
X1412404Y1050952D03*
Y1057361D03*
Y1063770D03*
X1397604Y1057361D03*
X1401304Y1050952D03*
X1399453Y1054157D03*
X1405004Y1050952D03*
X1397604D03*
X1401304Y1063770D03*
X1399453Y1060565D03*
X1403153D03*
X1405003Y1063770D03*
X1406853Y1060565D03*
X1397604Y1076587D03*
X1408702Y1070178D03*
X1399453Y1073383D03*
Y1079791D03*
X1412404Y1070178D03*
Y1076587D03*
X1397604Y1070178D03*
X1401304D03*
X1405004D03*
X1406853Y1066974D03*
X1412404Y1082995D03*
Y1089404D03*
X1412403Y1095813D03*
X1397604Y1102221D03*
X1399453Y1099017D03*
X1412404Y1102221D03*
Y1108630D03*
X1401304D03*
X1403154Y1105426D03*
Y1111834D03*
X1405003Y1102221D03*
Y1108630D03*
X1406853Y1099017D03*
Y1105426D03*
Y1111834D03*
X1408703Y1102221D03*
Y1108630D03*
X1410554Y1099017D03*
X1412404Y1115039D03*
Y1121447D03*
Y1127856D03*
X1397603Y1121447D03*
Y1127856D03*
X1401304Y1115039D03*
Y1121447D03*
Y1127856D03*
X1403154Y1118243D03*
Y1124651D03*
X1405003Y1115039D03*
Y1121447D03*
Y1127856D03*
X1406853Y1118243D03*
Y1124651D03*
X1408703Y1115039D03*
Y1121447D03*
Y1127856D03*
X1412403Y1134264D03*
X1397603D03*
Y1140973D03*
X1401304Y1134264D03*
X1401303Y1140973D03*
X1403154Y1131060D03*
Y1137569D03*
X1405003Y1134264D03*
Y1140973D03*
X1406853Y1131060D03*
Y1137769D03*
X1408703Y1134264D03*
X1421220Y860993D03*
X1428621D03*
X1413821Y873810D03*
X1428621D03*
X1421220D03*
X1428620Y899445D03*
Y886627D03*
X1421220D03*
X1419371Y909057D03*
X1415671Y915466D03*
X1421221Y905853D03*
X1417521D03*
X1430471Y909057D03*
X1426772D03*
X1428621Y905853D03*
X1424921D03*
X1424922Y912262D03*
X1417522D03*
X1415671Y909057D03*
X1421222Y912262D03*
X1419371Y915466D03*
X1426771D03*
X1428620Y912262D03*
X1424921Y918670D03*
X1430471Y915466D03*
X1415671Y921875D03*
X1417520Y918670D03*
X1426771Y921875D03*
X1421220Y918670D03*
X1419371Y921875D03*
X1428620Y918670D03*
X1424921Y931488D03*
X1419371Y928283D03*
X1413820Y931488D03*
X1424921Y925079D03*
X1419371Y934691D03*
X1421220Y931488D03*
Y925079D03*
X1415671Y928283D03*
X1413820Y925079D03*
X1426771Y928283D03*
X1413821Y944304D03*
X1415671Y941100D03*
X1417521Y944304D03*
X1419371Y941100D03*
X1421220Y944304D03*
X1424921D03*
X1426771Y941100D03*
X1415670Y947509D03*
X1419370D03*
X1426771D03*
X1423071Y934691D03*
X1415671D03*
X1413821Y950713D03*
Y957122D03*
X1415670Y953917D03*
Y960326D03*
X1417521Y950713D03*
Y957122D03*
X1419370Y953917D03*
Y960326D03*
X1421220Y950713D03*
Y957122D03*
X1424921Y950713D03*
Y957122D03*
X1426771Y953917D03*
Y960326D03*
X1413821Y963530D03*
X1415670Y966735D03*
X1417521Y963530D03*
X1419370Y966735D03*
X1421220Y963530D03*
X1424921D03*
X1426771Y966735D03*
X1413821Y969939D03*
Y976347D03*
X1415670Y973143D03*
X1417521Y969939D03*
Y976347D03*
X1419370Y973143D03*
X1421220Y969939D03*
Y976347D03*
X1424921Y969939D03*
Y976347D03*
X1426771Y973143D03*
X1413821Y982756D03*
X1415670Y979552D03*
X1417521Y982756D03*
X1419370Y979552D03*
X1421220Y982756D03*
X1424921D03*
X1426771Y979552D03*
X1414254Y1002888D03*
Y1009297D03*
X1416103Y999684D03*
Y1006093D03*
Y1012501D03*
X1417954Y1002888D03*
Y1009297D03*
X1419803Y999684D03*
Y1006093D03*
Y1012501D03*
X1421653Y1002888D03*
Y1009297D03*
X1425354Y1002888D03*
Y1009297D03*
X1427203Y999684D03*
Y1006093D03*
Y1012501D03*
X1421653Y1028523D03*
X1414254D03*
X1417954D03*
X1425354D03*
X1414254Y1015705D03*
Y1022114D03*
X1416103Y1018910D03*
X1417954Y1015705D03*
Y1022114D03*
X1419803Y1018910D03*
X1421653Y1015705D03*
Y1022114D03*
X1425354Y1015705D03*
Y1022114D03*
X1427203Y1018910D03*
X1416103Y1025318D03*
X1419803D03*
X1427203D03*
X1416103Y1031727D03*
X1419803D03*
X1427203D03*
X1429053Y1047749D03*
X1414254Y1034931D03*
Y1041340D03*
X1416103Y1038136D03*
Y1044544D03*
X1417954Y1034931D03*
Y1041340D03*
X1419803Y1038136D03*
Y1044544D03*
X1421653Y1034931D03*
Y1041340D03*
X1423503Y1044544D03*
X1425354Y1034931D03*
X1425353Y1041340D03*
X1427203Y1038136D03*
X1421653Y1047749D03*
X1414254D03*
X1417954D03*
X1425353Y1054157D03*
X1425355Y1060565D03*
X1414254Y1054157D03*
X1416103Y1050952D03*
X1417954Y1054157D03*
X1419803Y1050952D03*
X1421653Y1054157D03*
X1414254Y1060565D03*
X1416103Y1057361D03*
X1417954Y1060565D03*
X1419803Y1057361D03*
X1421653Y1060565D03*
X1416103Y1063770D03*
X1419803D03*
X1427203D03*
X1429053Y1054157D03*
X1427203Y1050952D03*
X1430903D03*
X1430904Y1057361D03*
X1427204D03*
X1429053Y1073383D03*
X1427203Y1076587D03*
X1414254Y1066974D03*
Y1073383D03*
X1416103Y1070178D03*
Y1076587D03*
X1417954Y1066974D03*
Y1073383D03*
X1419803Y1070178D03*
Y1076587D03*
X1421653Y1066974D03*
Y1073383D03*
X1414254Y1079791D03*
X1417954D03*
X1421653D03*
X1429053Y1066974D03*
X1425353D03*
X1427204Y1070178D03*
X1429053Y1086200D03*
X1416103Y1082995D03*
X1419803D03*
X1414254Y1086200D03*
Y1092608D03*
X1416103Y1089404D03*
Y1095813D03*
X1417954Y1086200D03*
Y1092608D03*
X1419803Y1089404D03*
Y1095813D03*
X1421653Y1086200D03*
Y1092608D03*
X1423503Y1089404D03*
Y1095813D03*
X1425353Y1092608D03*
X1427202Y1082995D03*
X1414254Y1099017D03*
Y1105426D03*
Y1111834D03*
X1416103Y1102221D03*
Y1108630D03*
X1417954Y1099017D03*
Y1105426D03*
Y1111834D03*
X1419803Y1102221D03*
Y1108630D03*
X1421653Y1099017D03*
Y1105426D03*
Y1111834D03*
X1425354Y1099017D03*
Y1105426D03*
Y1111834D03*
X1427203Y1102221D03*
Y1108630D03*
X1429054Y1105426D03*
Y1111834D03*
X1414254Y1118243D03*
Y1124651D03*
X1416103Y1115039D03*
Y1121447D03*
Y1127856D03*
X1417954Y1118243D03*
Y1124651D03*
X1419803Y1115039D03*
Y1121447D03*
Y1127856D03*
X1421653Y1118243D03*
Y1124651D03*
X1425354Y1118243D03*
Y1124651D03*
X1427203Y1115039D03*
Y1121447D03*
Y1127856D03*
X1429054Y1118243D03*
Y1124651D03*
X1414254Y1131060D03*
Y1137769D03*
X1416103Y1134264D03*
X1417954Y1131060D03*
Y1137769D03*
X1419803Y1134264D03*
X1421653Y1131060D03*
Y1137769D03*
X1425354Y1131060D03*
Y1137769D03*
X1427203Y1134264D03*
X1429054Y1131060D03*
Y1137769D03*
X1443420Y848176D03*
X1436020D03*
X1443420Y860993D03*
X1436020D03*
Y873810D03*
X1443420D03*
X1436020Y899445D03*
X1443420D03*
X1436020Y886627D03*
X1443420D03*
X1447120Y899445D03*
X1445271Y902649D03*
X1434171Y909057D03*
X1437871Y915466D03*
X1443420Y912262D03*
X1445271Y915466D03*
X1437871Y909057D03*
X1434171Y915466D03*
X1436020Y918670D03*
X1439720Y912262D03*
X1436020D03*
Y905853D03*
X1439720D03*
X1443420D03*
X1445271Y909057D03*
X1430471Y921875D03*
X1443420Y918670D03*
X1439777Y928348D03*
X1437477D03*
X1435177D03*
X1444377D03*
X1442077D03*
X1445271Y921875D03*
X1439720Y918670D03*
X1441571Y921875D03*
X1434171D03*
X1445392Y942195D03*
X1429726Y944537D03*
Y939937D03*
Y942237D03*
X1429544Y959298D03*
Y956998D03*
X1437565Y956619D03*
X1434545D03*
X1445045D03*
X1429544Y970798D03*
Y973098D03*
X1437565Y971139D03*
X1434545Y971099D03*
X1429544Y986898D03*
Y984598D03*
X1437565Y985579D03*
X1434545D03*
X1445045D03*
X1429544Y998398D03*
Y1012198D03*
Y1000698D03*
X1437565Y1000079D03*
X1434545D03*
X1445045D03*
X1429544Y1014498D03*
X1437436Y1014509D03*
X1434545Y1014539D03*
X1445036Y1014549D03*
X1439321Y1028854D03*
X1436821D03*
X1434321D03*
X1441821D03*
X1434083Y1031908D03*
X1447553Y1041340D03*
X1443853D03*
X1436453Y1047750D03*
X1443853D03*
X1430904Y1044544D03*
Y1038136D03*
X1434083Y1034408D03*
X1434813Y1037069D03*
X1439413D03*
X1437113D03*
X1432753Y1041340D03*
X1440153D03*
X1438304Y1044544D03*
X1434604D03*
X1432753Y1060565D03*
X1438303Y1057361D03*
Y1063770D03*
X1442002Y1050952D03*
X1440153Y1054157D03*
X1436454D03*
X1434604Y1057361D03*
X1443854Y1054157D03*
Y1060565D03*
X1430903Y1063770D03*
X1440154Y1060565D03*
X1434603Y1050952D03*
X1436453Y1060565D03*
Y1073383D03*
X1434602Y1070178D03*
X1436453Y1066974D03*
X1440153D03*
X1442002Y1070178D03*
X1447553Y1066974D03*
X1440154Y1079791D03*
X1436454D03*
X1438304Y1076587D03*
X1432753Y1066974D03*
X1442004Y1076587D03*
X1440153Y1073383D03*
X1434604Y1076587D03*
X1438304Y1082995D03*
X1442004D03*
X1438303Y1095812D03*
X1434603D03*
X1442003Y1089403D03*
X1432754Y1092607D03*
X1430903Y1089403D03*
X1436454Y1086199D03*
X1430902Y1082995D03*
X1442003Y1095812D03*
X1440154Y1092607D03*
X1430903Y1095812D03*
X1434603Y1089403D03*
X1438303D03*
X1438304Y1102221D03*
X1443853Y1099017D03*
X1430903Y1102221D03*
Y1108630D03*
X1432754Y1105426D03*
X1432753Y1111834D03*
X1434603Y1108630D03*
X1436454Y1111834D03*
Y1099016D03*
X1430903Y1115039D03*
Y1121447D03*
Y1127856D03*
X1432753Y1118243D03*
Y1124651D03*
X1436454Y1118243D03*
Y1124651D03*
X1438303Y1115039D03*
Y1121447D03*
Y1127856D03*
X1440153Y1118243D03*
X1440154Y1124651D03*
X1442003Y1127856D03*
X1443854Y1131060D03*
Y1137469D03*
X1430903Y1134264D03*
Y1140973D03*
X1432753Y1131060D03*
X1432754Y1137469D03*
X1434603Y1140973D03*
X1436454Y1131060D03*
Y1137469D03*
X1438303Y1134264D03*
Y1140973D03*
X1440154Y1131060D03*
Y1137469D03*
X1442003Y1134264D03*
Y1140973D03*
X1450820Y848176D03*
X1458220D03*
X1450820Y860993D03*
X1458220D03*
Y873810D03*
X1450820D03*
Y893036D03*
X1448971Y896240D03*
X1454520Y899445D03*
X1458220Y886627D03*
X1450820D03*
X1452671Y896240D03*
X1456371Y902649D03*
Y915466D03*
X1447122Y912262D03*
X1454521Y918670D03*
X1452671Y915466D03*
X1454522Y912262D03*
X1448971Y902649D03*
X1456370Y909057D03*
X1458220Y905853D03*
X1452671Y902649D03*
X1448970Y915466D03*
X1447120Y905853D03*
X1454520D03*
X1448971Y909057D03*
X1452671D03*
X1456371Y928283D03*
X1454522Y931488D03*
X1454520Y925079D03*
X1458220D03*
X1448971Y921875D03*
X1447120Y918670D03*
X1446677Y928348D03*
X1454520Y937896D03*
X1456371Y941100D03*
Y947509D03*
X1449992Y942195D03*
X1447692D03*
X1454520Y963530D03*
X1456371Y966735D03*
X1458220Y963529D03*
X1456370Y960326D03*
X1456371Y953917D03*
X1454520Y957122D03*
Y950713D03*
X1447545Y956619D03*
X1458220Y982756D03*
X1454521Y969939D03*
X1450045Y971099D03*
X1445445D03*
X1447745D03*
X1452426Y973825D03*
Y971525D03*
X1456371Y979552D03*
X1454520Y982756D03*
X1456371Y973143D03*
X1454520Y976347D03*
X1447545Y985579D03*
X1456804Y999684D03*
X1454953Y1002888D03*
Y1009297D03*
X1456804Y1012501D03*
X1447545Y1000079D03*
X1447345Y1014539D03*
X1456804Y1031727D03*
X1454953Y1028523D03*
Y1022114D03*
X1456803Y1018910D03*
X1454953Y1015705D03*
X1446934Y1028889D03*
X1452466Y1031794D03*
Y1029494D03*
Y1027194D03*
X1456804Y1025318D03*
X1458653Y1015705D03*
X1451253Y1047749D03*
X1445704Y1044544D03*
X1454953Y1034931D03*
X1456804Y1038136D03*
X1454953Y1041340D03*
X1456804Y1044544D03*
X1449404D03*
X1454953Y1047749D03*
X1453104Y1044544D03*
X1456804Y1063770D03*
X1458653Y1054157D03*
X1454954D03*
X1453104Y1057361D03*
Y1063770D03*
X1454954Y1060565D03*
X1456803Y1057361D03*
X1453103Y1050952D03*
X1445703Y1057361D03*
X1445704Y1063770D03*
X1447554Y1060565D03*
X1449403Y1057361D03*
X1449404Y1063770D03*
X1451254Y1054157D03*
X1445703Y1050952D03*
X1449404D03*
X1454953Y1066974D03*
X1445702Y1070178D03*
X1453104Y1076587D03*
X1456804D03*
Y1070178D03*
X1453104D03*
X1447553Y1073383D03*
X1449404Y1076587D03*
X1445704D03*
X1447553Y1079791D03*
X1451253Y1073383D03*
X1458653D03*
X1445704Y1082995D03*
X1456804Y1089404D03*
X1449404Y1095813D03*
X1454954Y1092607D03*
X1451254D03*
X1449403Y1089403D03*
X1447554Y1086199D03*
X1453103Y1082994D03*
X1458654Y1092607D03*
X1453103Y1095812D03*
X1447554Y1092607D03*
X1451254Y1086199D03*
X1454954D03*
X1456804Y1102221D03*
Y1121447D03*
X1449404D03*
X1456804Y1134264D03*
X1445703D03*
X1465620Y848176D03*
X1473020D03*
X1465620Y860993D03*
X1473020D03*
Y873810D03*
X1465620D03*
X1473020Y886627D03*
X1465620D03*
X1464204Y1095813D03*
X1477154Y1105426D03*
Y1111833D03*
X1464204Y1115039D03*
Y1121447D03*
X1471604Y1134264D03*
X1464204D03*
X1487820Y848176D03*
X1480420D03*
X1487820Y860993D03*
X1480420D03*
X1487820Y873810D03*
X1480420D03*
Y886627D03*
X1487820D03*
X1479004Y1006093D03*
X1486404Y1102221D03*
X1479003Y1108629D03*
X1488254Y1105426D03*
X1484554Y1111833D03*
X1482703Y1102220D03*
X1480854Y1111833D03*
Y1105426D03*
X1486403Y1108630D03*
X1488254Y1111833D03*
X1484554Y1105426D03*
X1479004Y1115039D03*
Y1121447D03*
X1493804D03*
X1486404D03*
X1482703Y1115038D03*
X1479004Y1134264D03*
X1493804D03*
X1486404D03*
X1495220Y848176D03*
Y860993D03*
X1502621D03*
X1495220Y873810D03*
X1502621D03*
X1506320Y893036D03*
X1495220Y886627D03*
X1502621D03*
X1510021D03*
X1506753Y1105426D03*
X1504904Y1102221D03*
X1501204D03*
X1499354Y1099017D03*
X1503053Y1118243D03*
X1510453D03*
X1501204Y1121447D03*
X1508603Y1121446D03*
X1510453Y1124650D03*
X1508603Y1127855D03*
X1501204Y1134264D03*
X1508603Y1140973D03*
X1504903D03*
X1517853Y1118243D03*
X1519703Y1121446D03*
X1516003Y1127855D03*
X1512303D03*
Y1121446D03*
X1516003D03*
X1517853Y1124650D03*
X1519703Y1127855D03*
X1514154Y1131059D03*
X1611475Y1259227D03*
X1714440Y1255381D03*
X1821083Y1252034D03*
G54D40*
X322500Y1391830D03*
X537477Y1395413D03*
X1298642Y1391830D03*
X1513618Y1395413D03*
G54D10*
X27559Y87795D03*
X40708Y631890D03*
Y1368897D03*
X51181Y1714961D03*
X373622Y87795D03*
X395670Y1714961D03*
X661023Y631890D03*
X707677Y1714961D03*
X800787Y87795D03*
X931692Y757874D03*
Y1072834D03*
Y1387795D03*
X1045865Y87795D03*
X1155708Y1714961D03*
X1271260Y631890D03*
X1461805Y1714961D03*
X1499606Y87795D03*
X1816771Y631890D03*
Y1368897D03*
X1806299Y1714961D03*
X1829921Y87795D03*
G54D36*
X238780Y1681456D03*
X230906Y1677519D03*
Y1682244D03*
X238780Y1686180D03*
Y1695629D03*
X230906Y1691692D03*
Y1696417D03*
X238780Y1700354D03*
Y1709803D03*
Y1714527D03*
X230906Y1705866D03*
Y1710590D03*
X238780Y1723976D03*
Y1728700D03*
X230906Y1720039D03*
Y1724763D03*
X254528Y1681456D03*
X246654Y1677519D03*
Y1682244D03*
X254528Y1686180D03*
Y1695629D03*
X246654Y1691692D03*
Y1696417D03*
X254528Y1700354D03*
Y1709803D03*
Y1714527D03*
X246654Y1705866D03*
Y1710590D03*
X254528Y1723976D03*
Y1728700D03*
X246654Y1720039D03*
Y1724763D03*
X270276Y1653110D03*
Y1657834D03*
Y1681456D03*
X262402Y1677519D03*
Y1682244D03*
X270276Y1686180D03*
Y1695629D03*
X262402Y1691692D03*
Y1696417D03*
X270276Y1700354D03*
Y1709803D03*
Y1714527D03*
X262402Y1705866D03*
Y1710590D03*
X270276Y1723976D03*
Y1728700D03*
X262402Y1720039D03*
Y1724763D03*
X286024Y1653110D03*
Y1657834D03*
Y1667283D03*
Y1672007D03*
Y1681456D03*
X278150Y1677519D03*
Y1682244D03*
X286024Y1686180D03*
Y1695629D03*
X278150Y1691692D03*
Y1696417D03*
X286024Y1700354D03*
Y1709803D03*
Y1714527D03*
X278150Y1705866D03*
Y1710590D03*
X286024Y1723976D03*
Y1728700D03*
X278150Y1720039D03*
Y1724763D03*
X297835Y1677519D03*
Y1682244D03*
X305709Y1681456D03*
Y1686180D03*
X297835Y1691692D03*
Y1696417D03*
X305709Y1695629D03*
Y1700354D03*
X297835Y1705866D03*
Y1710590D03*
X305709Y1709803D03*
Y1714527D03*
X297835Y1720039D03*
Y1724763D03*
X305709Y1723976D03*
Y1728700D03*
X313583Y1677519D03*
Y1682244D03*
X321457Y1681456D03*
Y1686180D03*
X313583Y1691692D03*
Y1696417D03*
X321457Y1695629D03*
Y1700354D03*
X313583Y1705866D03*
Y1710590D03*
X321457Y1709803D03*
Y1714527D03*
X313583Y1720039D03*
Y1724763D03*
X321457Y1723976D03*
Y1728700D03*
X329331Y1677519D03*
Y1682244D03*
X337205Y1681456D03*
Y1686180D03*
X329331Y1691692D03*
Y1696417D03*
X337205Y1695629D03*
Y1700354D03*
X329331Y1705866D03*
Y1710590D03*
X337205Y1709803D03*
Y1714527D03*
X329331Y1720039D03*
Y1724763D03*
X337205Y1723976D03*
Y1728700D03*
X345079Y1677519D03*
Y1682244D03*
X352953Y1681456D03*
Y1686180D03*
X345079Y1691692D03*
Y1696417D03*
X352953Y1695629D03*
Y1700354D03*
X345079Y1705866D03*
Y1710590D03*
X352953Y1709803D03*
Y1714527D03*
X345079Y1720039D03*
Y1724763D03*
X352953Y1723976D03*
Y1728700D03*
X495079Y1677519D03*
Y1682244D03*
Y1691692D03*
Y1696417D03*
Y1705866D03*
Y1710590D03*
Y1720039D03*
Y1724763D03*
X510827Y1677519D03*
X502953Y1681456D03*
X510827Y1682244D03*
X502953Y1686180D03*
X510827Y1691692D03*
X502953Y1695629D03*
X510827Y1696417D03*
X502953Y1700354D03*
X510827Y1705866D03*
X502953Y1709803D03*
X510827Y1710590D03*
X502953Y1714527D03*
X510827Y1720039D03*
X502953Y1723976D03*
X510827Y1724763D03*
X502953Y1728700D03*
X526575Y1677519D03*
X518701Y1681456D03*
X526575Y1682244D03*
X534449Y1681456D03*
X518701Y1686180D03*
X534449D03*
X526575Y1691692D03*
X518701Y1695629D03*
X526575Y1696417D03*
X534449Y1695629D03*
X518701Y1700354D03*
X534449D03*
X526575Y1705866D03*
X518701Y1709803D03*
X526575Y1710590D03*
X534449Y1709803D03*
X518701Y1714527D03*
X534449D03*
X526575Y1720039D03*
X518701Y1723976D03*
X526575Y1724763D03*
X534449Y1723976D03*
X518701Y1728700D03*
X534449D03*
X542323Y1677519D03*
Y1682244D03*
X550197Y1681456D03*
Y1686180D03*
X542323Y1691692D03*
Y1696417D03*
X550197Y1695629D03*
Y1700354D03*
X542323Y1705866D03*
Y1710590D03*
X550197Y1709803D03*
Y1714527D03*
X542323Y1720039D03*
Y1724763D03*
X550197Y1723976D03*
Y1728700D03*
X562008Y1677519D03*
Y1682244D03*
Y1691692D03*
Y1696417D03*
Y1705866D03*
Y1710590D03*
Y1720039D03*
Y1724763D03*
X577756Y1677519D03*
X569882Y1681456D03*
X577756Y1682244D03*
X569882Y1686180D03*
X577756Y1691692D03*
X569882Y1695629D03*
X577756Y1696417D03*
X569882Y1700354D03*
X577756Y1705866D03*
X569882Y1709803D03*
X577756Y1710590D03*
X569882Y1714527D03*
X577756Y1720039D03*
X569882Y1723976D03*
X577756Y1724763D03*
X569882Y1728700D03*
X593504Y1677519D03*
X585630Y1681456D03*
X593504Y1682244D03*
X585630Y1686180D03*
X593504Y1691692D03*
X585630Y1695629D03*
X593504Y1696417D03*
X585630Y1700354D03*
X593504Y1705866D03*
X585630Y1709803D03*
X593504Y1710590D03*
X585630Y1714527D03*
X593504Y1720039D03*
X585630Y1723976D03*
X593504Y1724763D03*
X585630Y1728700D03*
X609252Y1677519D03*
X601378Y1681456D03*
X609252Y1682244D03*
X601378Y1686180D03*
X609252Y1691692D03*
X601378Y1695629D03*
X609252Y1696417D03*
X601378Y1700354D03*
X609252Y1705866D03*
X601378Y1709803D03*
X609252Y1710590D03*
X601378Y1714527D03*
X609252Y1720039D03*
X601378Y1723976D03*
X609252Y1724763D03*
X601378Y1728700D03*
X617126Y1681456D03*
Y1686180D03*
Y1695629D03*
Y1700354D03*
Y1709803D03*
Y1714527D03*
Y1723976D03*
Y1728700D03*
X1238780Y1677519D03*
Y1682244D03*
X1246654Y1681456D03*
Y1686180D03*
X1238780Y1691692D03*
Y1696417D03*
X1246654Y1695629D03*
Y1700354D03*
X1238780Y1705866D03*
Y1710590D03*
X1246654Y1709803D03*
Y1714527D03*
X1238780Y1720039D03*
Y1724763D03*
X1246654Y1723976D03*
Y1728700D03*
X1254528Y1677519D03*
Y1682244D03*
X1262402Y1681456D03*
Y1686180D03*
X1254528Y1691692D03*
Y1696417D03*
X1262402Y1695629D03*
Y1700354D03*
X1254528Y1705866D03*
Y1710590D03*
X1262402Y1709803D03*
Y1714527D03*
X1254528Y1720039D03*
Y1724763D03*
X1262402Y1723976D03*
Y1728700D03*
X1270276Y1677519D03*
Y1682244D03*
X1278150Y1681456D03*
Y1686180D03*
X1270276Y1691692D03*
Y1696417D03*
X1278150Y1695629D03*
Y1700354D03*
X1270276Y1705866D03*
Y1710590D03*
X1278150Y1709803D03*
Y1714527D03*
X1270276Y1720039D03*
Y1724763D03*
X1278150Y1723976D03*
Y1728700D03*
X1286024Y1677519D03*
Y1682244D03*
X1293898Y1681456D03*
Y1686180D03*
X1286024Y1691692D03*
Y1696417D03*
X1293898Y1695629D03*
Y1700354D03*
X1286024Y1705866D03*
Y1710590D03*
X1293898Y1709803D03*
Y1714527D03*
X1286024Y1720039D03*
Y1724763D03*
X1293898Y1723976D03*
Y1728700D03*
X1305709Y1677519D03*
Y1682244D03*
X1313583Y1681456D03*
Y1686180D03*
X1305709Y1691692D03*
Y1696417D03*
X1313583Y1695629D03*
Y1700354D03*
X1305709Y1705866D03*
Y1710590D03*
X1313583Y1709803D03*
Y1714527D03*
X1305709Y1720039D03*
Y1724763D03*
X1313583Y1723976D03*
Y1728700D03*
X1321457Y1677519D03*
Y1682244D03*
X1329331Y1681456D03*
Y1686180D03*
X1321457Y1691692D03*
Y1696417D03*
X1329331Y1695629D03*
Y1700354D03*
X1321457Y1705866D03*
Y1710590D03*
X1329331Y1709803D03*
Y1714527D03*
X1321457Y1720039D03*
Y1724763D03*
X1329331Y1723976D03*
Y1728700D03*
X1337205Y1677519D03*
Y1682244D03*
X1345079Y1681456D03*
Y1686180D03*
X1337205Y1691692D03*
Y1696417D03*
X1345079Y1695629D03*
Y1700354D03*
X1337205Y1705866D03*
Y1710590D03*
X1345079Y1709803D03*
Y1714527D03*
X1337205Y1720039D03*
Y1724763D03*
X1345079Y1723976D03*
Y1728700D03*
X1352953Y1677519D03*
Y1682244D03*
X1360827Y1681456D03*
Y1686180D03*
X1352953Y1691692D03*
Y1696417D03*
X1360827Y1695629D03*
Y1700354D03*
X1352953Y1705866D03*
Y1710590D03*
X1360827Y1709803D03*
Y1714527D03*
X1352953Y1720039D03*
Y1724763D03*
X1360827Y1723976D03*
Y1728700D03*
X1502953Y1677519D03*
Y1682244D03*
X1510827Y1681456D03*
Y1686180D03*
X1502953Y1691692D03*
Y1696417D03*
X1510827Y1695629D03*
Y1700354D03*
X1502953Y1705866D03*
Y1710590D03*
X1510827Y1709803D03*
Y1714527D03*
X1502953Y1720039D03*
Y1724763D03*
X1510827Y1723976D03*
Y1728700D03*
X1518701Y1677519D03*
Y1682244D03*
X1526575Y1681456D03*
Y1686180D03*
X1518701Y1691692D03*
Y1696417D03*
X1526575Y1695629D03*
Y1700354D03*
X1518701Y1705866D03*
Y1710590D03*
X1526575Y1709803D03*
Y1714527D03*
X1518701Y1720039D03*
Y1724763D03*
X1526575Y1723976D03*
Y1728700D03*
X1534449Y1677519D03*
Y1682244D03*
X1542323Y1681456D03*
Y1686180D03*
X1534449Y1691692D03*
Y1696417D03*
X1542323Y1695629D03*
Y1700354D03*
X1534449Y1705866D03*
Y1710590D03*
X1542323Y1709803D03*
Y1714527D03*
X1534449Y1720039D03*
Y1724763D03*
X1542323Y1723976D03*
Y1728700D03*
X1550197Y1677519D03*
Y1682244D03*
X1558071Y1681456D03*
Y1686180D03*
X1550197Y1691692D03*
Y1696417D03*
X1558071Y1695629D03*
Y1700354D03*
X1550197Y1705866D03*
Y1710590D03*
X1558071Y1709803D03*
Y1714527D03*
X1550197Y1720039D03*
Y1724763D03*
X1558071Y1723976D03*
Y1728700D03*
X1569882Y1677519D03*
Y1682244D03*
Y1691692D03*
Y1696417D03*
Y1705866D03*
Y1710590D03*
Y1720039D03*
Y1724763D03*
X1585630Y1677519D03*
X1577756Y1681456D03*
X1585630Y1682244D03*
X1577756Y1686180D03*
X1585630Y1691692D03*
X1577756Y1695629D03*
X1585630Y1696417D03*
X1577756Y1700354D03*
X1585630Y1705866D03*
X1577756Y1709803D03*
X1585630Y1710590D03*
X1577756Y1714527D03*
X1585630Y1720039D03*
X1577756Y1723976D03*
X1585630Y1724763D03*
X1577756Y1728700D03*
X1601378Y1677519D03*
X1593504Y1681456D03*
X1601378Y1682244D03*
X1593504Y1686180D03*
X1601378Y1691692D03*
X1593504Y1695629D03*
X1601378Y1696417D03*
X1593504Y1700354D03*
X1601378Y1705866D03*
X1593504Y1709803D03*
X1601378Y1710590D03*
X1593504Y1714527D03*
X1601378Y1720039D03*
X1593504Y1723976D03*
X1601378Y1724763D03*
X1593504Y1728700D03*
X1617126Y1677519D03*
X1609252Y1681456D03*
X1617126Y1682244D03*
X1609252Y1686180D03*
X1617126Y1691692D03*
X1609252Y1695629D03*
X1617126Y1696417D03*
X1609252Y1700354D03*
X1617126Y1705866D03*
X1609252Y1709803D03*
X1617126Y1710590D03*
X1609252Y1714527D03*
X1617126Y1720039D03*
X1609252Y1723976D03*
X1617126Y1724763D03*
X1609252Y1728700D03*
X1625000Y1681456D03*
Y1686180D03*
Y1695629D03*
Y1700354D03*
Y1709803D03*
Y1714527D03*
Y1723976D03*
Y1728700D03*
G54D37*
X277098Y185236D03*
X395208D03*
G54D32*
X205159Y1430034D03*
X393067Y1354446D03*
X422833D03*
X453169D03*
X468443Y1379662D03*
X482543Y1353962D03*
X718638Y1429579D03*
X1178470Y1466363D03*
X1369208Y1353946D03*
X1398974D03*
X1429310D03*
X1444043Y1379362D03*
X1459076Y1353946D03*
X1679944Y1463655D03*
X1836248Y269763D03*
Y299056D03*
G54D30*
X174685Y637367D03*
X174393Y668511D03*
X526478Y1439952D03*
X1502956Y1439530D03*
X1682882Y618174D03*
Y669109D03*
X1769790Y194789D03*
X1799350D03*
G54D48*
X493500Y246362D03*
X559236Y1441207D03*
G54D51*
X688500Y1601900D03*
X1041435Y153357D03*
X1056225Y153131D03*
X1099970Y1702570D03*
G54D66*
X1133779Y1653543D03*
G54D38*
X278126Y676260D03*
Y700414D03*
X395771Y1242785D03*
X420171D03*
X444493D03*
X468893D03*
X493293D03*
X1371912D03*
X1396312D03*
X1420634D03*
X1445034D03*
X1469434D03*
G54D28*
X159474Y1320753D03*
X183847Y1320778D03*
X208247D03*
X275289Y575702D03*
Y599861D03*
Y624015D03*
Y648169D03*
X673093Y1320778D03*
X697466Y1320803D03*
X721866D03*
X1100800Y251488D03*
X1100700Y275788D03*
X1131100Y1357088D03*
X1155500D03*
X1179900D03*
X1577000Y591888D03*
Y616388D03*
Y640888D03*
Y665288D03*
Y689788D03*
Y714288D03*
X1634259Y1354374D03*
X1658632Y1354399D03*
X1683032D03*
G54D78*
X1902608Y988322D03*
X1902682Y1351295D03*
X1951178Y1349597D03*
X1993618Y1349897D03*
G54D75*
X1881720Y988279D03*
X1881211Y1350983D03*
X1930200Y1349548D03*
X1972697Y1349606D03*
G54D22*
X40120Y744554D03*
Y1000853D03*
Y1287664D03*
X69820Y744554D03*
Y1000853D03*
Y1287664D03*
X99520Y744554D03*
Y1000853D03*
Y1287664D03*
X129220Y744554D03*
Y1000853D03*
Y1287664D03*
X158920Y744554D03*
Y1000853D03*
Y1287664D03*
X188620Y744554D03*
Y1000853D03*
Y1287664D03*
X218320Y744554D03*
Y1000853D03*
Y1287664D03*
X248020Y744554D03*
Y1000853D03*
Y1287664D03*
X633320Y744554D03*
Y1000853D03*
Y1287664D03*
X663020Y744554D03*
Y1000853D03*
Y1287664D03*
X692720Y744554D03*
Y1000853D03*
Y1287664D03*
X722420Y744554D03*
Y1000853D03*
Y1287664D03*
X752120Y744554D03*
Y1000853D03*
Y1287664D03*
X781820Y744554D03*
Y1000853D03*
Y1287664D03*
X811520Y744554D03*
Y1000853D03*
Y1287664D03*
X841220Y744554D03*
Y1000853D03*
Y1287664D03*
X1016262Y744554D03*
Y1000853D03*
Y1287664D03*
X1045962Y744554D03*
Y1000853D03*
Y1287664D03*
X1075662Y744554D03*
Y1000853D03*
Y1287664D03*
X1105362Y744554D03*
Y1000853D03*
Y1287664D03*
X1135062Y744554D03*
Y1000853D03*
Y1287664D03*
X1164762Y744554D03*
Y1000853D03*
Y1287664D03*
X1194462Y744554D03*
Y1000853D03*
Y1287664D03*
X1224162Y744554D03*
Y1000853D03*
Y1287664D03*
X1609462Y744554D03*
Y1000853D03*
Y1287664D03*
X1639162Y744554D03*
Y1000853D03*
Y1287664D03*
X1668862Y744554D03*
Y1000853D03*
Y1287664D03*
X1698562Y744554D03*
Y1000853D03*
Y1287664D03*
X1728262Y744554D03*
Y1000853D03*
Y1287664D03*
X1757962Y744554D03*
Y1000853D03*
Y1287664D03*
X1787662Y744554D03*
Y1000853D03*
Y1287664D03*
X1817362Y744554D03*
Y1000853D03*
Y1287664D03*
G54D61*
X928739Y321653D03*
G54D33*
X250326Y185236D03*
X368437D03*
G54D62*
X916545Y309459D03*
X911494Y321653D03*
X916545Y333847D03*
X940933Y309459D03*
X928739Y304408D03*
Y338898D03*
X940933Y333847D03*
X945984Y321653D03*
G54D68*
X1247638Y269488D03*
X1405118Y112008D03*
X1766929Y1714960D03*
G54D13*
X19685Y-29134D03*
Y1803261D03*
X1837795Y-29134D03*
Y1803261D03*
X2081889Y-29134D03*
Y1803261D03*
G54D69*
X1405876Y1453298D03*
X1430204Y1452014D03*
G54D18*
X38346Y1420330D03*
X117932Y605380D03*
X763601Y605413D03*
X1094074Y605380D03*
X1739706Y605455D03*
X1819208Y1420330D03*
G54D21*
X49280Y337402D03*
X41870Y1511291D03*
X441043Y1672205D03*
Y1718465D03*
X1416437Y1672204D03*
Y1718464D03*
X1808192Y1569255D03*
X1812980Y502472D03*
G54D39*
X306772Y991220D03*
X350099Y811121D03*
X356063Y1171318D03*
X531240Y811121D03*
X525276Y1171318D03*
X574567Y991220D03*
X1282914D03*
X1326240Y811121D03*
X1332205Y1171318D03*
X1507382Y811121D03*
X1501418Y1171318D03*
X1550709Y991220D03*
G54D54*
X791280Y1704890D03*
X1066280D03*
G54D34*
X238780Y1648385D03*
X230906Y1644448D03*
X238780Y1662558D03*
X230906Y1658621D03*
X238780Y1676732D03*
X230906Y1672795D03*
X238780Y1690905D03*
X230906Y1686968D03*
X238780Y1705078D03*
X230906Y1701141D03*
Y1715314D03*
X238780Y1719251D03*
X230906Y1729488D03*
X238780Y1733425D03*
X254528Y1648385D03*
X246654Y1644448D03*
X254528Y1662558D03*
X246654Y1658621D03*
X254528Y1676732D03*
X246654Y1672795D03*
X254528Y1690905D03*
X246654Y1686968D03*
X254528Y1705078D03*
X246654Y1701141D03*
Y1715314D03*
X254528Y1719251D03*
X246654Y1729488D03*
X254528Y1733425D03*
X270276Y1648385D03*
X262402Y1644448D03*
X270276Y1662558D03*
X262402Y1658621D03*
X270276Y1676732D03*
X262402Y1672795D03*
X270276Y1690905D03*
X262402Y1686968D03*
X270276Y1705078D03*
X262402Y1701141D03*
Y1715314D03*
X270276Y1719251D03*
X262402Y1729488D03*
X270276Y1733425D03*
X286024Y1648385D03*
X278150Y1644448D03*
X286024Y1662558D03*
X278150Y1658621D03*
X286024Y1676732D03*
X278150Y1672795D03*
X286024Y1690905D03*
X278150Y1686968D03*
X286024Y1705078D03*
X278150Y1701141D03*
Y1715314D03*
X286024Y1719251D03*
X278150Y1729488D03*
X286024Y1733425D03*
X297835Y1672795D03*
X305709Y1676732D03*
X297835Y1686968D03*
X305709Y1690905D03*
X297835Y1701141D03*
X305709Y1705078D03*
X297835Y1715314D03*
X305709Y1719251D03*
X297835Y1729488D03*
X305709Y1733425D03*
X313583Y1672795D03*
X321457Y1676732D03*
X313583Y1686968D03*
X321457Y1690905D03*
X313583Y1701141D03*
X321457Y1705078D03*
X313583Y1715314D03*
X321457Y1719251D03*
X313583Y1729488D03*
X321457Y1733425D03*
X329331Y1672795D03*
X337205Y1676732D03*
X329331Y1686968D03*
X337205Y1690905D03*
X329331Y1701141D03*
X337205Y1705078D03*
X329331Y1715314D03*
X337205Y1719251D03*
X329331Y1729488D03*
X337205Y1733425D03*
X345079Y1672795D03*
X352953Y1676732D03*
X345079Y1686968D03*
X352953Y1690905D03*
X345079Y1701141D03*
X352953Y1705078D03*
X345079Y1715314D03*
X352953Y1719251D03*
X345079Y1729488D03*
X352953Y1733425D03*
X495079Y1672795D03*
Y1686968D03*
Y1701141D03*
Y1715314D03*
Y1729488D03*
X510827Y1672795D03*
X502953Y1676732D03*
X518701D03*
X510827Y1686968D03*
X502953Y1690905D03*
X518701D03*
X510827Y1701141D03*
X502953Y1705078D03*
X518701D03*
X510827Y1715314D03*
X502953Y1719251D03*
X518701D03*
X510827Y1729488D03*
X502953Y1733425D03*
X518701D03*
X526575Y1672795D03*
X534449Y1676732D03*
X526575Y1686968D03*
X534449Y1690905D03*
X526575Y1701141D03*
X534449Y1705078D03*
X526575Y1715314D03*
X534449Y1719251D03*
X526575Y1729488D03*
X534449Y1733425D03*
X542323Y1672795D03*
X550197Y1676732D03*
X542323Y1686968D03*
X550197Y1690905D03*
X542323Y1701141D03*
X550197Y1705078D03*
X542323Y1715314D03*
X550197Y1719251D03*
X542323Y1729488D03*
X550197Y1733425D03*
X562008Y1672795D03*
Y1686968D03*
Y1701141D03*
Y1715314D03*
Y1729488D03*
X577756Y1672795D03*
X569882Y1676732D03*
X577756Y1686968D03*
X569882Y1690905D03*
X577756Y1701141D03*
X569882Y1705078D03*
X577756Y1715314D03*
X569882Y1719251D03*
X577756Y1729488D03*
X569882Y1733425D03*
X593504Y1672795D03*
X585630Y1676732D03*
X593504Y1686968D03*
X585630Y1690905D03*
X593504Y1701141D03*
X585630Y1705078D03*
X593504Y1715314D03*
X585630Y1719251D03*
X593504Y1729488D03*
X585630Y1733425D03*
X609252Y1672795D03*
X601378Y1676732D03*
X609252Y1686968D03*
X601378Y1690905D03*
X609252Y1701141D03*
X601378Y1705078D03*
X609252Y1715314D03*
X601378Y1719251D03*
X609252Y1729488D03*
X601378Y1733425D03*
X617126Y1676732D03*
Y1690905D03*
Y1705078D03*
Y1719251D03*
Y1733425D03*
X1238780Y1672795D03*
X1246654Y1676732D03*
X1238780Y1686968D03*
X1246654Y1690905D03*
X1238780Y1701141D03*
X1246654Y1705078D03*
X1238780Y1715314D03*
X1246654Y1719251D03*
X1238780Y1729488D03*
X1246654Y1733425D03*
X1254528Y1672795D03*
X1262402Y1676732D03*
X1254528Y1686968D03*
X1262402Y1690905D03*
X1254528Y1701141D03*
X1262402Y1705078D03*
X1254528Y1715314D03*
X1262402Y1719251D03*
X1254528Y1729488D03*
X1262402Y1733425D03*
X1270276Y1672795D03*
X1278150Y1676732D03*
X1270276Y1686968D03*
X1278150Y1690905D03*
X1270276Y1701141D03*
X1278150Y1705078D03*
X1270276Y1715314D03*
X1278150Y1719251D03*
X1270276Y1729488D03*
X1278150Y1733425D03*
X1286024Y1672795D03*
X1293898Y1676732D03*
X1286024Y1686968D03*
X1293898Y1690905D03*
X1286024Y1701141D03*
X1293898Y1705078D03*
X1286024Y1715314D03*
X1293898Y1719251D03*
X1286024Y1729488D03*
X1293898Y1733425D03*
X1305709Y1672795D03*
X1313583Y1676732D03*
X1305709Y1686968D03*
X1313583Y1690905D03*
X1305709Y1701141D03*
X1313583Y1705078D03*
X1305709Y1715314D03*
X1313583Y1719251D03*
X1305709Y1729488D03*
X1313583Y1733425D03*
X1321457Y1672795D03*
X1329331Y1676732D03*
X1321457Y1686968D03*
X1329331Y1690905D03*
X1321457Y1701141D03*
X1329331Y1705078D03*
X1321457Y1715314D03*
X1329331Y1719251D03*
X1321457Y1729488D03*
X1329331Y1733425D03*
X1337205Y1672795D03*
X1345079Y1676732D03*
X1337205Y1686968D03*
X1345079Y1690905D03*
X1337205Y1701141D03*
X1345079Y1705078D03*
X1337205Y1715314D03*
X1345079Y1719251D03*
X1337205Y1729488D03*
X1345079Y1733425D03*
X1352953Y1672795D03*
X1360827Y1676732D03*
X1352953Y1686968D03*
X1360827Y1690905D03*
X1352953Y1701141D03*
X1360827Y1705078D03*
X1352953Y1715314D03*
X1360827Y1719251D03*
X1352953Y1729488D03*
X1360827Y1733425D03*
X1502953Y1672795D03*
X1510827Y1676732D03*
X1502953Y1686968D03*
X1510827Y1690905D03*
X1502953Y1701141D03*
X1510827Y1705078D03*
X1502953Y1715314D03*
X1510827Y1719251D03*
X1502953Y1729488D03*
X1510827Y1733425D03*
X1518701Y1672795D03*
X1526575Y1676732D03*
X1518701Y1686968D03*
X1526575Y1690905D03*
X1518701Y1701141D03*
X1526575Y1705078D03*
X1518701Y1715314D03*
X1526575Y1719251D03*
X1518701Y1729488D03*
X1526575Y1733425D03*
X1534449Y1672795D03*
X1542323Y1676732D03*
X1534449Y1686968D03*
X1542323Y1690905D03*
X1534449Y1701141D03*
X1542323Y1705078D03*
X1534449Y1715314D03*
X1542323Y1719251D03*
X1534449Y1729488D03*
X1542323Y1733425D03*
X1550197Y1672795D03*
X1558071Y1676732D03*
X1550197Y1686968D03*
X1558071Y1690905D03*
X1550197Y1701141D03*
X1558071Y1705078D03*
X1550197Y1715314D03*
X1558071Y1719251D03*
X1550197Y1729488D03*
X1558071Y1733425D03*
X1569882Y1672795D03*
Y1686968D03*
Y1701141D03*
Y1715314D03*
Y1729488D03*
X1585630Y1672795D03*
X1577756Y1676732D03*
X1585630Y1686968D03*
X1577756Y1690905D03*
X1585630Y1701141D03*
X1577756Y1705078D03*
X1585630Y1715314D03*
X1577756Y1719251D03*
X1585630Y1729488D03*
X1577756Y1733425D03*
X1601378Y1672795D03*
X1593504Y1676732D03*
X1601378Y1686968D03*
X1593504Y1690905D03*
X1601378Y1701141D03*
X1593504Y1705078D03*
X1601378Y1715314D03*
X1593504Y1719251D03*
X1601378Y1729488D03*
X1593504Y1733425D03*
X1617126Y1672795D03*
X1609252Y1676732D03*
X1625000D03*
X1617126Y1686968D03*
X1609252Y1690905D03*
X1625000D03*
X1617126Y1701141D03*
X1609252Y1705078D03*
X1625000D03*
X1617126Y1715314D03*
X1609252Y1719251D03*
X1625000D03*
X1617126Y1729488D03*
X1609252Y1733425D03*
X1625000D03*
G54D45*
X441043Y1698268D03*
X1416437Y1698267D03*
G54D56*
X805690Y204724D03*
X1057658D03*
G54D20*
X41492Y290637D03*
X44833Y1659909D03*
X61340Y384362D03*
X61250Y396142D03*
X49250Y396332D03*
X49400Y384392D03*
X47618Y413113D03*
X47619Y421155D03*
X56799Y1524094D03*
Y1528094D03*
Y1532094D03*
Y1544094D03*
Y1548094D03*
Y1552094D03*
Y1556094D03*
X54333Y1604359D03*
X50900Y1677775D03*
X65881Y305426D03*
X72774Y1549669D03*
X66906Y1598324D03*
Y1603280D03*
X84274Y1517619D03*
X81038Y1536899D03*
X91538Y1539399D03*
X84700Y1627000D03*
X99274Y1526019D03*
X126225Y504368D03*
X120225D03*
Y510368D03*
X126225Y516368D03*
X120225D03*
X112749Y1524594D03*
Y1540594D03*
Y1544594D03*
Y1548594D03*
Y1536594D03*
Y1564594D03*
Y1560594D03*
X132225Y504368D03*
Y510368D03*
X132401Y516368D03*
X129670Y1563160D03*
X153271Y1540961D03*
X153138Y1549032D03*
X166986Y575918D03*
X161321Y1540858D03*
X161374Y1549073D03*
X189800Y705062D03*
X208312Y576125D03*
X196526Y567825D03*
X208312Y581085D03*
Y578605D03*
X197423Y601496D03*
X194059Y604901D03*
X208312Y615085D03*
Y610125D03*
Y612605D03*
X194059Y638901D03*
X197423Y635496D03*
X208312Y649085D03*
Y644125D03*
Y646605D03*
X213912Y576125D03*
X220668Y574131D03*
X223775D03*
X224064Y568113D03*
X221464D03*
X213912Y578605D03*
Y581085D03*
X217556Y590575D03*
X217561Y582131D03*
Y579531D03*
X223775Y587731D03*
X223759Y590675D03*
X220652D03*
X223775Y584531D03*
X220668Y576731D03*
Y579331D03*
X223775Y581931D03*
Y579331D03*
Y576731D03*
X220668Y581931D03*
Y608131D03*
X223775D03*
X224064Y602113D03*
X221464D03*
X223403Y596820D03*
Y594220D03*
X213912Y612605D03*
Y615085D03*
Y610125D03*
X217561Y616131D03*
Y613531D03*
X217556Y624575D03*
X223759Y624675D03*
X220652D03*
X223775Y618531D03*
X220668Y610731D03*
Y613331D03*
X223775Y615931D03*
Y613331D03*
Y610731D03*
X220668Y615931D03*
X223775Y621731D03*
X223403Y630820D03*
Y628220D03*
X224064Y636113D03*
X221464D03*
X213912Y646605D03*
Y649085D03*
Y644125D03*
X217561Y650131D03*
Y647531D03*
X223775Y655731D03*
Y652531D03*
X220668Y644731D03*
Y647331D03*
Y642131D03*
X223775Y649931D03*
Y647331D03*
Y644731D03*
Y642131D03*
X220668Y649931D03*
X217556Y658575D03*
X223403Y664820D03*
X223759Y658675D03*
X220652D03*
X217510Y668712D03*
X225167Y672006D03*
X222567D03*
X219967D03*
X217367D03*
X211348Y688087D03*
Y685287D03*
X214100Y687376D03*
Y690376D03*
Y684376D03*
Y681376D03*
Y678376D03*
X211348Y690787D03*
Y693587D03*
X214100Y693576D03*
X224506Y698138D03*
Y700738D03*
X221906Y698138D03*
Y700738D03*
X219306D03*
Y698138D03*
X231864Y568113D03*
X229264D03*
X226664D03*
X238393Y570490D03*
X240993D03*
X229264Y602113D03*
X226664D03*
X226003Y594220D03*
Y596820D03*
X228603Y594220D03*
Y596820D03*
X231864Y602113D03*
X233803Y594220D03*
Y596820D03*
X231203Y594220D03*
Y596820D03*
X238393Y604490D03*
X240993D03*
Y596820D03*
X238393D03*
X240993Y594220D03*
X238393D03*
X226003Y628220D03*
Y630820D03*
X228603Y628220D03*
Y630820D03*
X231864Y636113D03*
X233803Y628220D03*
Y630820D03*
X231203Y628220D03*
Y630820D03*
X229264Y636113D03*
X226664D03*
X238393Y638490D03*
X240993D03*
Y630820D03*
X238393D03*
X240993Y628220D03*
X238393D03*
X228603Y664820D03*
X233803D03*
X231203D03*
X226003D03*
X230367Y672006D03*
X227767D03*
X227106Y698138D03*
Y700738D03*
X246400Y563162D03*
X263580Y218627D03*
X318651Y22921D03*
X320825Y159062D03*
X410700Y1658460D03*
X435340Y125346D03*
X435240Y1609200D03*
X433383Y1602629D03*
X450380Y104647D03*
X440019Y1576809D03*
X442128Y1574879D03*
X441308Y1602654D03*
X505055Y1387601D03*
Y1382301D03*
Y1396001D03*
Y1398601D03*
Y1390201D03*
X563634Y1334315D03*
X561034D03*
X612670Y142872D03*
X612520Y154812D03*
X624610Y142842D03*
X624520Y154622D03*
X702975Y414864D03*
X739206Y608020D03*
Y603064D03*
X758830Y1674823D03*
X819114Y115223D03*
X824498Y145198D03*
X831114Y115223D03*
X829114Y150273D03*
X854577Y99651D03*
X876124Y66072D03*
Y86072D03*
Y106072D03*
Y126072D03*
X887869Y386618D03*
X881372Y920655D03*
X898062Y976652D03*
Y969716D03*
X942646Y400793D03*
X946865Y974077D03*
X953235Y972642D03*
X946938Y991162D03*
X943720Y985772D03*
X956022Y1620730D03*
X953022D03*
Y1632730D03*
X956022D03*
Y1629730D03*
X953022D03*
X956022Y1626730D03*
X953022D03*
Y1623730D03*
X956022D03*
X963610Y981292D03*
X959535Y990477D03*
X963780Y997496D03*
X966852Y1585920D03*
X969852D03*
X960852D03*
X963852D03*
X957852D03*
X962022Y1620730D03*
X959022D03*
Y1632730D03*
X962022D03*
Y1629730D03*
X959022D03*
X962022Y1626730D03*
X959022D03*
Y1623730D03*
X962022D03*
X978403Y-9022D03*
Y-13978D03*
Y-19022D03*
Y-23978D03*
Y6022D03*
Y10978D03*
Y20978D03*
Y16022D03*
X988835Y185443D03*
X989500Y376362D03*
X985672Y432961D03*
X987662Y1620870D03*
Y1629870D03*
Y1626870D03*
Y1623870D03*
Y1632870D03*
X1002500Y266862D03*
X991770Y418835D03*
X992608Y432961D03*
X1002640Y594692D03*
X1002782Y1585920D03*
X999782D03*
X996782D03*
X990782D03*
X993782D03*
X990662Y1620870D03*
X993662D03*
Y1629870D03*
X990662D03*
X993662Y1626870D03*
X990662D03*
Y1623870D03*
X993662D03*
X990662Y1632870D03*
X993662D03*
X1001810Y1662700D03*
Y1665200D03*
X1018000Y263862D03*
X1022000Y264362D03*
X1014500Y263862D03*
X1010500D03*
X1018000Y266862D03*
X1010500D03*
X1006500D03*
X1014500D03*
X1011611Y430038D03*
X1021942Y1586090D03*
X1019252Y1620870D03*
X1022252D03*
Y1623870D03*
Y1626870D03*
X1019252Y1623870D03*
Y1626870D03*
X1019910Y1662700D03*
Y1665200D03*
X1025000Y264362D03*
X1038220Y589862D03*
X1030980Y598722D03*
X1023740Y596152D03*
X1036480Y596272D03*
X1030942Y1586090D03*
X1033942D03*
X1024942D03*
X1027942D03*
X1025252Y1620870D03*
Y1623870D03*
Y1626870D03*
X1023580Y1662700D03*
Y1665200D03*
X1027370Y1662700D03*
Y1665200D03*
X1040924Y286073D03*
X1043720Y589362D03*
X1050200Y598062D03*
X1050390Y604172D03*
X1053200Y612162D03*
X1053612Y1586010D03*
X1050721Y1633043D03*
X1053721D03*
Y1624043D03*
Y1627043D03*
Y1630043D03*
X1050721Y1624043D03*
Y1627043D03*
Y1630043D03*
X1053721Y1621043D03*
X1050721D03*
X1044850Y1665050D03*
Y1662550D03*
X1067718Y288500D03*
X1070618D03*
X1056280Y601232D03*
X1062612Y1586010D03*
X1065612D03*
X1056612D03*
X1059612D03*
X1056721Y1633043D03*
Y1624043D03*
Y1627043D03*
Y1630043D03*
Y1621043D03*
X1092302Y1585650D03*
X1089302D03*
X1098302D03*
X1095302D03*
X1095900Y1646935D03*
X1095649Y1638875D03*
X1099457D03*
X1104457Y1675490D03*
X1120544Y312200D03*
X1129995Y301637D03*
X1150914Y197407D03*
X1148354Y222677D03*
X1150272Y638346D03*
X1160720Y180862D03*
X1165000Y190962D03*
X1162500D03*
X1164300Y197262D03*
X1163732Y204887D03*
X1160732D03*
X1158172Y230157D03*
X1159912Y638216D03*
X1166722Y636206D03*
X1158762Y642266D03*
X1168402Y642136D03*
X1159930Y1645632D03*
X1164830D03*
X1161613Y1669112D03*
X1173065Y194174D03*
X1172865Y210174D03*
X1172795Y222174D03*
X1180398Y289814D03*
X1171540Y310902D03*
X1176362Y636076D03*
X1180262Y642216D03*
X1181930Y1645632D03*
X1186830D03*
X1175830D03*
X1170930D03*
X1183613Y1669112D03*
X1172613D03*
X1189902Y642086D03*
X1192500Y1645942D03*
X1197400D03*
X1194183Y1669422D03*
X1192340Y1691422D03*
X1197240D03*
X1194023Y1714902D03*
X1206093Y120362D03*
X1214593Y168962D03*
X1208518Y174162D03*
X1203858Y185451D03*
X1208365Y271151D03*
X1210457Y1658415D03*
X1218810Y1691732D03*
X1213910D03*
X1203110Y1691467D03*
X1208010D03*
X1215593Y1715212D03*
X1204793Y1714947D03*
X1228704Y112122D03*
X1223100Y127300D03*
X1226093Y152792D03*
X1227500Y380400D03*
X1242520Y165362D03*
X1236593Y209562D03*
X1236584Y217462D03*
X1245614Y227462D03*
X1266093Y129962D03*
X1256093Y143462D03*
X1264685Y175506D03*
X1279485Y105752D03*
X1278949Y123567D03*
X1282293Y248962D03*
X1275557Y269477D03*
Y272436D03*
X1282653Y269446D03*
X1278557Y272436D03*
Y269477D03*
X1272557Y272436D03*
X1287795Y-29033D03*
Y-33989D03*
Y-9033D03*
Y-13989D03*
Y-19033D03*
Y-23989D03*
Y967D03*
Y-3989D03*
X1293430Y84072D03*
X1294354Y105912D03*
X1295053Y140181D03*
X1292293Y143162D03*
X1287943Y233748D03*
X1284437Y230280D03*
X1293893Y237962D03*
X1286611Y260908D03*
X1295887Y315571D03*
X1314741Y68652D03*
X1300454Y95302D03*
X1302964Y124633D03*
X1301993Y140462D03*
X1313950Y261612D03*
X1308790Y290172D03*
X1302450Y290072D03*
X1307798Y287561D03*
X1313246Y287631D03*
X1308220Y304262D03*
X1303120Y304162D03*
X1330102Y59025D03*
X1327920Y84418D03*
X1316478Y92970D03*
X1330273Y128373D03*
X1326493Y249562D03*
X1317893Y257462D03*
X1328393Y264262D03*
X1339280Y126175D03*
X1356223Y131569D03*
X1362793Y145262D03*
X1366124Y101529D03*
X1377597Y197604D03*
X1375300Y208422D03*
X1378452Y236055D03*
X1389609Y145291D03*
X1389443Y147859D03*
X1386780Y197668D03*
X1395321D03*
X1409558Y151948D03*
Y156904D03*
X1401240Y171672D03*
X1404071Y197668D03*
X1412851D03*
X1398700Y1597800D03*
X1436436Y300319D03*
X1456423Y209362D03*
X1453823Y205982D03*
X1445777Y362021D03*
X1449296Y410497D03*
X1451580Y1627990D03*
X1462777Y362021D03*
X1470877Y374496D03*
X1463277Y406446D03*
X1470954D03*
X1476570Y1657974D03*
X1480154Y-29033D03*
Y-33989D03*
Y-9033D03*
Y-13989D03*
Y-19033D03*
Y-23989D03*
Y967D03*
Y-3989D03*
X1481155Y1387742D03*
X1481255Y1382042D03*
X1481155Y1396342D03*
Y1398942D03*
Y1390342D03*
X1478724Y1637189D03*
X1505821Y215802D03*
X1524770Y195792D03*
X1521201Y215551D03*
X1531750Y199762D03*
X1529610Y211614D03*
X1532590Y225432D03*
X1561494Y584292D03*
X1604040Y219692D03*
X1604290Y242472D03*
X1636393Y181778D03*
X1632899Y213012D03*
X1670004Y537065D03*
Y543065D03*
Y531065D03*
X1683394Y469878D03*
X1683476Y473378D03*
X1684356Y476290D03*
X1681602Y485180D03*
X1684356Y485628D03*
X1677464Y491790D03*
X1682004Y537065D03*
X1682180Y543065D03*
X1676004D03*
X1682004Y531065D03*
X1676004D03*
X1697648Y463724D03*
X1693648D03*
X1692883Y703943D03*
X1709027Y655141D03*
X1725473Y474859D03*
X1754307Y262186D03*
X1751068Y262123D03*
X1754245Y269724D03*
X1751068Y266048D03*
X1754307Y266111D03*
X1754414Y275329D03*
X1752165Y273901D03*
X1749565D03*
X1751006Y269661D03*
X1749595Y276711D03*
X1752195D03*
X1748989Y380206D03*
X1764955Y301951D03*
X1768757Y380498D03*
X1793061Y24659D03*
X1828880Y1626595D03*
Y1646595D03*
Y1666595D03*
Y1686595D03*
X1840691Y329470D03*
Y349470D03*
Y369470D03*
Y389470D03*
Y409470D03*
Y429470D03*
Y449470D03*
Y469470D03*
Y489470D03*
Y509470D03*
Y529470D03*
Y549470D03*
Y569470D03*
Y589470D03*
Y669470D03*
Y1329470D03*
Y1409470D03*
Y1429470D03*
Y1449470D03*
Y1469470D03*
Y1489470D03*
Y1509470D03*
Y1529470D03*
Y1549470D03*
Y1569470D03*
Y1589470D03*
X1854470Y112379D03*
Y152379D03*
Y172379D03*
Y192379D03*
Y212379D03*
Y232379D03*
Y252379D03*
Y272379D03*
Y292379D03*
G54D60*
X922441Y154311D03*
Y243799D03*
G54D12*
X14092Y287115D03*
X17371Y49388D03*
X22223Y388057D03*
X29509Y398132D03*
X29962Y401000D03*
X24700Y765600D03*
X37371Y49388D03*
X36255Y304972D03*
X42809Y360862D03*
X39410Y384582D03*
X39226Y395346D03*
X33020Y382822D03*
X36524Y398013D03*
X30680Y438142D03*
X58379Y69340D03*
X60379Y66844D03*
Y71836D03*
X60692Y87118D03*
X54920Y185039D03*
Y177165D03*
X46834Y360862D03*
X55190D03*
X53825Y421746D03*
X54762Y444993D03*
X53800Y435451D03*
X58658Y754145D03*
X55177Y1322328D03*
X55277Y1326068D03*
X46994Y1663165D03*
X69058Y3010D03*
X79047Y23978D03*
X74091D03*
X72091Y25974D03*
X73020Y37106D03*
Y48720D03*
X67335Y69340D03*
X65335Y66844D03*
Y71836D03*
X65648Y87118D03*
X71379Y72844D03*
Y77836D03*
X76335Y72844D03*
Y77836D03*
X78335Y75340D03*
X69379D03*
X71772Y421746D03*
X75490Y432519D03*
X68365Y443677D03*
X64150Y434972D03*
X74340Y663422D03*
X76365Y699244D03*
X76565Y717949D03*
X72315Y717414D03*
X64325Y715674D03*
X75564Y1509952D03*
X78120Y1512936D03*
Y1521336D03*
X75922Y1564874D03*
Y1556474D03*
X73429Y1570008D03*
X78415D03*
X73832Y1689362D03*
X77833Y1689162D03*
X89058Y3010D03*
X81196Y17042D03*
Y22034D03*
X86152Y17042D03*
Y22034D03*
X95369Y17042D03*
Y22034D03*
X79196Y19538D03*
X88152D03*
X93369D03*
X88264Y23978D03*
X93220D03*
X86264Y25974D03*
X95220D03*
X81047D03*
X94279Y37106D03*
X87193D03*
X80106D03*
X94279Y48720D03*
X87193D03*
X80106D03*
X80379Y69340D03*
X89335D03*
X82379Y66844D03*
Y71836D03*
X87335Y66844D03*
Y71836D03*
X91379Y75340D03*
X93379Y72844D03*
Y77836D03*
X86490Y200787D03*
Y208661D03*
X85960Y224409D03*
X85788Y240157D03*
X90700Y282762D03*
Y300262D03*
X87654Y376026D03*
X87520Y386502D03*
X94811Y510173D03*
X80460Y655672D03*
X83100Y649762D03*
X82735Y717949D03*
X87865Y714394D03*
X85165D03*
X81225Y715854D03*
X79635Y717949D03*
X85835Y718049D03*
X93295Y762019D03*
X92071Y1492888D03*
X80649Y1509944D03*
X93544Y1510099D03*
X88459Y1510107D03*
X90998Y1513037D03*
Y1521437D03*
X84048Y1578008D03*
X90713Y1585852D03*
Y1589852D03*
Y1593867D03*
X90788Y1611821D03*
Y1605867D03*
Y1623821D03*
X90698Y1638362D03*
Y1634362D03*
X86245Y1690362D03*
X81833Y1689162D03*
X94220Y1686622D03*
X109058Y3010D03*
X100325Y17042D03*
Y22034D03*
X109542Y17042D03*
Y22034D03*
X102325Y19538D03*
X107542D03*
X102437Y23978D03*
X107393D03*
X100437Y25974D03*
X109393D03*
X108453Y37106D03*
X101366D03*
X108453Y48720D03*
X101366D03*
X102379Y69340D03*
X111335D03*
X104379Y66844D03*
Y71836D03*
X109335Y66844D03*
Y71836D03*
X98335Y72844D03*
Y77836D03*
X100335Y75340D03*
X101317Y431727D03*
X102060Y493578D03*
X111087Y520052D03*
X98134Y722501D03*
X99716Y1567878D03*
X99750Y1559478D03*
X96251Y1577532D03*
X107451Y1574704D03*
X100451D03*
X104318Y1592304D03*
Y1603690D03*
X110200Y1605200D03*
X104318Y1622380D03*
Y1641075D03*
X99980Y1685362D03*
Y1696052D03*
X114498Y17042D03*
Y22034D03*
X123716Y17042D03*
Y22034D03*
X116498Y19538D03*
X121716D03*
X121567Y23978D03*
X116611D03*
X114611Y25974D03*
X123567D03*
X122626Y37106D03*
X115539D03*
X122626Y48720D03*
X115539D03*
X124379Y69340D03*
X126379Y66844D03*
Y71836D03*
X115379Y72844D03*
Y77836D03*
X120335Y72844D03*
Y77836D03*
X122335Y75340D03*
X113379D03*
X114087Y285495D03*
Y302854D03*
X127206Y480216D03*
X123257Y547506D03*
X119087D03*
X115060D03*
X120267Y1327697D03*
X127366Y1535855D03*
Y1541874D03*
Y1547935D03*
X116798Y1586288D03*
Y1598572D03*
Y1635303D03*
X127195Y1670362D03*
X117795Y1698862D03*
X127195Y1688362D03*
Y1692362D03*
Y1708362D03*
X117255Y1730422D03*
X129058Y3010D03*
X128672Y17042D03*
Y22034D03*
X130672Y19538D03*
X129713Y37106D03*
Y48720D03*
X133335Y69340D03*
X131335Y66844D03*
Y71836D03*
X137379Y72844D03*
Y77836D03*
X142335Y72844D03*
Y77836D03*
X135379Y75340D03*
X130057Y636103D03*
X129600Y669400D03*
X132967Y760525D03*
X141470Y1359100D03*
X140104Y1560136D03*
X139080Y1731398D03*
X149058Y3010D03*
X159582Y17042D03*
Y22034D03*
X157582Y19538D03*
X152477Y23978D03*
X157433D03*
X150477Y25974D03*
X159433D03*
X158492Y37106D03*
X151405D03*
X158492Y48720D03*
X151405D03*
X146379Y69340D03*
X155335D03*
X148379Y66844D03*
Y71836D03*
X153335Y66844D03*
Y71836D03*
X158583Y75340D03*
X144335D03*
X149371Y423383D03*
Y419383D03*
Y427383D03*
Y439383D03*
Y431383D03*
Y435383D03*
Y443383D03*
X147141Y698811D03*
X147435Y690807D03*
X149861Y698831D03*
X150155Y690807D03*
X156685Y706836D03*
X153965Y706816D03*
X153879Y721660D03*
X156469D03*
X147031Y706835D03*
X149621D03*
X149669Y721660D03*
X147079D03*
X154477Y1360797D03*
X148663Y1378607D03*
X151163D03*
Y1383807D03*
Y1381207D03*
X158318Y1384286D03*
X155718D03*
X158318Y1387393D03*
X155718D03*
X148663Y1386407D03*
X151163D03*
X148663Y1383807D03*
Y1381207D03*
X160201Y1399732D03*
X157731D03*
Y1394132D03*
X160201D03*
X152806Y1414175D03*
X144748Y1514878D03*
X149728D03*
X154581Y1520981D03*
X158570D03*
X150502Y1572021D03*
X145522D03*
X159107Y1571364D03*
X144854Y1702389D03*
X154803Y1708532D03*
X155100Y1723262D03*
X169058Y3010D03*
X164538Y17042D03*
Y22034D03*
X173755Y17042D03*
Y22034D03*
X166538Y19538D03*
X171755D03*
X166650Y23978D03*
X171606D03*
X164650Y25974D03*
X173606D03*
X172665Y37106D03*
X165579D03*
X172665Y48720D03*
X165579D03*
X169583Y69340D03*
X171583Y66844D03*
Y71836D03*
X176539Y66844D03*
Y71836D03*
X165539Y72844D03*
X160583D03*
Y77836D03*
X165539D03*
X167539Y75340D03*
X174327Y230928D03*
X171180Y401885D03*
X163900Y409362D03*
X163132Y493299D03*
X162750Y512502D03*
X172807Y1360797D03*
X160918Y1384286D03*
X163518D03*
Y1387393D03*
X160918D03*
X169318Y1384286D03*
X166118D03*
X172262Y1384302D03*
Y1387409D03*
X174932Y1378797D03*
Y1381397D03*
X163718Y1390500D03*
X161118D03*
X162631Y1399732D03*
Y1394132D03*
X172231Y1390532D03*
X162693Y1411529D03*
X171262Y1443390D03*
X168900Y1520510D03*
X163920D03*
X166476Y1572464D03*
X171456D03*
X166529Y1707678D03*
X166661Y1721211D03*
X189058Y3010D03*
X178711Y17042D03*
Y22034D03*
X180711Y19538D03*
X179752Y37106D03*
Y48720D03*
X191583Y69340D03*
X178539D03*
X182583Y72844D03*
Y77836D03*
X187539Y72844D03*
Y77836D03*
X189539Y75340D03*
X180583D03*
X186457Y393071D03*
Y385071D03*
Y389071D03*
Y405071D03*
X192220Y408662D03*
Y412162D03*
X177871Y421383D03*
Y425383D03*
Y430883D03*
Y443383D03*
X187490Y568752D03*
X190977Y669718D03*
X191976Y684326D03*
X184215Y1361072D03*
X181403Y1361115D03*
X192620Y1360797D03*
X188233Y1387027D03*
Y1379227D03*
Y1381827D03*
Y1384427D03*
X183283Y1387987D03*
X185633Y1387027D03*
X180672Y1387987D03*
X185633Y1379227D03*
X180672Y1380187D03*
X183283D03*
X177532Y1378797D03*
X185633Y1384427D03*
Y1381827D03*
X180672Y1382787D03*
Y1385387D03*
X183283Y1382787D03*
Y1385387D03*
X177421Y1383997D03*
X177532Y1381397D03*
X182653Y1404535D03*
X192767Y1413725D03*
X185643Y1413945D03*
X185895Y1535462D03*
Y1539723D03*
Y1544029D03*
Y1548487D03*
Y1552875D03*
X176793Y1585173D03*
X188119Y1580678D03*
Y1575686D03*
Y1592590D03*
Y1587598D03*
X192529Y1728947D03*
X183822Y1720517D03*
X209058Y3010D03*
X203716Y17042D03*
Y22034D03*
X208672Y17042D03*
Y22034D03*
X201716Y19538D03*
X201567Y23978D03*
X196611D03*
X194611Y25974D03*
X203567D03*
X208784D03*
X202626Y37106D03*
X195539D03*
X202626Y48720D03*
X195539D03*
X200539Y69340D03*
X193583Y66844D03*
Y71836D03*
X198539Y66844D03*
Y71836D03*
X204717Y72844D03*
Y77836D03*
X202717Y75340D03*
X195888Y581071D03*
X194515Y583433D03*
X195888Y615071D03*
X194515Y617433D03*
Y651433D03*
X195888Y649071D03*
X205320Y667562D03*
X207856Y686443D03*
X203043Y686483D03*
X207824Y681560D03*
X203044Y684036D03*
X207834Y684006D03*
X203237Y681549D03*
X199720Y732862D03*
X206720Y731862D03*
X199220Y739362D03*
X207602Y756855D03*
X199602D03*
X201661Y1384286D03*
X193861D03*
X196461D03*
X199061D03*
X201661Y1387393D03*
X193861D03*
X196461D03*
X199061D03*
X204261Y1384286D03*
X207461D03*
X201861Y1390500D03*
X199261D03*
X195874Y1399732D03*
X198344D03*
X200774D03*
X195874Y1394132D03*
X198344D03*
X200774D03*
X201071Y1412173D03*
X193075Y1580678D03*
Y1575686D03*
X200179D03*
X205135D03*
X200179Y1580678D03*
X205135D03*
X193075Y1592590D03*
Y1587598D03*
X200179Y1592590D03*
X205135D03*
X200179Y1587598D03*
X205135D03*
X198375Y1599884D03*
X193419D03*
X205479D03*
X193419Y1616788D03*
Y1611796D03*
X198375D03*
X193419Y1604876D03*
X198375D03*
Y1616788D03*
X205479Y1611796D03*
Y1604876D03*
Y1616788D03*
X207229Y1631181D03*
X193410Y1711606D03*
X205582Y1700867D03*
X196443Y1722197D03*
X217889Y17042D03*
Y22034D03*
X222845Y17042D03*
Y22034D03*
X210672Y19538D03*
X215889D03*
X224845D03*
X215740Y23978D03*
X210784D03*
X217740Y25974D03*
X223886Y37106D03*
X216799D03*
X209713D03*
X223886Y48720D03*
X216799D03*
X209713D03*
X215717Y66844D03*
Y71836D03*
X220673Y66844D03*
Y71836D03*
X213717Y69340D03*
X222673D03*
X209673Y72844D03*
Y77836D03*
X211673Y75340D03*
X224717D03*
X209579Y457222D03*
Y462235D03*
X211220Y740362D03*
X215824Y1361199D03*
X211350Y1360797D03*
X218960Y1388312D03*
X210405Y1384302D03*
Y1387409D03*
X213075Y1381558D03*
X217133Y1384055D03*
X214425Y1384058D03*
X215675Y1381558D03*
X218175D03*
X213075Y1378958D03*
X215675D03*
X218175D03*
X210374Y1390532D03*
X212239Y1580678D03*
X217195D03*
Y1575686D03*
X212239D03*
X224299D03*
Y1580678D03*
X212239Y1587598D03*
X217195D03*
X212239Y1592590D03*
X217195D03*
X224299Y1587598D03*
Y1592590D03*
X210435Y1599884D03*
X222495D03*
X217539D03*
X210435Y1611796D03*
Y1604876D03*
Y1616788D03*
X222495D03*
X217539D03*
X222495Y1604876D03*
Y1611796D03*
X217539Y1604876D03*
Y1611796D03*
X212684Y1720307D03*
X229058Y3010D03*
X238063Y37162D03*
X230972Y37106D03*
Y48720D03*
X226717Y72844D03*
Y77836D03*
X231673Y72844D03*
Y77836D03*
X233673Y75340D03*
X233800Y162692D03*
X237539Y174266D03*
X228550Y420412D03*
X229255Y1575686D03*
Y1580678D03*
X236359D03*
Y1575686D03*
X241315Y1580678D03*
Y1575686D03*
X229255Y1587598D03*
Y1592590D03*
X236359D03*
Y1587598D03*
X241315Y1592590D03*
Y1587598D03*
X229599Y1599884D03*
X234555D03*
X229599Y1604876D03*
Y1611796D03*
X234555Y1604876D03*
Y1611796D03*
X229599Y1616788D03*
X234555D03*
X249058Y3010D03*
X243490Y23002D03*
X247720Y71862D03*
X244300Y59762D03*
X247720Y75862D03*
X251797Y100843D03*
X249735Y152694D03*
X242255Y162512D03*
X249300Y510362D03*
X253800Y515362D03*
X249860Y518222D03*
X248419Y1575686D03*
X253375D03*
X248419Y1580678D03*
X253375D03*
X248419Y1587598D03*
X253375D03*
X248419Y1592590D03*
X253375D03*
X246615Y1599884D03*
X241659D03*
X253719D03*
X241659Y1616788D03*
X246615D03*
Y1604876D03*
X241659D03*
X246615Y1611796D03*
X241659D03*
X253719Y1604876D03*
Y1611796D03*
Y1616788D03*
X269058Y3010D03*
X263280Y35312D03*
X272600Y27182D03*
X271600Y40162D03*
X272361Y120243D03*
X270364Y118415D03*
X261387Y133783D03*
X258257D03*
X264578Y155203D03*
Y159203D03*
X260700Y218662D03*
X268940Y217982D03*
X270745Y207562D03*
X265343Y244460D03*
X272029Y443735D03*
X274270Y746602D03*
X260479Y1580678D03*
X265435D03*
X260479Y1575592D03*
X265435D03*
X272539Y1575686D03*
Y1580678D03*
X260479Y1592590D03*
X265435D03*
X260479Y1587598D03*
X265435D03*
X272539D03*
Y1592590D03*
X258675Y1599884D03*
X270735Y1599790D03*
X265779D03*
X258675Y1604876D03*
Y1611796D03*
Y1616788D03*
X270735D03*
X265779D03*
X270735Y1611796D03*
Y1604876D03*
X265779D03*
Y1611796D03*
X289058Y3010D03*
X285900Y23962D03*
X287952Y39984D03*
X286071Y48720D03*
X286500Y52462D03*
X278984Y48720D03*
X287800Y60062D03*
X283953Y152503D03*
X288520Y157062D03*
X279740Y205962D03*
X276890Y249022D03*
X289920Y248652D03*
X286920D03*
X282420D03*
X287819Y691097D03*
X287820Y727962D03*
X278520Y738072D03*
X290077Y739735D03*
X289047Y760245D03*
X277495Y1575686D03*
Y1580678D03*
X284599D03*
X289555D03*
Y1575686D03*
X284599D03*
X277495Y1587598D03*
Y1592590D03*
X284599D03*
X289555D03*
X284599Y1587598D03*
X289555D03*
X282795Y1599884D03*
X277839D03*
X289899D03*
X282795Y1604876D03*
Y1611796D03*
X277839D03*
Y1604876D03*
X282795Y1616788D03*
X277839D03*
X289899D03*
Y1604876D03*
Y1611796D03*
X291520Y12762D03*
X291660Y21642D03*
X298720Y40017D03*
X306720Y39982D03*
X292942Y67513D03*
X293447Y78573D03*
X293452Y82483D03*
Y85983D03*
X303047Y79373D03*
X299947Y79273D03*
X299657Y92503D03*
X299628Y149203D03*
Y158703D03*
X294553Y153819D03*
X306087Y569718D03*
X294658Y637809D03*
X290680Y745312D03*
X299427Y768265D03*
X303831Y1318566D03*
X303807Y1342225D03*
X303831Y1344866D03*
X304047Y1368565D03*
X296659Y1575686D03*
X301615D03*
X296659Y1580678D03*
X301615D03*
X296659Y1587598D03*
X301615D03*
X296659Y1592590D03*
X301615D03*
X294855Y1599884D03*
X301959D03*
X294855Y1616788D03*
Y1604876D03*
Y1611796D03*
X301959Y1604876D03*
Y1611796D03*
Y1616788D03*
X309058Y3010D03*
X320057Y85803D03*
Y88803D03*
X314200Y585282D03*
X316080Y578262D03*
X320691Y602448D03*
X311820Y598762D03*
X316397Y776125D03*
X312301Y1345539D03*
Y1342432D03*
X309701Y1345539D03*
Y1342432D03*
X316655Y1352295D03*
X314175D03*
X311695D03*
X320101Y1342432D03*
X317701Y1348646D03*
X315101D03*
X314901Y1345539D03*
X317501D03*
X314901Y1342432D03*
X317501D03*
X316655Y1357895D03*
X311695D03*
X314175D03*
X317979Y1371248D03*
X315221Y1372445D03*
X308719Y1580678D03*
X313675D03*
X308719Y1575686D03*
X313675D03*
X320779D03*
Y1580678D03*
X308719Y1592590D03*
X313675D03*
X308719Y1587598D03*
X313675D03*
X320779D03*
Y1592590D03*
X306915Y1599884D03*
X318975D03*
X314019D03*
X306915Y1604876D03*
Y1611796D03*
Y1616788D03*
X318975D03*
X314019D03*
X318975Y1604876D03*
Y1611796D03*
X314019Y1604876D03*
Y1611796D03*
X329535Y49388D03*
X336240Y150738D03*
X330674Y368261D03*
X331760Y705882D03*
X328915Y1337104D03*
X331515D03*
X328915Y1331904D03*
X331515D03*
X328915Y1329304D03*
X331515D03*
X328915Y1334504D03*
X331515D03*
X328915Y1339704D03*
X326145Y1348651D03*
X326245Y1345555D03*
Y1342448D03*
X323301Y1342432D03*
X338917Y1349488D03*
X336347Y1348353D03*
X325735Y1575686D03*
Y1580678D03*
X332839D03*
X337795D03*
X332839Y1575686D03*
X337795D03*
X325735Y1587598D03*
Y1592590D03*
X332839D03*
X337795D03*
X332839Y1587598D03*
X337795D03*
X326079Y1599884D03*
X331035D03*
X338139D03*
X326079Y1604876D03*
Y1611796D03*
X331035Y1604876D03*
Y1611796D03*
X326079Y1616788D03*
X331035D03*
X338139D03*
Y1604876D03*
Y1611796D03*
X349535Y49388D03*
X343040Y122522D03*
X345869Y192716D03*
X353145Y228362D03*
X345164Y314234D03*
X349187Y715485D03*
X344446Y739434D03*
X348000Y755362D03*
X344429Y1322741D03*
X347029D03*
X341829D03*
X347029Y1319634D03*
X344429D03*
X341829D03*
X349629Y1322741D03*
Y1319634D03*
X352229D03*
X355429D03*
X346303Y1335097D03*
X343823D03*
Y1329497D03*
X346303D03*
X347229Y1325848D03*
X348783Y1329497D03*
X349829Y1325848D03*
X348783Y1335097D03*
X348804Y1346877D03*
X350470Y1349030D03*
X344899Y1575686D03*
X349855D03*
X344899Y1580678D03*
X349855D03*
X344899Y1587598D03*
X349855D03*
X344899Y1592590D03*
X349855D03*
X343095Y1599884D03*
X355155D03*
X350199D03*
X343095Y1616788D03*
Y1604876D03*
Y1611796D03*
X355155Y1604876D03*
Y1611796D03*
X350199Y1604876D03*
Y1611796D03*
X355155Y1616788D03*
X350199D03*
X366775Y127662D03*
X356250Y216342D03*
X358209Y208169D03*
X357764Y314234D03*
X363750Y369362D03*
X371370Y373622D03*
X364014Y382304D03*
X359930Y732985D03*
X360927Y757665D03*
X361043Y1306506D03*
X363643D03*
X367939Y1303319D03*
Y1305919D03*
Y1308519D03*
X358373Y1322757D03*
Y1319650D03*
X361043Y1314306D03*
Y1316906D03*
X362393Y1319406D03*
X361043Y1309106D03*
Y1311706D03*
X363643Y1316906D03*
Y1314306D03*
Y1309106D03*
Y1311706D03*
X358273Y1325853D03*
X370874Y1335876D03*
X367490Y1332568D03*
X356959Y1580678D03*
X361915D03*
X356959Y1575592D03*
X361915D03*
X369019Y1575686D03*
Y1580678D03*
X356959Y1592590D03*
X361915D03*
X356959Y1587598D03*
X361915D03*
X367215Y1599790D03*
X362259D03*
X369019Y1587598D03*
Y1592590D03*
X367215Y1616788D03*
X362259D03*
X367215Y1604876D03*
Y1611796D03*
X362259Y1604876D03*
Y1611796D03*
X376245Y212862D03*
Y217362D03*
Y221362D03*
Y225362D03*
X386120Y220322D03*
X385720Y323761D03*
X376500Y362736D03*
X373957Y1306208D03*
X381757D03*
X379157D03*
X376557D03*
X384357D03*
X387557D03*
X375951Y1321671D03*
X380911Y1316071D03*
X378431D03*
Y1321671D03*
X380911D03*
X373957Y1309315D03*
X381957Y1312422D03*
X381757Y1309315D03*
X379357Y1312422D03*
X379157Y1309315D03*
X376557D03*
X375951Y1316071D03*
X380842Y1334095D03*
X383549Y1333998D03*
X383127Y1395610D03*
X381060Y1433622D03*
X380930Y1531402D03*
X384210Y1534152D03*
X387152Y1582659D03*
X373975Y1575686D03*
Y1580678D03*
Y1587598D03*
Y1592590D03*
X379275Y1599884D03*
X374319D03*
X379275Y1604876D03*
Y1611796D03*
X374319Y1604876D03*
Y1611796D03*
X379275Y1616788D03*
X374319D03*
X374690Y1631700D03*
X375550Y1662052D03*
X386824Y1682866D03*
X387760Y1671092D03*
X393830Y62062D03*
X399800Y59662D03*
X403800D03*
X390830Y155833D03*
X388965Y209949D03*
X398720Y318643D03*
X403675Y363081D03*
X391195Y368199D03*
X391101Y380939D03*
X403581Y375880D03*
X390730Y394852D03*
X403570Y388874D03*
X395771Y1303480D03*
X393171D03*
X395771Y1300880D03*
X393171D03*
X395771Y1295680D03*
X393171D03*
X395771Y1298280D03*
X393171D03*
X394521Y1305980D03*
X390501Y1306224D03*
X400067Y1303319D03*
Y1300719D03*
Y1295519D03*
Y1298119D03*
Y1305919D03*
Y1308519D03*
X390401Y1312427D03*
X390501Y1309331D03*
X399673Y1332653D03*
X403130Y1335963D03*
X400919Y1411231D03*
X391370Y1424782D03*
X392108Y1582659D03*
X401812Y1616456D03*
X394910Y1632364D03*
Y1637320D03*
X402246Y1671745D03*
X409535Y49388D03*
X412930Y62572D03*
X413459Y129061D03*
X411434Y163662D03*
X407490Y216912D03*
X412820Y231922D03*
X405478Y236726D03*
X410090Y241932D03*
X420710Y242482D03*
X419023Y381760D03*
X418982Y407847D03*
X416485Y1306208D03*
X419685D03*
X413885D03*
X406085D03*
X411285D03*
X408685D03*
X414085Y1312422D03*
X413885Y1309315D03*
X411485Y1312422D03*
X408685Y1309315D03*
X406085D03*
X411285D03*
X413039Y1316071D03*
X408079D03*
X410559D03*
X413039Y1321671D03*
X408079D03*
X410559D03*
X416099Y1335568D03*
X414617Y1333473D03*
X412465Y1393878D03*
X419974Y1405289D03*
Y1412789D03*
X420474Y1420289D03*
X407125Y1424978D03*
X404475Y1552452D03*
X419002Y1600306D03*
X406526Y1591212D03*
Y1596168D03*
X406768Y1616456D03*
X408700Y1603500D03*
Y1614300D03*
X411910Y1629170D03*
Y1624214D03*
X410232Y1670244D03*
X429535Y49388D03*
X430655Y58677D03*
X433695Y214862D03*
X429395Y232562D03*
X426295Y227862D03*
X422210Y221452D03*
X429395Y236562D03*
Y240562D03*
X425249Y338061D03*
X431503Y376642D03*
X431462Y402729D03*
X422629Y1306224D03*
X432195Y1303319D03*
Y1305919D03*
X425299Y1303480D03*
X426649Y1305980D03*
X427899Y1303480D03*
X425299Y1295680D03*
X427899D03*
X432195Y1295519D03*
Y1298119D03*
X427899Y1298280D03*
X425299D03*
X432195Y1300719D03*
X427899Y1300880D03*
X425299D03*
X432195Y1308519D03*
X422529Y1312427D03*
X422629Y1309331D03*
X434983Y1335924D03*
X431578Y1332560D03*
X427474Y1405289D03*
X434974D03*
Y1412789D03*
X427474Y1420289D03*
X434974D03*
X423958Y1600306D03*
X428099Y1586282D03*
X428941Y1606441D03*
X449535Y49388D03*
X443678Y145710D03*
X445964Y314234D03*
X450400Y338812D03*
X442853Y542519D03*
Y547519D03*
X448613Y1306208D03*
X446013D03*
X443413D03*
X440813D03*
X438213D03*
X451813D03*
X443613Y1312422D03*
X443413Y1309315D03*
X440813D03*
X438213D03*
X446213Y1312422D03*
X446013Y1309315D03*
X440207Y1316071D03*
X445167D03*
X442687D03*
X440207Y1321671D03*
X445167D03*
X442687D03*
X446944Y1335928D03*
X445153Y1334095D03*
X446258Y1441606D03*
X449778D03*
X451910Y1643282D03*
X437562Y1649770D03*
X442518D03*
X469535Y49388D03*
X454568Y78782D03*
X466992Y145888D03*
X458264Y254862D03*
X460300Y303662D03*
X468490Y340572D03*
X469830Y366158D03*
X460323Y510183D03*
X458327Y1303980D03*
X460927D03*
X464427Y1305380D03*
X454757Y1306224D03*
X460927Y1306580D03*
X458327D03*
Y1301380D03*
X460927D03*
X464427Y1300180D03*
Y1302780D03*
X458327Y1296180D03*
X460927D03*
X464427D03*
X458327Y1298780D03*
X460927D03*
X464423Y1308519D03*
X454657Y1312427D03*
X454757Y1309331D03*
X464738Y1333085D03*
X467644Y1335981D03*
X455576Y1409125D03*
Y1417125D03*
Y1420625D03*
Y1427632D03*
Y1424125D03*
X454450Y1433580D03*
X464160Y1587122D03*
X458414Y1624994D03*
Y1629950D03*
X468040Y1654807D03*
X478240Y55935D03*
Y66575D03*
Y61129D03*
X484396Y161364D03*
X475500Y212685D03*
X472800Y299462D03*
X484800Y307362D03*
X476740Y309272D03*
X479740Y300202D03*
X482920Y398060D03*
X479379Y452445D03*
X480741Y1306208D03*
X478141D03*
X475541D03*
X472941D03*
X470341D03*
X483941D03*
X472941Y1309315D03*
X478141D03*
X470341D03*
X478341Y1312422D03*
X475741D03*
X475541Y1309315D03*
X472335Y1316071D03*
X477295D03*
X474815D03*
X472335Y1321671D03*
X477295D03*
X474815D03*
X477162Y1334095D03*
X478909Y1336038D03*
X485236Y1417844D03*
X482741Y1438698D03*
X482742Y1441312D03*
X484333Y1575686D03*
Y1580678D03*
X477229D03*
X472273D03*
Y1575686D03*
X477229D03*
X482529Y1599884D03*
X477573D03*
X484333Y1587598D03*
Y1592590D03*
X472273D03*
X477229D03*
Y1587598D03*
X472273D03*
X482529Y1616788D03*
X477573D03*
Y1611796D03*
X482529D03*
X477573Y1604876D03*
X482529D03*
X472210Y1618626D03*
X485150Y1624942D03*
X477905Y1667242D03*
X489535Y49347D03*
X497002Y88167D03*
X501540Y105152D03*
X498630Y140492D03*
X489980Y250512D03*
X492074Y300306D03*
X497568Y397632D03*
X494193Y550447D03*
X486885Y1306224D03*
X496451Y1306345D03*
X489555Y1303480D03*
X492155D03*
X490905Y1305980D03*
X492155Y1300880D03*
X489555D03*
X486785Y1312427D03*
X486885Y1309331D03*
X496220Y1322440D03*
X496451Y1316745D03*
Y1308945D03*
Y1314145D03*
Y1311545D03*
X499458Y1349468D03*
X499818Y1385027D03*
X499859Y1393027D03*
X490307Y1421499D03*
X491156Y1438713D03*
X499541Y1438698D03*
X491142Y1441312D03*
X499542D03*
X501349Y1580678D03*
X496393D03*
Y1575686D03*
X501349D03*
X489289D03*
Y1580678D03*
X501693Y1599884D03*
X494589D03*
X489633D03*
X501349Y1592590D03*
X496393D03*
X501349Y1587598D03*
X496393D03*
X489289D03*
Y1592590D03*
X501693Y1611796D03*
Y1604876D03*
Y1616788D03*
X489633Y1611796D03*
X494589Y1604876D03*
X489633D03*
X494589Y1611796D03*
X489633Y1616788D03*
X494589D03*
X487340Y1641352D03*
X517902Y69508D03*
X510815D03*
X503100Y78402D03*
X510030Y78412D03*
X504980Y101752D03*
X503290Y140492D03*
X507360D03*
X514850Y168443D03*
X504075Y231262D03*
X508000Y237862D03*
X505900Y311562D03*
X510740Y332592D03*
X513173Y408740D03*
X514425Y489112D03*
Y495112D03*
X509493Y539819D03*
X513025Y615742D03*
X516069Y1319634D03*
X502469D03*
Y1322741D03*
X512869Y1319634D03*
X510269D03*
X507669D03*
X505069D03*
X507669Y1322741D03*
X505069D03*
X510269D03*
X504463Y1329497D03*
Y1335097D03*
X509423Y1329497D03*
X506943D03*
X509423Y1335097D03*
X506943D03*
X510469Y1325848D03*
X507869D03*
X509382Y1347521D03*
X511149Y1349468D03*
X505018Y1385027D03*
X502418D03*
X505059Y1393027D03*
X502459D03*
X508001Y1438669D03*
X507942Y1441312D03*
X508453Y1575686D03*
X513409D03*
X508453Y1580678D03*
X513409D03*
X513753Y1599884D03*
X506649D03*
X508453Y1587598D03*
X513409D03*
X508453Y1592590D03*
X513409D03*
X513753Y1616788D03*
Y1604876D03*
Y1611796D03*
X506649D03*
Y1604876D03*
Y1616788D03*
X518606Y23797D03*
X532075Y69508D03*
Y57894D03*
X524988Y69508D03*
X529239Y99997D03*
Y92911D03*
X528400Y104225D03*
Y114275D03*
X527823Y131802D03*
Y149802D03*
X527278Y164726D03*
X529480Y183921D03*
X536127Y247652D03*
X523660Y323222D03*
X535220Y383552D03*
X528145Y408705D03*
X518735Y452442D03*
X526852Y511331D03*
X527042Y505830D03*
X526853Y516817D03*
X523033Y1319406D03*
X519013Y1319650D03*
Y1322757D03*
X527645Y1326076D03*
X528579Y1329143D03*
X528377Y1335982D03*
X518913Y1325853D03*
X528579Y1342143D03*
Y1344743D03*
X534597Y1345539D03*
Y1342432D03*
X528975Y1369724D03*
X532573Y1575686D03*
Y1580678D03*
X520513D03*
X525469D03*
X520513Y1575686D03*
X525469D03*
X525813Y1599884D03*
X530769D03*
X518709D03*
X532573Y1587598D03*
Y1592590D03*
X525469D03*
X520513D03*
Y1587598D03*
X525469D03*
X525813Y1611796D03*
X530769D03*
X525813Y1604876D03*
X530769D03*
Y1616788D03*
X525813D03*
X518709D03*
Y1604876D03*
Y1611796D03*
X548609Y32500D03*
X546248Y69508D03*
X539161D03*
Y57894D03*
X546234Y77443D03*
X542620Y103352D03*
X537360Y120522D03*
X550545Y147302D03*
X542798Y202646D03*
X535630Y306602D03*
X543035Y441005D03*
X538120Y463137D03*
X544813Y1322668D03*
X542213D03*
X538293D03*
X535693D03*
X548197Y1342432D03*
X539997Y1348646D03*
X542397Y1345539D03*
X542597Y1348646D03*
X537197Y1342432D03*
X539797D03*
X542397D03*
X544997D03*
X537197Y1345539D03*
X539797D03*
X539071Y1352295D03*
X536591D03*
X541551D03*
Y1357895D03*
X542256Y1369935D03*
X536591Y1357895D03*
X539071D03*
X549589Y1580678D03*
X544633D03*
X549589Y1575592D03*
X544633D03*
X537529Y1575686D03*
Y1580678D03*
X549933Y1599790D03*
X537873Y1599884D03*
X542829D03*
X549589Y1592590D03*
X544633D03*
X549589Y1587598D03*
X544633D03*
X537529D03*
Y1592590D03*
X549933Y1611796D03*
Y1604876D03*
Y1616788D03*
X542829D03*
X537873D03*
Y1604876D03*
X542829D03*
X537873Y1611796D03*
X542829D03*
X560421Y69508D03*
X553335D03*
X553320Y77443D03*
X564988Y118670D03*
X555545Y134340D03*
X565500Y145252D03*
X555220Y167937D03*
X553657Y193862D03*
X564944Y252173D03*
X553536Y307527D03*
X569080Y414002D03*
X559300Y422732D03*
X558933Y1323658D03*
Y1326258D03*
X556563Y1337918D03*
X553963D03*
X558933Y1328938D03*
X556563Y1335318D03*
Y1332718D03*
X558933Y1331538D03*
X553963Y1335318D03*
Y1332718D03*
X555313Y1340418D03*
X551141Y1345555D03*
X551041Y1348651D03*
X551141Y1342448D03*
X555372Y1343037D03*
X561070Y1346174D03*
X556693Y1575686D03*
X561649D03*
X556693Y1580678D03*
X561649D03*
X561993Y1599884D03*
X554889Y1599790D03*
X556693Y1587598D03*
X561649D03*
Y1592590D03*
X556693D03*
X561993Y1616788D03*
Y1604876D03*
Y1611796D03*
X554889D03*
Y1604876D03*
Y1616788D03*
X567673Y130542D03*
X581175Y164717D03*
X569965Y161232D03*
X579481Y202378D03*
Y210378D03*
X568149Y217916D03*
X580712Y215877D03*
X581645Y233362D03*
X569668Y229812D03*
X578711Y230109D03*
X578509Y265132D03*
X569880Y300992D03*
X580400Y302402D03*
X582436Y361032D03*
X570200Y372229D03*
X570760Y451710D03*
X571990Y501046D03*
X571700Y552200D03*
X580813Y1575686D03*
Y1580678D03*
X573709D03*
X568753D03*
Y1575686D03*
X573709D03*
X579009Y1599884D03*
X574053D03*
X566949D03*
X580813Y1587598D03*
Y1592590D03*
X573709D03*
X568753D03*
X573709Y1587598D03*
X568753D03*
X574053Y1616788D03*
X579009D03*
Y1611796D03*
X574053D03*
X579009Y1604876D03*
X574053D03*
X566949Y1616788D03*
Y1604876D03*
Y1611796D03*
X591395Y132142D03*
X595220Y140922D03*
X588000D03*
X592710Y156342D03*
X593248Y159480D03*
X598295Y171862D03*
X596581Y184849D03*
X590337Y177604D03*
X598760Y203712D03*
X593966Y229965D03*
X592039Y252202D03*
X588577Y285862D03*
X586820Y314662D03*
X597820Y317062D03*
X592920Y326362D03*
X591720Y430787D03*
X599220Y444362D03*
X593545Y488212D03*
X594090Y505107D03*
X589260Y519421D03*
X594240Y511953D03*
X593675Y534702D03*
X589989Y745475D03*
X597829Y1580678D03*
X592873D03*
X597829Y1575686D03*
X592873D03*
X585769D03*
Y1580678D03*
X598173Y1599884D03*
X586113D03*
X591069D03*
X597829Y1592590D03*
X592873D03*
X597829Y1587598D03*
X592873D03*
X585769D03*
Y1592590D03*
X598173Y1616788D03*
Y1611796D03*
Y1604876D03*
X586113D03*
X591069D03*
X586113Y1611796D03*
X591069D03*
Y1616788D03*
X586113D03*
X615185Y69508D03*
X603374D03*
X601050Y100008D03*
X610104Y119342D03*
X602306Y143077D03*
X602430Y153862D03*
X606260Y161652D03*
X615572Y173942D03*
X615573Y181984D03*
X614531Y200378D03*
X611030Y188372D03*
X603340Y208142D03*
X614531Y209878D03*
X609456Y204994D03*
X606719Y254966D03*
X609844Y330407D03*
X608830Y374302D03*
X605830Y402782D03*
X604779Y423862D03*
X600351Y461862D03*
X614220Y452862D03*
X610820Y472862D03*
X603779Y486922D03*
X606200Y514862D03*
X609520Y515162D03*
X614086Y537624D03*
X614000Y550800D03*
X603317Y738415D03*
X614660Y739553D03*
X602027Y761445D03*
X612407Y769485D03*
X609889Y1575686D03*
X604933D03*
X609889Y1580678D03*
X604933D03*
X615189Y1599884D03*
X610233D03*
X603129D03*
X609889Y1587598D03*
X604933D03*
X609889Y1592590D03*
X604933D03*
X615189Y1604876D03*
X610233D03*
X615189Y1611796D03*
X610233D03*
X615189Y1616788D03*
X610233D03*
X603129D03*
Y1611796D03*
Y1604876D03*
X631546Y85024D03*
X618460Y119342D03*
X631300Y167872D03*
X628195Y178414D03*
X628194Y170372D03*
X630818Y191248D03*
X625862D03*
X620030Y188782D03*
X627645Y236862D03*
X629564Y256277D03*
X623150Y273172D03*
X625800Y311912D03*
X628294Y317007D03*
X623580Y336429D03*
X629248Y436972D03*
X629220Y472862D03*
Y477862D03*
Y467862D03*
Y482862D03*
X626207Y747585D03*
X618114Y1258470D03*
X629053Y1575686D03*
Y1580678D03*
X621949D03*
X616993D03*
X621949Y1575686D03*
X616993D03*
X622293Y1599884D03*
X627249D03*
X629053Y1587598D03*
Y1592590D03*
X621949D03*
X616993D03*
X621949Y1587598D03*
X616993D03*
X627249Y1616788D03*
X622293D03*
Y1611796D03*
X627249D03*
X622293Y1604876D03*
X627249D03*
X646440Y43632D03*
X632463Y43302D03*
X645150Y69508D03*
X645350Y60612D03*
X632640Y107532D03*
X637500Y110362D03*
X642480Y184862D03*
X645876Y296231D03*
X633138Y296766D03*
X645528Y308623D03*
X645807Y304291D03*
X647200Y354300D03*
X643736Y457214D03*
X644245Y472862D03*
X644220Y467862D03*
X644245Y482862D03*
X636960Y516002D03*
X646069Y1580678D03*
X641113D03*
X646069Y1575592D03*
X641113D03*
X634009Y1575686D03*
Y1580678D03*
X646413Y1599790D03*
X639309Y1599884D03*
X634353D03*
X646069Y1592590D03*
X641113D03*
X646069Y1587598D03*
X641113D03*
X634009D03*
Y1592590D03*
X646413Y1616788D03*
Y1611796D03*
Y1604876D03*
X639309D03*
X634353D03*
X639309Y1611796D03*
X634353D03*
Y1616788D03*
X639309D03*
X641057Y1648659D03*
X645407Y1660425D03*
X639745Y1714362D03*
X648290Y1720052D03*
X639745Y1726362D03*
X661550Y45133D03*
X654464D03*
X652153Y98105D03*
X652680Y89712D03*
X651579Y102703D03*
X659000Y89262D03*
X651980Y133822D03*
X650790Y144982D03*
X660690Y408162D03*
X660720Y404362D03*
X653800Y498740D03*
X662282Y1386432D03*
X654606Y1431203D03*
X653173Y1575686D03*
X658129D03*
X653173Y1580678D03*
X658129D03*
X663429Y1599884D03*
X658473D03*
X651369Y1599790D03*
X653173Y1587598D03*
X658129D03*
X653173Y1592590D03*
X658129D03*
X663429Y1604876D03*
X658473D03*
X663429Y1611796D03*
X658473D03*
Y1616788D03*
X663429D03*
X651369D03*
Y1611796D03*
Y1604876D03*
X663043Y1647557D03*
X655307Y1647436D03*
X663118Y1659557D03*
X663145Y1664862D03*
Y1676862D03*
X656973Y1698727D03*
X652712Y1686275D03*
X672005Y44119D03*
X668800Y45262D03*
X666406Y69508D03*
X675225Y58108D03*
X673750Y77692D03*
X673690Y200672D03*
X673300Y211332D03*
X667020Y225762D03*
X680600Y375462D03*
X668329Y411714D03*
X677295Y404362D03*
X677195Y408262D03*
X674628Y414864D03*
Y443210D03*
X671479Y430612D03*
Y462108D03*
X668329Y481006D03*
X675220Y503837D03*
X680220D03*
X675220Y516852D03*
X671607Y742835D03*
X668096Y1360822D03*
X677137Y1384311D03*
X674537D03*
X671937D03*
X669337D03*
X677137Y1387418D03*
X674537D03*
X671937D03*
X669337D03*
X664782Y1383832D03*
Y1381232D03*
Y1378632D03*
Y1386432D03*
X679737Y1384311D03*
X677337Y1390525D03*
X674737D03*
X676250Y1399757D03*
X673820D03*
X671350D03*
X676250Y1394157D03*
X673820D03*
X671350D03*
X666425Y1414200D03*
X676312Y1411554D03*
X667926Y1547018D03*
X679192Y1564252D03*
X678515Y1573910D03*
X676648Y1657380D03*
X671620Y1670862D03*
X674195Y1708362D03*
X669120Y1718862D03*
X674195Y1732362D03*
X696838Y45112D03*
X686854Y43701D03*
X692380Y43532D03*
X682941Y69982D03*
X687050Y79212D03*
X685230Y76952D03*
X683820Y79192D03*
X682890Y72642D03*
X684953Y104968D03*
X694390Y133682D03*
X684520Y152482D03*
X688520D03*
X692520D03*
X686760Y222912D03*
X685600Y375462D03*
X690600D03*
X695600D03*
X688220Y388362D03*
X697220Y404362D03*
X697120Y408262D03*
X684077Y414864D03*
X680928Y424313D03*
X696676Y436911D03*
X693526Y443210D03*
Y440061D03*
Y436911D03*
X690376Y440061D03*
Y433761D03*
X693526Y452659D03*
Y449510D03*
X696676Y455809D03*
X693526D03*
X690376Y452659D03*
Y458959D03*
X696676Y477856D03*
X684077D03*
X680928Y468407D03*
X690220Y516852D03*
X684357Y742345D03*
X692784Y1298845D03*
X686426Y1360822D03*
X695022Y1361990D03*
X696462Y1386122D03*
X682937Y1384311D03*
X685881Y1384327D03*
Y1387434D03*
X691351Y1380922D03*
X688751D03*
X691240Y1383522D03*
X693851D03*
Y1378322D03*
Y1380922D03*
X691351Y1378322D03*
X688751D03*
X693851Y1386122D03*
X696462Y1378322D03*
Y1383522D03*
Y1380922D03*
X696272Y1404560D03*
X685850Y1390557D03*
X685015Y1438475D03*
X696940Y1437955D03*
X689875Y1577913D03*
X689128Y1652262D03*
X692595Y1670862D03*
X701838Y45112D03*
X700610Y57782D03*
X700741Y83050D03*
X706673Y122762D03*
X703520Y122540D03*
X704880Y133643D03*
X701926Y166535D03*
Y178346D03*
Y184252D03*
Y172441D03*
Y190157D03*
Y196063D03*
Y201968D03*
Y207874D03*
Y213779D03*
Y219685D03*
X700600Y375462D03*
X705600D03*
X706125Y421163D03*
X709274Y436911D03*
X706125Y440061D03*
Y436911D03*
X699825Y440061D03*
Y436911D03*
X712424Y443210D03*
Y440061D03*
Y436911D03*
Y455809D03*
X709274D03*
X706125D03*
Y452659D03*
X699825Y455809D03*
Y452659D03*
X712424D03*
Y449510D03*
X709274Y477856D03*
X699825Y468407D03*
X711220Y516852D03*
X705220D03*
X698600Y530700D03*
X701917Y742865D03*
X703755Y1290545D03*
X708795Y1303701D03*
X698094Y1361947D03*
X706239Y1360822D03*
X699062Y1380922D03*
Y1383522D03*
Y1378322D03*
X707480Y1384311D03*
X710080D03*
X707480Y1387418D03*
X710080D03*
X701662Y1380922D03*
Y1383522D03*
Y1378322D03*
X699062Y1386122D03*
X701662D03*
X712680Y1384311D03*
Y1387418D03*
X709493Y1399757D03*
Y1394157D03*
X712880Y1390525D03*
X711963Y1399757D03*
Y1394157D03*
X699262Y1413970D03*
X704568Y1414119D03*
X706680Y1437535D03*
X701730Y1437855D03*
X711440Y1436905D03*
X702112Y1583683D03*
X709111Y1618842D03*
X697595Y1658862D03*
X704433Y1657964D03*
X697770Y1680810D03*
X714015Y-27612D03*
X720308Y-26403D03*
X714015Y-21457D03*
Y-17583D03*
X714030Y-15068D03*
X714015Y-11428D03*
X714030Y-25097D03*
X720308Y-16374D03*
X714015Y-7554D03*
X714030Y-5039D03*
X720308Y-6345D03*
X728980Y39872D03*
X728028Y101968D03*
X728023Y98058D03*
X728028Y105468D03*
X727720Y356362D03*
X725220Y380787D03*
X715600Y375462D03*
X718220Y388362D03*
X715220Y404362D03*
X715120Y408262D03*
X725022Y414864D03*
X715574Y433761D03*
Y458959D03*
X728172Y449510D03*
X725022Y477856D03*
X722720Y521362D03*
X729200Y588952D03*
X713836Y1283689D03*
X724969Y1360822D03*
X729443Y1361224D03*
X726694Y1381583D03*
Y1378983D03*
X715280Y1384311D03*
X717880D03*
X715280Y1387418D03*
X721080Y1384311D03*
X724024Y1384327D03*
Y1387434D03*
X728044Y1384083D03*
X729294Y1381583D03*
Y1378983D03*
X715480Y1390525D03*
X723993Y1390557D03*
X714393Y1399757D03*
Y1394157D03*
X714455Y1411554D03*
X718230Y1600372D03*
X725378Y1614503D03*
X719770Y1614590D03*
X715780D03*
X722040Y1623970D03*
X713791Y1629816D03*
X721345Y1647300D03*
X716140Y1649895D03*
X726830Y1655380D03*
X724500Y1676500D03*
X744987Y49062D03*
X742840Y39832D03*
X736790D03*
X745130Y69508D03*
X738043D03*
X730957D03*
X731330Y60712D03*
X730820Y84062D03*
X737623Y98858D03*
X734523Y98758D03*
X735733Y111988D03*
X733220Y388362D03*
X737621Y411714D03*
X743720Y404362D03*
X743820Y408262D03*
X731322Y430612D03*
Y462108D03*
X737621Y481006D03*
X730070Y506212D03*
X744630Y506529D03*
X745220Y530362D03*
X737299Y766887D03*
X737784Y1360017D03*
X730752Y1384080D03*
X731794Y1381583D03*
Y1378983D03*
X732238Y1388343D03*
X738810Y1396665D03*
X741540Y1396585D03*
X739170Y1405655D03*
X741670Y1405675D03*
X738170Y1414185D03*
X740760Y1414165D03*
X741382Y1590691D03*
X758606Y23797D03*
X747487Y49062D03*
X752720Y59002D03*
X754219Y75707D03*
X754633Y108288D03*
Y105288D03*
X762172Y123898D03*
X754290Y286632D03*
X755200Y296062D03*
X759940Y438232D03*
X758420Y447662D03*
X751220Y530362D03*
X753137Y766625D03*
X757779Y1390645D03*
X757542Y1420684D03*
X761770Y1695347D03*
X765606Y44894D03*
X769474Y75360D03*
X765858Y87340D03*
X762368Y84088D03*
X769284Y103895D03*
X767061Y99959D03*
X767045Y95960D03*
X767028Y91490D03*
X776730Y117479D03*
X773943Y114633D03*
X771131Y111788D03*
X769775Y107977D03*
X766769Y140138D03*
X771774Y167518D03*
X773220Y296262D03*
X772866Y311558D03*
X776100Y375100D03*
X766195Y418212D03*
X765315Y464862D03*
Y488862D03*
X772220Y530362D03*
X775317Y764025D03*
X763747Y764335D03*
X768520Y1379962D03*
X768620Y1392762D03*
X767820Y1410262D03*
X785095Y49388D03*
X780617Y296345D03*
X779120Y306162D03*
X794600Y360600D03*
X787925Y387900D03*
X781195Y418212D03*
X791590Y417050D03*
X780020Y438287D03*
X781410Y431822D03*
X780340Y468982D03*
Y474862D03*
X793673Y512862D03*
X792720Y589862D03*
X789720Y581862D03*
X783100Y593582D03*
X788225Y1388683D03*
X805095Y49388D03*
X797443Y271469D03*
X806300Y279662D03*
X809700Y273562D03*
X795190Y298572D03*
X798620Y312773D03*
X809800Y360600D03*
X802200D03*
X806588Y351097D03*
X799800Y368700D03*
X802220Y393727D03*
X803150Y408512D03*
X795600Y402500D03*
X799458Y431217D03*
X795370Y474862D03*
X801567Y512942D03*
X798720Y585362D03*
X798220Y597362D03*
X808860Y603802D03*
X797720Y617862D03*
X799637Y763625D03*
X825095Y49388D03*
X821118Y134632D03*
X825698Y139062D03*
X813900Y269698D03*
X827403Y286625D03*
X816420Y287062D03*
X813855Y354008D03*
X820936Y356956D03*
X824980Y405260D03*
Y409260D03*
X821720Y428437D03*
X818500Y451700D03*
X816500Y476800D03*
X821720Y519082D03*
X815040Y590772D03*
X814800Y760922D03*
X822442Y762369D03*
X814234Y1340465D03*
X830975Y2388D03*
X830990Y4903D03*
X837268Y3597D03*
X830975Y22446D03*
Y8543D03*
Y12417D03*
X830990Y14932D03*
X830975Y18572D03*
X837268Y13626D03*
X830990Y24961D03*
X837268Y23655D03*
X836126Y62681D03*
X837791Y85186D03*
X831297Y104206D03*
X842864Y110296D03*
X830339Y228143D03*
X829680Y264580D03*
X836210Y272452D03*
X829720Y277562D03*
X829800Y271562D03*
X829320Y296762D03*
X834400Y283862D03*
X834900Y293462D03*
X828222Y359960D03*
X835471Y363003D03*
X843133Y366158D03*
X833300Y386500D03*
X838784Y392880D03*
X839200Y434300D03*
X841300Y446800D03*
X842600Y477200D03*
X842341Y474241D03*
X841795Y492862D03*
X829745Y498082D03*
X834635Y515447D03*
X830480Y527817D03*
X831700Y596962D03*
X836847Y762495D03*
X828799Y1336870D03*
X828910Y1331756D03*
Y1341725D03*
X845095Y49388D03*
X854107Y91232D03*
X850280Y113852D03*
X853828Y265057D03*
X854333Y276117D03*
X854338Y280027D03*
Y283527D03*
X852800Y288562D03*
X853200Y297462D03*
X856700Y304862D03*
X848000Y374622D03*
X851396Y369614D03*
X859734Y373032D03*
X857560Y417762D03*
X844200Y418800D03*
X847830Y443892D03*
X843810Y453322D03*
X846700Y473000D03*
X848710Y505641D03*
X860345Y522162D03*
X856698Y594011D03*
X853200Y751062D03*
X854687Y761685D03*
X865095Y49388D03*
X868187Y72006D03*
X860937Y71877D03*
X861350Y61672D03*
X871980Y199500D03*
X860833Y276817D03*
X863933Y276917D03*
X862043Y290047D03*
X867922Y376450D03*
X875922Y379793D03*
X870700Y382415D03*
Y390620D03*
Y394620D03*
X871320Y416752D03*
X862620Y503162D03*
Y499062D03*
X860345Y513062D03*
X892214Y141891D03*
X878220Y192055D03*
X880943Y283347D03*
Y286347D03*
X880473Y329370D03*
X883472Y382910D03*
X886362Y534380D03*
X886500Y739162D03*
X878152Y876760D03*
X889439Y1437938D03*
X903930Y202885D03*
X903980Y210355D03*
X903930Y217059D03*
X903980Y224529D03*
X893500Y339062D03*
X900061Y510962D03*
X906127Y496343D03*
X900061Y517898D03*
X893298Y534380D03*
X899462Y533380D03*
X906398D03*
X897000Y891895D03*
X894375Y913692D03*
X912214Y141891D03*
X917680Y174999D03*
Y177999D03*
Y171999D03*
X909386Y195925D03*
Y203011D03*
Y210098D03*
Y217185D03*
Y224271D03*
Y231358D03*
X919279Y461244D03*
X920682Y494586D03*
X920980Y503393D03*
X911720Y511662D03*
X911626Y523430D03*
X918562D03*
X924647Y526808D03*
Y533744D03*
X924600Y824262D03*
X922320Y1660953D03*
X932214Y141891D03*
X927133Y189386D03*
X925320Y203399D03*
X940709Y460438D03*
X938437Y455454D03*
X932724Y455538D03*
X926215Y461244D03*
X929234Y494915D03*
X938588Y485197D03*
X929698Y503595D03*
X928231Y530479D03*
X936273Y530478D03*
X927200Y811462D03*
X931496Y962082D03*
X929221Y1014664D03*
X927122Y1661380D03*
X938220Y1661062D03*
X952214Y141891D03*
X949710Y198289D03*
X941634Y199051D03*
Y193451D03*
X951354Y209437D03*
Y203837D03*
X944880Y210959D03*
Y216559D03*
Y230697D03*
Y225097D03*
X954874Y232071D03*
X954904Y225741D03*
X942827Y422743D03*
Y429679D03*
X945800Y432463D03*
Y439399D03*
X946492Y460410D03*
X956188Y495384D03*
Y502320D03*
X948495Y502784D03*
X948693Y509497D03*
X956188Y509484D03*
Y516420D03*
X952622Y529364D03*
X956700Y786862D03*
X941400Y810062D03*
X946100Y1661100D03*
X972214Y141891D03*
X963520Y214699D03*
X960703Y212668D03*
X971471Y242358D03*
X965792Y350959D03*
X965420Y365719D03*
X963856Y394202D03*
X960059Y387004D03*
X972986Y393171D03*
X970054Y478773D03*
Y485709D03*
X966720Y511362D03*
X960620Y509462D03*
X972379Y509303D03*
X959558Y529364D03*
X962162Y535130D03*
X969098D03*
X958755Y657078D03*
X963520Y665062D03*
X958866Y662378D03*
X959100Y789862D03*
X965622Y1579240D03*
Y1576240D03*
Y1573240D03*
X975688Y152950D03*
Y149950D03*
X985016Y344659D03*
X974791Y339990D03*
X986182Y361062D03*
X979380Y373082D03*
X988159Y409068D03*
X983760Y424292D03*
X980092Y421289D03*
X983720Y512362D03*
X976283Y534226D03*
X988988Y1579240D03*
Y1573240D03*
Y1576240D03*
X994553Y365711D03*
X997598Y382952D03*
X997612Y391804D03*
X1006221Y382945D03*
X997900Y400720D03*
X993387Y429827D03*
X999720Y512862D03*
X991097Y529902D03*
X996675Y1286985D03*
X1012214Y141826D03*
X1022002Y267342D03*
Y270142D03*
X1013500Y344900D03*
X1015638Y382968D03*
X1015637Y391334D03*
X1006589Y392017D03*
X1006750Y401010D03*
X1015657Y401013D03*
X1021259Y420548D03*
X1007249Y422682D03*
X1017511Y430038D03*
X1008720Y498362D03*
X1019145Y503823D03*
X1011720Y589362D03*
X1018720Y592362D03*
X1021720Y601862D03*
X1010630Y748741D03*
X1012354Y1579240D03*
Y1573240D03*
Y1576240D03*
X1023407Y-27681D03*
X1029700Y-26472D03*
X1023407Y-32055D03*
X1029700Y-37001D03*
X1023407Y-17652D03*
X1023422Y-15137D03*
X1023407Y-11497D03*
X1029700Y-16443D03*
X1023422Y-25166D03*
X1023407Y-21526D03*
X1029700Y3615D03*
X1023422Y4921D03*
X1023407Y2406D03*
X1023422Y-5108D03*
X1023407Y-7623D03*
Y-1468D03*
X1029700Y-6414D03*
X1023407Y22464D03*
Y18590D03*
Y8561D03*
X1023422Y14950D03*
X1023407Y12435D03*
X1029700Y13644D03*
Y23673D03*
X1023422Y24979D03*
X1038609Y49388D03*
X1027520Y122732D03*
X1037650Y128842D03*
X1023220Y187574D03*
X1031502Y267342D03*
X1028202D03*
X1025102D03*
X1033133Y272564D03*
X1031502Y270142D03*
X1029833Y272564D03*
X1026733D03*
X1023633D03*
X1028202Y270142D03*
X1025102D03*
X1029094Y383070D03*
Y387872D03*
X1033860Y400802D03*
X1038294Y506504D03*
X1027190Y510672D03*
X1029220Y520032D03*
X1035720Y1579240D03*
Y1573240D03*
Y1576240D03*
X1043629Y375078D03*
Y372578D03*
X1049100Y390162D03*
X1046156Y442699D03*
X1058609Y49388D03*
X1066820Y151632D03*
X1072310Y364422D03*
X1059086Y1579240D03*
Y1573240D03*
Y1576240D03*
X1078609Y49388D03*
X1075100Y55682D03*
X1084146Y67102D03*
X1078270Y93462D03*
X1077270Y369061D03*
Y374131D03*
Y379251D03*
X1073724Y476867D03*
X1081906Y472577D03*
X1076739Y506461D03*
X1077751Y522235D03*
X1098609Y49388D03*
X1097794Y67881D03*
X1102480Y133722D03*
X1105553Y356475D03*
X1096477Y744385D03*
X1102930Y1668690D03*
X1092072Y1734244D03*
X1118609Y49388D03*
X1118110Y1398010D03*
X1109118Y1526046D03*
X1116338Y1711380D03*
X1113055Y1718338D03*
X1132856Y52926D03*
X1129948Y66786D03*
X1127788Y1397126D03*
X1131629Y1420615D03*
X1129029D03*
X1134229D03*
X1123674Y1414936D03*
X1121174D03*
X1123674Y1417536D03*
Y1420136D03*
X1121174Y1417536D03*
Y1420136D03*
X1131629Y1423722D03*
X1129029D03*
X1134229D03*
X1123674Y1422736D03*
X1121174D03*
X1131042Y1436061D03*
X1135942D03*
X1133512D03*
X1131042Y1430461D03*
X1135942D03*
X1133512D03*
X1134429Y1426829D03*
X1136004Y1447858D03*
X1126117Y1450504D03*
X1127008Y1550285D03*
X1133780Y1550301D03*
X1138609Y49388D03*
X1145603Y73679D03*
X1140465Y379592D03*
X1142302Y366532D03*
X1142790Y611122D03*
X1146118Y1397126D03*
X1150843Y1415126D03*
X1148243D03*
X1150843Y1417726D03*
X1148243D03*
X1150732Y1420326D03*
X1142629Y1420615D03*
X1145573Y1420631D03*
X1139429Y1420615D03*
X1136829D03*
X1145573Y1423738D03*
X1136829Y1423722D03*
X1145542Y1426861D03*
X1137029Y1426829D03*
X1145108Y1476732D03*
X1158609Y49388D03*
X1156790Y373231D03*
X1153467Y586462D03*
X1153490Y610322D03*
X1165931Y1397126D03*
X1154714Y1398295D03*
X1157786Y1398252D03*
X1167172Y1420615D03*
X1153913Y1420606D03*
Y1415406D03*
Y1418006D03*
X1159124D03*
Y1420606D03*
Y1415406D03*
X1161724D03*
Y1420606D03*
Y1418006D03*
X1156524Y1415406D03*
Y1420606D03*
Y1418006D03*
X1167172Y1423722D03*
X1153913Y1423206D03*
X1159124D03*
X1161724D03*
X1156524D03*
X1155964Y1440864D03*
X1164260Y1450423D03*
X1158954Y1450274D03*
X1168192Y1604130D03*
X1152950Y1616470D03*
X1165950Y1617729D03*
X1152930Y1633880D03*
X1174980Y585632D03*
X1174880Y592652D03*
X1173990Y602192D03*
X1183230Y739102D03*
X1184661Y1397126D03*
X1183716Y1420631D03*
X1180772Y1420615D03*
X1174972D03*
X1177572D03*
X1172372D03*
X1169772D03*
X1183716Y1423738D03*
X1174972Y1423722D03*
X1172372D03*
X1169772D03*
X1174085Y1436061D03*
Y1430461D03*
X1171655Y1436061D03*
X1169185D03*
X1171655Y1430461D03*
X1169185D03*
X1183685Y1426861D03*
X1175172Y1426829D03*
X1172572D03*
X1174147Y1447858D03*
X1179922Y1550285D03*
X1184501Y1606521D03*
X1185030Y1633010D03*
X1182470Y1618914D03*
X1172530Y1623020D03*
X1176900Y1627510D03*
X1198609Y49388D03*
X1188720Y56755D03*
X1191700Y56822D03*
X1185500Y101400D03*
X1190700Y99000D03*
X1197627Y132859D03*
X1196100Y188962D03*
X1193500D03*
X1192600Y217662D03*
X1193000Y204486D03*
X1195500D03*
X1195100Y217662D03*
X1194840Y240672D03*
X1199027Y588714D03*
X1189135Y1397529D03*
X1187736Y1420387D03*
X1188986Y1415287D03*
Y1417887D03*
X1186386Y1415287D03*
Y1417887D03*
X1191486Y1415287D03*
Y1417887D03*
X1190444Y1420384D03*
X1194750Y1424672D03*
X1197700Y1432672D03*
X1191930Y1424647D03*
X1198010Y1441902D03*
X1198880Y1457162D03*
X1197181Y1563587D03*
X1195994Y1580678D03*
Y1575686D03*
X1200950Y1580678D03*
Y1575686D03*
X1201294Y1599884D03*
X1195994Y1592590D03*
Y1587598D03*
X1200950Y1592590D03*
Y1587598D03*
X1201294Y1604876D03*
Y1611796D03*
Y1616788D03*
X1213026Y56742D03*
X1201800Y94600D03*
X1204800Y108900D03*
X1206900Y115900D03*
X1214573Y148909D03*
X1204420Y195362D03*
X1210084Y224362D03*
X1207220Y247148D03*
X1217720Y249862D03*
X1204880Y754032D03*
X1213010Y1575686D03*
X1208054D03*
X1213010Y1580678D03*
X1208054D03*
X1206250Y1599884D03*
X1213354D03*
X1213010Y1587598D03*
X1208054D03*
X1213010Y1592590D03*
X1208054D03*
X1206250Y1604876D03*
Y1611796D03*
Y1616788D03*
X1213354D03*
Y1604876D03*
Y1611796D03*
X1213980Y1676500D03*
X1218609Y49388D03*
X1228420Y58862D03*
X1230250Y89450D03*
X1223720Y217862D03*
Y205862D03*
X1232000Y244332D03*
Y248332D03*
X1225070Y1580678D03*
Y1575686D03*
X1220114D03*
Y1580678D03*
X1232174D03*
Y1575686D03*
X1218310Y1599884D03*
X1225414D03*
X1230370D03*
X1225070Y1592590D03*
X1220114D03*
X1225070Y1587598D03*
X1220114D03*
X1232174D03*
Y1592590D03*
X1218310Y1616788D03*
Y1604876D03*
Y1611796D03*
X1225414D03*
Y1604876D03*
X1230370Y1611796D03*
Y1604876D03*
X1225414Y1616788D03*
X1230370D03*
X1238609Y49388D03*
X1239907Y95008D03*
X1243808Y116832D03*
X1247333Y121999D03*
X1236520Y213462D03*
X1246444Y256098D03*
X1252040Y306480D03*
X1237130Y1575686D03*
Y1580678D03*
X1244234D03*
X1249190D03*
X1244234Y1575686D03*
X1249190D03*
X1242430Y1599884D03*
X1237474D03*
X1249534D03*
X1237130Y1587598D03*
Y1592590D03*
X1249190D03*
X1244234D03*
Y1587598D03*
X1249190D03*
X1242430Y1616788D03*
X1237474D03*
X1242430Y1611796D03*
Y1604876D03*
X1237474Y1611796D03*
Y1604876D03*
X1249534Y1611796D03*
Y1604876D03*
Y1616788D03*
X1258609Y49388D03*
X1262800Y101100D03*
X1264620Y92724D03*
X1252961Y111903D03*
X1267150Y305998D03*
X1256787Y749605D03*
X1261250Y1575686D03*
X1256294D03*
X1261250Y1580678D03*
X1256294D03*
X1254490Y1599884D03*
X1261594D03*
X1261250Y1587598D03*
X1256294D03*
X1261250Y1592590D03*
X1256294D03*
X1254490Y1611796D03*
Y1604876D03*
Y1616788D03*
X1261594D03*
Y1611796D03*
Y1604876D03*
X1278300Y81232D03*
X1280135Y1340002D03*
Y1337402D03*
Y1345202D03*
Y1342602D03*
X1280312Y1365689D03*
X1273310Y1580678D03*
Y1575592D03*
X1268354D03*
Y1580678D03*
X1280414Y1575686D03*
Y1580678D03*
X1266550Y1599884D03*
X1273654Y1599790D03*
X1278610D03*
X1273310Y1592590D03*
X1268354D03*
X1273310Y1587598D03*
X1268354D03*
X1280414D03*
Y1592590D03*
X1266550Y1616788D03*
Y1611796D03*
Y1604876D03*
X1273654Y1611796D03*
Y1604876D03*
X1278610Y1611796D03*
Y1604876D03*
X1273654Y1616788D03*
X1278610D03*
X1295278Y297056D03*
X1290322D03*
X1294937Y746965D03*
X1292904Y782048D03*
X1292614Y789910D03*
X1291205Y1345875D03*
X1286005Y1342768D03*
Y1345875D03*
X1296405Y1342768D03*
X1293805D03*
X1288605D03*
X1291205D03*
X1288605Y1345875D03*
X1293805D03*
X1291405Y1348982D03*
X1294005D03*
X1292916Y1352531D03*
X1290436D03*
X1287956D03*
X1292916Y1358131D03*
X1290436D03*
X1287956D03*
X1283280Y1372301D03*
X1293887Y1370043D03*
X1294477Y1372651D03*
X1285370Y1575686D03*
Y1580678D03*
X1297430D03*
X1292474D03*
Y1575686D03*
X1297430D03*
X1285714Y1599884D03*
X1290670D03*
X1297774D03*
X1285370Y1587598D03*
Y1592590D03*
X1297430D03*
X1292474D03*
X1297430Y1587598D03*
X1292474D03*
X1290670Y1616788D03*
X1285714D03*
Y1611796D03*
X1290670D03*
X1285714Y1604876D03*
X1290670D03*
X1297774Y1611796D03*
Y1604876D03*
Y1616788D03*
X1311960Y49672D03*
X1314450Y319841D03*
X1312845Y324764D03*
X1305909D03*
X1303017Y785837D03*
X1311952Y1321945D03*
X1307656Y1337104D03*
X1305056D03*
X1307656Y1334504D03*
Y1329304D03*
Y1331904D03*
X1305056Y1334504D03*
Y1329304D03*
Y1331904D03*
Y1339704D03*
X1312488Y1348353D03*
X1299605Y1342768D03*
X1302549Y1345891D03*
X1302520Y1348762D03*
X1315058Y1349488D03*
X1302549Y1342784D03*
X1309490Y1575686D03*
X1304534D03*
X1309490Y1580678D03*
X1304534D03*
X1302730Y1599884D03*
X1309834D03*
X1314790D03*
X1309490Y1587598D03*
X1304534D03*
X1309490Y1592590D03*
X1304534D03*
X1302730Y1611796D03*
Y1604876D03*
Y1616788D03*
X1309834D03*
Y1611796D03*
Y1604876D03*
X1314790Y1616788D03*
Y1611796D03*
Y1604876D03*
X1318609Y49388D03*
X1319125Y296540D03*
X1324081D03*
X1324636Y290920D03*
X1329592D03*
X1330248Y325670D03*
X1323312D03*
X1321386Y319841D03*
X1329977Y334384D03*
X1327601Y540049D03*
X1317970Y1322741D03*
Y1319634D03*
X1325770Y1322741D03*
X1323170D03*
X1331570Y1319634D03*
X1323170D03*
X1325770D03*
X1328370D03*
X1320570Y1322741D03*
Y1319634D03*
X1322444Y1329497D03*
X1324924D03*
X1319964D03*
X1322444Y1335097D03*
X1324924D03*
X1319964D03*
X1323370Y1325848D03*
X1325970D03*
X1324945Y1346877D03*
X1327196Y1349068D03*
X1321550Y1580678D03*
X1316594D03*
X1321550Y1575686D03*
X1316594D03*
X1328654D03*
Y1580678D03*
X1321894Y1599884D03*
X1326850D03*
X1321550Y1592590D03*
X1316594D03*
X1321550Y1587598D03*
X1316594D03*
X1328654D03*
Y1592590D03*
X1321894Y1611796D03*
Y1604876D03*
X1326850Y1611796D03*
Y1604876D03*
X1321894Y1616788D03*
X1326850D03*
X1332726Y-27681D03*
X1339019Y-26472D03*
X1332726Y-32055D03*
X1339019Y-37001D03*
X1332726Y-11497D03*
X1339019Y-16443D03*
X1332741Y-15137D03*
X1332726Y-17652D03*
Y-21526D03*
X1332741Y-25166D03*
X1332726Y2406D03*
X1332741Y4921D03*
X1339019Y3615D03*
X1332726Y-1468D03*
X1339019Y-6414D03*
X1332726Y-7623D03*
X1332741Y-5108D03*
X1332726Y18590D03*
Y22464D03*
X1339019Y13644D03*
X1332726Y12435D03*
X1332741Y14950D03*
X1332726Y8561D03*
X1332741Y24979D03*
X1339019Y23673D03*
X1338609Y49388D03*
X1346720Y82912D03*
X1343362Y283155D03*
X1335947Y290755D03*
X1340903D03*
X1343656Y330749D03*
X1343199Y324461D03*
X1336263D03*
X1336913Y334384D03*
X1335643Y540048D03*
X1336187Y755635D03*
X1339784Y1306506D03*
X1337184D03*
X1344080Y1305919D03*
X1343968Y1300579D03*
X1344080Y1308519D03*
X1334514Y1322757D03*
Y1319650D03*
X1337184Y1309106D03*
X1339784D03*
X1338534Y1319406D03*
X1339784Y1316906D03*
Y1314306D03*
Y1311706D03*
X1337184Y1314306D03*
Y1316906D03*
Y1311706D03*
X1334414Y1325853D03*
X1347015Y1335876D03*
X1343631Y1332568D03*
X1333610Y1575686D03*
Y1580678D03*
X1345670D03*
X1340714D03*
X1345670Y1575686D03*
X1340714D03*
X1338910Y1599884D03*
X1333954D03*
X1346014D03*
X1333610Y1587598D03*
Y1592590D03*
X1345670D03*
X1340714D03*
X1345670Y1587598D03*
X1340714D03*
X1338910Y1616788D03*
Y1611796D03*
Y1604876D03*
X1333954Y1616788D03*
Y1611796D03*
Y1604876D03*
X1346014Y1611796D03*
Y1604876D03*
Y1616788D03*
X1350550Y101632D03*
X1363846Y279848D03*
X1349362Y283155D03*
X1353902Y287540D03*
X1359902D03*
X1350592Y330749D03*
X1356968Y339611D03*
X1350032D03*
X1363539Y334043D03*
X1356603D03*
X1350098Y1306208D03*
X1352698D03*
X1355298D03*
X1360498D03*
X1363698D03*
X1357898D03*
X1352698Y1309315D03*
X1350098D03*
X1355498Y1312422D03*
X1358098D03*
X1355298Y1309315D03*
X1357898D03*
X1352092Y1316071D03*
Y1321671D03*
X1357052Y1316071D03*
X1354572D03*
X1357052Y1321671D03*
X1354572D03*
X1356983Y1334095D03*
X1359516Y1334058D03*
X1355357Y1396020D03*
X1357730Y1575686D03*
X1352774D03*
X1357730Y1580678D03*
X1352774D03*
X1350970Y1599884D03*
X1363030D03*
X1358074D03*
X1357730Y1587598D03*
X1352774D03*
X1357730Y1592590D03*
X1352774D03*
X1350970Y1611796D03*
Y1604876D03*
Y1616788D03*
X1363030D03*
Y1611796D03*
Y1604876D03*
X1358074Y1616788D03*
Y1611796D03*
Y1604876D03*
X1378550Y110692D03*
X1377742Y244372D03*
Y250372D03*
X1377626Y258914D03*
Y264914D03*
X1369846Y279848D03*
X1372381Y661428D03*
X1371931Y672978D03*
Y685278D03*
X1372243Y697108D03*
Y709108D03*
Y721108D03*
X1370662Y1305980D03*
X1371912Y1303480D03*
X1376208Y1305919D03*
Y1303319D03*
X1371912Y1300880D03*
X1376208Y1300719D03*
Y1295586D03*
X1371912Y1295747D03*
Y1298280D03*
X1376208Y1298119D03*
X1369312Y1303480D03*
X1366642Y1306224D03*
X1369312Y1300880D03*
Y1295747D03*
Y1298280D03*
X1376208Y1308519D03*
X1366542Y1312427D03*
X1366642Y1309331D03*
X1379271Y1335963D03*
X1375814Y1332653D03*
X1377060Y1411231D03*
X1371960Y1436172D03*
X1365040Y1431142D03*
X1369790Y1580678D03*
X1364834D03*
X1369790Y1575592D03*
X1364834D03*
X1376894Y1575686D03*
Y1580678D03*
X1375090Y1599790D03*
X1370134D03*
X1369790Y1592590D03*
X1364834D03*
X1369790Y1587598D03*
X1364834D03*
X1376894D03*
Y1592590D03*
X1375090Y1611796D03*
Y1604876D03*
Y1616788D03*
X1370134Y1611796D03*
Y1604876D03*
Y1616788D03*
X1383480Y88932D03*
X1383734Y243329D03*
Y237329D03*
X1388778Y250661D03*
X1388908Y260301D03*
X1386237Y265620D03*
Y275200D03*
X1385190Y501242D03*
X1390220Y497742D03*
X1381131Y656378D03*
Y668378D03*
X1395831Y666278D03*
X1386931Y660978D03*
X1381131Y680278D03*
X1396031Y680678D03*
X1386931Y675478D03*
X1387143Y690208D03*
X1380731Y692208D03*
X1395631Y695108D03*
X1380731Y704208D03*
X1387143Y704708D03*
X1380731Y716208D03*
X1395631Y709608D03*
X1387143Y719235D03*
X1395631Y724135D03*
X1382920Y733725D03*
X1391408Y738625D03*
X1382226Y1306208D03*
X1384826D03*
X1387426D03*
X1390026D03*
X1392626D03*
X1395826D03*
X1386700Y1321671D03*
X1389180D03*
X1382226Y1309315D03*
X1384826D03*
X1390226Y1312422D03*
X1387626D03*
X1390026Y1309315D03*
X1387426D03*
X1384220Y1316071D03*
Y1321671D03*
X1389180Y1316071D03*
X1386700D03*
X1390758Y1333473D03*
X1392076Y1335658D03*
X1388813Y1393160D03*
X1396115Y1405289D03*
Y1412789D03*
X1396615Y1420289D03*
X1384695Y1425047D03*
X1392475Y1576097D03*
X1381850Y1575686D03*
Y1580678D03*
X1396600Y1582500D03*
X1387150Y1599884D03*
X1382194D03*
X1381850Y1587598D03*
Y1592590D03*
X1396600Y1594000D03*
X1387150Y1616788D03*
X1382194D03*
X1387150Y1611796D03*
Y1604876D03*
X1382194Y1611796D03*
Y1604876D03*
X1404630Y220018D03*
X1412270Y230952D03*
X1405436Y238378D03*
X1400207Y238257D03*
X1398770Y1306224D03*
X1404040Y1303480D03*
X1408336Y1305919D03*
Y1303319D03*
X1404040Y1300880D03*
X1408336Y1300719D03*
Y1295586D03*
X1404040Y1295747D03*
Y1298280D03*
X1408336Y1298119D03*
X1401440Y1303480D03*
X1402790Y1305980D03*
X1401440Y1300880D03*
Y1295747D03*
Y1298280D03*
X1408336Y1308519D03*
X1398670Y1312427D03*
X1398770Y1309331D03*
X1411124Y1335924D03*
X1407719Y1332560D03*
X1403615Y1405289D03*
X1411115D03*
Y1412789D03*
X1403615Y1420289D03*
X1411115D03*
X1403350Y1516435D03*
X1403590Y1532255D03*
X1403350Y1521335D03*
X1403740Y1548375D03*
X1403590Y1537155D03*
X1403740Y1543475D03*
X1407200Y1591400D03*
X1411070Y1603282D03*
X1400000Y1630362D03*
Y1642362D03*
X1413350Y220018D03*
X1416020D03*
X1424690D03*
X1424520Y225002D03*
X1416810Y225422D03*
X1428640Y230022D03*
X1431430Y251265D03*
X1428940Y269292D03*
X1414354Y1306208D03*
X1416954D03*
X1419554D03*
X1422154D03*
X1424754D03*
X1427954D03*
X1418828Y1316071D03*
X1416348D03*
X1418828Y1321671D03*
X1416348D03*
X1421308Y1316071D03*
Y1321671D03*
X1414354Y1309315D03*
X1416954D03*
X1419554D03*
X1422354Y1312422D03*
X1419754D03*
X1422154Y1309315D03*
X1421294Y1334095D03*
X1423656Y1335468D03*
X1429345Y1433695D03*
X1427349Y1442776D03*
X1414264Y1439494D03*
X1419256Y1440258D03*
X1423829Y1442776D03*
X1416800Y1564862D03*
X1428403Y1581378D03*
X1418241Y1583441D03*
X1422145Y1575362D03*
X1426680Y1603262D03*
X1425770Y1633772D03*
X1413230Y1641042D03*
X1438609Y49388D03*
X1441125Y57362D03*
X1438680Y64412D03*
X1441490Y224062D03*
X1438720Y220018D03*
X1430130Y259342D03*
X1437177Y720965D03*
X1437182Y1298991D03*
X1430898Y1306224D03*
X1434582Y1304191D03*
Y1306791D03*
Y1301591D03*
Y1296458D03*
Y1298991D03*
X1440507Y1305430D03*
Y1302830D03*
Y1300230D03*
X1440536Y1296455D03*
X1440464Y1308519D03*
X1437182Y1304191D03*
Y1306791D03*
Y1301591D03*
Y1296458D03*
X1430798Y1312427D03*
X1430898Y1309331D03*
X1443785Y1335981D03*
X1440879Y1333085D03*
X1439155Y1399064D03*
X1431717Y1420625D03*
Y1417125D03*
Y1409125D03*
Y1427632D03*
X1436330Y1521152D03*
X1436570Y1536972D03*
X1436720Y1548192D03*
X1437140Y1576012D03*
X1438300Y1598400D03*
X1430250Y1608442D03*
X1438300Y1611000D03*
X1438273Y1671103D03*
X1458609Y49388D03*
X1458720Y153362D03*
Y149362D03*
Y169862D03*
Y165862D03*
Y161862D03*
Y157862D03*
Y181862D03*
Y177862D03*
Y173862D03*
X1446830Y236232D03*
X1453670Y278170D03*
X1459312Y341130D03*
X1460600Y352742D03*
X1456700Y369642D03*
X1454889Y658712D03*
X1454439Y670262D03*
Y682562D03*
X1454751Y694392D03*
Y706392D03*
X1454439Y718362D03*
X1459057Y733545D03*
X1457597Y739035D03*
X1446482Y1306208D03*
X1449082D03*
X1451682D03*
X1456882D03*
X1460082D03*
X1454282D03*
X1450956Y1321671D03*
X1448476D03*
X1453436Y1316071D03*
Y1321671D03*
X1446482Y1309315D03*
X1451882Y1312422D03*
X1449082Y1309315D03*
X1451682D03*
X1454482Y1312422D03*
X1454282Y1309315D03*
X1450956Y1316071D03*
X1448476D03*
X1453303Y1334095D03*
X1455436Y1335598D03*
X1461377Y1417844D03*
X1459135Y1439627D03*
X1459136Y1442241D03*
X1461517Y1575686D03*
Y1580678D03*
X1446600Y1595400D03*
X1461517Y1587598D03*
Y1592590D03*
X1460441Y1602441D03*
X1446786Y1610639D03*
X1452757Y1671399D03*
X1446380Y1676291D03*
X1464200Y67802D03*
X1470220Y145362D03*
X1470101Y207751D03*
X1476858Y225448D03*
X1466940Y230272D03*
X1466958Y244948D03*
X1468620Y258857D03*
X1467230Y252472D03*
X1466660Y273878D03*
X1475790Y404842D03*
X1473310Y418502D03*
X1463639Y653662D03*
X1469651Y655992D03*
X1462010Y645842D03*
X1463639Y665662D03*
X1478139Y660892D03*
X1469439Y670262D03*
X1463639Y677562D03*
X1463239Y689492D03*
X1478139Y689892D03*
X1469651Y684992D03*
X1463239Y701492D03*
X1478139Y704392D03*
X1469477Y699475D03*
X1463239Y713492D03*
X1478139Y718892D03*
X1469651Y713992D03*
X1474100Y735662D03*
X1466451Y726992D03*
X1474939Y731892D03*
X1472592Y1306345D03*
X1463026Y1306224D03*
X1465696Y1303480D03*
X1467046Y1305980D03*
X1468296Y1303480D03*
X1465696Y1300880D03*
X1468296D03*
X1472361Y1322440D03*
X1472592Y1308945D03*
Y1316745D03*
Y1314145D03*
Y1311545D03*
X1462926Y1312427D03*
X1463026Y1309331D03*
X1475599Y1349468D03*
X1475959Y1385027D03*
X1476000Y1393027D03*
X1465747Y1401405D03*
X1466448Y1421499D03*
X1475935Y1439627D03*
X1475936Y1442241D03*
X1467550Y1439642D03*
X1467536Y1442241D03*
X1473577Y1580678D03*
Y1575686D03*
X1466473D03*
Y1580678D03*
X1471773Y1599884D03*
X1466817D03*
X1473577Y1592590D03*
Y1587598D03*
X1466473D03*
Y1592590D03*
X1466817Y1611796D03*
X1471773D03*
X1466817Y1604876D03*
X1471773D03*
Y1616788D03*
X1466817D03*
X1478609Y49388D03*
X1481360Y358792D03*
X1488500Y410152D03*
X1478539Y675462D03*
X1486410Y1322741D03*
X1483810D03*
X1486410Y1319634D03*
X1483810D03*
X1481210Y1322741D03*
Y1319634D03*
X1492210D03*
X1489010D03*
X1478610Y1322741D03*
Y1319634D03*
X1484010Y1325848D03*
X1486610D03*
X1485564Y1335097D03*
X1483084D03*
X1485564Y1329497D03*
X1483084D03*
X1480604Y1335097D03*
Y1329497D03*
X1485523Y1347521D03*
X1487386Y1349258D03*
X1478559Y1385027D03*
X1481159Y1384727D03*
X1478600Y1393027D03*
X1481107Y1393095D03*
X1484395Y1439598D03*
X1484336Y1442241D03*
X1490593Y1580678D03*
Y1575686D03*
X1485637D03*
Y1580678D03*
X1478533D03*
Y1575686D03*
X1490937Y1599884D03*
X1478877D03*
X1483833D03*
X1490593Y1587598D03*
X1485637D03*
Y1592590D03*
X1490593D03*
X1478533D03*
Y1587598D03*
X1490937Y1604876D03*
Y1611796D03*
Y1616788D03*
X1483833D03*
X1478877D03*
Y1611796D03*
X1483833D03*
X1478877Y1604876D03*
X1483833D03*
X1498609Y49388D03*
X1496200Y359522D03*
X1497880Y373062D03*
X1503450Y382693D03*
X1497770Y732502D03*
X1495154Y1322757D03*
Y1319650D03*
X1499048Y1319946D03*
X1504720Y1329143D03*
X1495054Y1325853D03*
X1503786Y1326076D03*
X1504518Y1335982D03*
X1504720Y1342143D03*
Y1344743D03*
X1505116Y1369724D03*
X1509757Y1575686D03*
Y1580678D03*
X1502653D03*
X1497697D03*
X1502653Y1575686D03*
X1497697D03*
X1502997Y1599884D03*
X1507953D03*
X1495893D03*
X1509757Y1587598D03*
Y1592590D03*
X1502653D03*
X1497697D03*
X1502653Y1587598D03*
X1497697D03*
X1502997Y1616788D03*
X1507953D03*
X1502997Y1604876D03*
Y1611796D03*
X1507953Y1604876D03*
Y1611796D03*
X1495893Y1604876D03*
Y1611796D03*
Y1616788D03*
X1518608Y49377D03*
X1522920Y113030D03*
X1526675Y140117D03*
X1526083Y146225D03*
X1513759Y263676D03*
X1516683Y278437D03*
X1511624Y291175D03*
X1519336Y303426D03*
X1520094Y306543D03*
X1514369Y308467D03*
X1524505Y748912D03*
X1522066Y1312808D03*
X1526066D03*
X1518066D03*
X1515066D03*
X1511066D03*
X1510738Y1345539D03*
Y1342432D03*
X1518538Y1345539D03*
Y1342432D03*
X1515938Y1345539D03*
Y1342432D03*
X1513338Y1345539D03*
Y1342432D03*
X1521138D03*
X1524338D03*
X1518738Y1348646D03*
X1516138D03*
X1515212Y1352295D03*
X1512732D03*
X1517692D03*
X1515212Y1357895D03*
X1512732D03*
X1517692D03*
X1518451Y1369919D03*
X1521817Y1580678D03*
Y1575686D03*
X1514713D03*
Y1580678D03*
X1520013Y1599884D03*
X1515057D03*
X1521817Y1592590D03*
Y1587598D03*
X1514713D03*
Y1592590D03*
X1520013Y1604876D03*
X1515057D03*
X1520013Y1611796D03*
X1515057D03*
Y1616788D03*
X1520013D03*
X1534818Y66801D03*
Y71793D03*
X1539774Y66801D03*
Y71793D03*
X1541774Y69297D03*
X1532818D03*
X1534774Y103093D03*
X1529818D03*
X1535320Y113062D03*
X1529500Y129602D03*
X1545447Y156035D03*
X1537262Y197834D03*
X1540989Y616587D03*
X1535052Y1325904D03*
X1532552Y1334504D03*
X1535052D03*
X1529952D03*
X1532552Y1339704D03*
X1529952D03*
X1537652Y1325904D03*
Y1334504D03*
X1532552Y1337104D03*
X1529952D03*
X1538510Y1346392D03*
X1531302Y1342204D03*
X1535892Y1346354D03*
Y1343754D03*
X1527282Y1345555D03*
Y1342448D03*
X1538757Y1356355D03*
X1527182Y1348651D03*
X1538757Y1360855D03*
Y1365355D03*
X1533877Y1575592D03*
X1538833D03*
X1533877Y1580678D03*
X1538833D03*
X1526773D03*
Y1575686D03*
X1539177Y1599790D03*
X1527117Y1599884D03*
X1532073D03*
X1533877Y1587598D03*
X1538833D03*
X1533877Y1592590D03*
X1538833D03*
X1526773D03*
Y1587598D03*
X1539177Y1611796D03*
Y1604876D03*
Y1616788D03*
X1527117D03*
Y1604876D03*
Y1611796D03*
X1532073Y1616788D03*
Y1604876D03*
Y1611796D03*
X1547768Y3010D03*
X1555635Y16999D03*
Y21991D03*
X1553635Y19495D03*
X1553486Y23935D03*
X1548530D03*
X1546530Y25931D03*
X1555486D03*
X1547429Y37106D03*
X1554515D03*
Y48720D03*
X1547429D03*
X1554818Y69297D03*
X1556818Y66801D03*
Y71793D03*
X1543818Y75297D03*
X1552774D03*
X1550774Y77793D03*
Y72801D03*
X1545818Y77793D03*
Y72801D03*
X1554239Y138263D03*
X1554723Y200375D03*
X1557560Y196912D03*
X1554723Y224529D03*
Y248945D03*
X1554727Y631527D03*
X1550417Y677045D03*
X1550057Y693485D03*
X1548479Y706088D03*
X1557997Y1575686D03*
Y1580678D03*
X1550893D03*
X1545937D03*
X1550893Y1575686D03*
X1545937D03*
X1556193Y1599884D03*
X1551237D03*
X1544133Y1599790D03*
X1557997Y1587598D03*
Y1592590D03*
X1545937D03*
X1550893D03*
Y1587598D03*
X1545937D03*
X1551237Y1616788D03*
X1556193D03*
Y1604876D03*
X1551237D03*
X1556193Y1611796D03*
X1551237D03*
X1544133Y1604876D03*
Y1611796D03*
Y1616788D03*
X1567768Y3010D03*
X1560591Y16999D03*
Y21991D03*
X1569808Y16999D03*
Y21991D03*
X1574764Y16999D03*
Y21991D03*
X1562591Y19495D03*
X1567808D03*
X1567659Y23935D03*
X1562703D03*
X1560703Y25931D03*
X1569659D03*
X1574876D03*
X1561602Y37106D03*
X1568688D03*
Y48720D03*
X1561602D03*
X1563774Y69297D03*
X1561774Y66801D03*
Y71793D03*
X1565818Y75297D03*
X1574774D03*
X1572774Y77793D03*
Y72801D03*
X1567818Y77793D03*
Y72801D03*
X1559860Y240002D03*
X1575169Y303929D03*
X1560717Y648522D03*
X1570720Y729362D03*
X1570057Y1580678D03*
X1575013D03*
X1570057Y1575686D03*
X1575013D03*
X1562953D03*
Y1580678D03*
X1575357Y1599884D03*
X1563297D03*
X1568253D03*
X1570057Y1592590D03*
X1575013D03*
X1570057Y1587598D03*
X1575013D03*
X1562953D03*
Y1592590D03*
X1575357Y1616788D03*
Y1604876D03*
Y1611796D03*
X1563297Y1604876D03*
Y1611796D03*
X1568253Y1604876D03*
Y1611796D03*
X1563297Y1616788D03*
X1568253D03*
X1587768Y3010D03*
X1583981Y16999D03*
Y21991D03*
X1588937Y16999D03*
Y21991D03*
X1576764Y19495D03*
X1581981D03*
X1590937D03*
X1576876Y23935D03*
X1581832D03*
X1591050D03*
X1583832Y25931D03*
X1589050D03*
X1575775Y37106D03*
X1582862D03*
X1589948D03*
Y48720D03*
X1582862D03*
X1575775D03*
X1576818Y69297D03*
X1585774D03*
X1578818Y66801D03*
Y71793D03*
X1583774Y66801D03*
Y71793D03*
X1587818Y75297D03*
X1589818Y77793D03*
Y72801D03*
X1582117Y1575686D03*
X1587073D03*
X1582117Y1580678D03*
X1587073D03*
X1587417Y1599884D03*
X1580313D03*
X1582117Y1587598D03*
X1587073D03*
X1582117Y1592590D03*
X1587073D03*
X1587417Y1604876D03*
Y1611796D03*
Y1616788D03*
X1580313D03*
Y1604876D03*
Y1611796D03*
X1607768Y3010D03*
X1598155Y16999D03*
Y21991D03*
X1603111Y16999D03*
Y21991D03*
X1596155Y19495D03*
X1605111D03*
X1596006Y23935D03*
X1598006Y25931D03*
X1597035Y37106D03*
X1604122D03*
Y48720D03*
X1597035D03*
X1598818Y69297D03*
X1607774D03*
X1600818Y66801D03*
Y71793D03*
X1605774Y66801D03*
Y71793D03*
X1596774Y75297D03*
X1594774Y77793D03*
Y72801D03*
X1603778Y189943D03*
X1603726Y198061D03*
X1596444Y215526D03*
X1598030Y251002D03*
X1606980Y1449922D03*
X1606237Y1575686D03*
Y1580678D03*
X1594177D03*
X1599133D03*
X1594177Y1575686D03*
X1599133D03*
X1599477Y1599884D03*
X1604433D03*
X1592373D03*
X1606237Y1587598D03*
Y1592590D03*
X1594177D03*
X1599133D03*
X1594177Y1587598D03*
X1599133D03*
X1599477Y1616788D03*
X1604433D03*
X1599477Y1604876D03*
Y1611796D03*
X1604433Y1604876D03*
Y1611796D03*
X1592373Y1604876D03*
Y1611796D03*
Y1616788D03*
X1620818Y69297D03*
X1622818Y66801D03*
Y71793D03*
X1609818Y75297D03*
X1618774D03*
X1616774Y77793D03*
Y72801D03*
X1611818Y77793D03*
Y72801D03*
X1623448Y1420028D03*
Y1417428D03*
Y1414828D03*
Y1412228D03*
X1612630Y1418842D03*
X1615597Y1433669D03*
X1618297Y1580678D03*
X1623253D03*
X1618297Y1575686D03*
X1623253D03*
X1611193D03*
Y1580678D03*
X1623597Y1599884D03*
X1611537D03*
X1616493D03*
X1618297Y1592590D03*
X1623253D03*
X1618297Y1587598D03*
X1623253D03*
X1611193D03*
Y1592590D03*
X1623597Y1616788D03*
Y1604876D03*
Y1611796D03*
X1611537Y1604876D03*
Y1611796D03*
X1616493Y1604876D03*
Y1611796D03*
X1611537Y1616788D03*
X1616493D03*
X1634021Y16999D03*
Y21991D03*
X1638977Y16999D03*
Y21991D03*
X1632021Y19495D03*
X1631872Y23935D03*
X1626916D03*
X1624916Y25931D03*
X1633872D03*
X1639089D03*
X1625814Y37106D03*
X1632901D03*
X1639988D03*
X1625814Y48720D03*
X1632901D03*
X1639988D03*
X1629774Y69297D03*
X1627774Y66801D03*
Y71793D03*
X1633022Y75297D03*
X1635022Y77793D03*
X1639978D03*
Y72801D03*
X1635022D03*
X1635032Y196188D03*
X1642135Y414202D03*
X1629262Y1394418D03*
X1625948Y1417428D03*
Y1412228D03*
X1633103Y1417907D03*
X1630503D03*
X1635703D03*
X1633103Y1421014D03*
X1630503D03*
X1635703D03*
X1638303Y1417907D03*
Y1421014D03*
X1625948Y1414828D03*
Y1420028D03*
X1635903Y1424121D03*
X1638503D03*
X1632516Y1427753D03*
Y1433353D03*
X1634986Y1427753D03*
Y1433353D03*
X1637416Y1427753D03*
Y1433353D03*
X1627591Y1447796D03*
X1637478Y1445150D03*
X1630357Y1575592D03*
X1635313D03*
X1630357Y1580678D03*
X1635313D03*
X1640613Y1599790D03*
X1635657D03*
X1628553Y1599884D03*
X1630357Y1587598D03*
X1635313D03*
X1630357Y1592590D03*
X1635313D03*
X1640613Y1604876D03*
Y1611796D03*
X1635657Y1604876D03*
Y1611796D03*
X1640613Y1616788D03*
X1635657D03*
X1628553D03*
Y1604876D03*
Y1611796D03*
X1648194Y16999D03*
Y21991D03*
X1653150Y16999D03*
Y21991D03*
X1640977Y19495D03*
X1646194D03*
X1655150D03*
X1641089Y23935D03*
X1646045D03*
X1648045Y25931D03*
X1654161Y37106D03*
X1647074D03*
Y48720D03*
X1654161D03*
X1644022Y69297D03*
X1652978D03*
X1646022Y66801D03*
Y71793D03*
X1650978Y66801D03*
Y71793D03*
X1655022Y75297D03*
X1641978D03*
X1657022Y77793D03*
Y72801D03*
X1652610Y394727D03*
X1652810Y407402D03*
X1647110Y434177D03*
X1651890Y520540D03*
X1649220Y620662D03*
X1656188Y1394736D03*
X1647592Y1394418D03*
X1655779Y1417618D03*
Y1412418D03*
Y1415018D03*
X1644103Y1417907D03*
X1647047Y1417923D03*
Y1421030D03*
X1653279Y1412418D03*
X1650679D03*
X1653279Y1415018D03*
X1650679D03*
X1653168Y1417618D03*
X1650557D03*
X1640903Y1417907D03*
X1647016Y1424153D03*
X1648947Y1476695D03*
X1647373Y1580678D03*
X1642417D03*
X1647373Y1575686D03*
X1642417D03*
X1647717Y1599884D03*
X1652673D03*
X1647373Y1592590D03*
X1642417D03*
X1647373Y1587598D03*
X1642417D03*
X1647717Y1616788D03*
X1652673D03*
X1647717Y1604876D03*
Y1611796D03*
X1652673Y1604876D03*
Y1611796D03*
X1671050Y23935D03*
X1669050Y25931D03*
X1669948Y37106D03*
Y48720D03*
X1666022Y69297D03*
X1668022Y66801D03*
Y71793D03*
X1672978Y66801D03*
Y71793D03*
X1663978Y75297D03*
X1661978Y77793D03*
Y72801D03*
X1668030Y200580D03*
X1666074Y229710D03*
X1660176Y231100D03*
X1670400Y229462D03*
X1659610Y394727D03*
X1663610D03*
X1661110Y434177D03*
X1660866Y546749D03*
X1664040Y569642D03*
X1668040D03*
X1672040D03*
X1662120Y604782D03*
X1657220Y620662D03*
X1667405Y1394418D03*
X1659260Y1394693D03*
X1658390Y1420218D03*
Y1415018D03*
Y1412418D03*
Y1417618D03*
X1663590Y1420218D03*
X1660990D03*
Y1415018D03*
Y1417618D03*
Y1412418D03*
X1663590Y1415018D03*
Y1417618D03*
Y1412418D03*
X1668646Y1417907D03*
Y1421014D03*
X1671246Y1417907D03*
Y1421014D03*
X1670659Y1427753D03*
X1673129D03*
X1670659Y1433353D03*
X1673129D03*
X1657438Y1438156D03*
X1660428Y1447566D03*
X1667577Y1447545D03*
X1666123Y1497362D03*
X1665940Y1512862D03*
X1666110Y1504662D03*
X1666123Y1524862D03*
Y1537862D03*
Y1541862D03*
Y1553557D03*
X1666198Y1565557D03*
Y1585321D03*
X1678155Y16999D03*
Y21991D03*
X1683111Y16999D03*
Y21991D03*
X1676155Y19495D03*
X1685111D03*
X1676006Y23935D03*
X1685223D03*
X1678006Y25931D03*
X1683223D03*
X1677035Y37106D03*
X1684122D03*
X1677035Y48720D03*
X1684122D03*
X1688156Y69297D03*
X1674978D03*
X1677156Y75297D03*
X1686112D03*
X1684112Y77793D03*
Y72801D03*
X1679156Y77793D03*
Y72801D03*
X1676300Y219762D03*
X1681900Y227962D03*
X1682810Y465940D03*
X1676040Y569627D03*
X1688301Y722158D03*
X1683121D03*
X1680401D03*
X1686135Y1394418D03*
X1687860Y1415179D03*
X1689210Y1417679D03*
X1687860Y1412579D03*
X1685190Y1417923D03*
X1676446Y1417907D03*
X1679046D03*
X1682246D03*
X1676446Y1421014D03*
X1685190Y1421030D03*
X1673846Y1417907D03*
Y1421014D03*
X1676646Y1424121D03*
X1685159Y1424153D03*
X1675559Y1427753D03*
Y1433353D03*
X1674046Y1424121D03*
X1675621Y1445150D03*
X1679508Y1503421D03*
Y1522921D03*
Y1543921D03*
Y1563380D03*
Y1583880D03*
X1692328Y16999D03*
Y21991D03*
X1697284Y16999D03*
Y21991D03*
X1690328Y19495D03*
X1699284D03*
X1690179Y23935D03*
X1692179Y25931D03*
X1691208Y37106D03*
X1698295D03*
X1705381D03*
X1698295Y48720D03*
X1691208D03*
X1705381D03*
X1697112Y69297D03*
X1690156Y66801D03*
Y71793D03*
X1695112Y66801D03*
Y71793D03*
X1699156Y75297D03*
X1701156Y77793D03*
Y72801D03*
X1695950Y96437D03*
X1697725Y205120D03*
X1700846Y455894D03*
X1702760Y478207D03*
X1696760D03*
X1702760Y490207D03*
X1696760D03*
Y484207D03*
X1696120Y506937D03*
X1703720Y509362D03*
X1696851Y515607D03*
X1693701D03*
X1702270Y552742D03*
X1698920Y698562D03*
X1695227Y722325D03*
X1699307Y722465D03*
X1698137Y718345D03*
X1701087Y719055D03*
X1695367Y719345D03*
X1691021Y722158D03*
X1698537Y766015D03*
X1690809Y1393970D03*
X1699150Y1393613D03*
X1690460Y1415179D03*
Y1412579D03*
X1691918Y1417676D03*
X1692960Y1415179D03*
Y1412579D03*
X1693404Y1421939D03*
X1699593Y1428384D03*
X1697820Y1423616D03*
X1699545Y1425868D03*
X1699437Y1431295D03*
X1699457Y1439185D03*
Y1447805D03*
X1691988Y1498303D03*
Y1517803D03*
Y1538803D03*
Y1558262D03*
X1714520Y37162D03*
X1710920Y82162D03*
X1708112Y75297D03*
X1706112Y77793D03*
Y72801D03*
X1708000Y99122D03*
X1714180Y154790D03*
X1721400Y374462D03*
X1711477Y465229D03*
Y468379D03*
X1708760Y478031D03*
Y490207D03*
Y484207D03*
X1710500Y538162D03*
X1706720Y703762D03*
X1709107Y728449D03*
X1718149Y1496270D03*
X1717149Y1505895D03*
X1720174D03*
X1717988Y1520951D03*
X1711988D03*
X1717149Y1513945D03*
X1720174D03*
X1714988Y1520951D03*
X1708988D03*
X1717988Y1530445D03*
X1714988D03*
X1708988D03*
X1711988D03*
X1727768Y3010D03*
X1732320Y28162D03*
X1728820D03*
X1725320D03*
X1729520Y61762D03*
X1729620Y57262D03*
X1730820Y76362D03*
X1726918Y101967D03*
X1733378Y134907D03*
X1736508D03*
X1723240Y185200D03*
X1737704Y183139D03*
X1737260Y368132D03*
X1732660Y372692D03*
X1725400Y372062D03*
X1725500Y383662D03*
X1737434Y398990D03*
X1727760Y420415D03*
X1747768Y3010D03*
X1754090Y16302D03*
X1748400Y37262D03*
X1753398Y48720D03*
X1745485Y119539D03*
X1747482Y121367D03*
X1741222Y151527D03*
X1747591Y171733D03*
X1751084Y190928D03*
X1745000Y299862D03*
X1746970Y1451872D03*
X1750970Y1459172D03*
Y1456172D03*
X1767768Y3010D03*
X1769900Y37732D03*
X1760485Y48720D03*
X1759700Y57662D03*
X1764400Y57462D03*
X1758063Y68637D03*
X1758573Y87107D03*
Y83607D03*
X1768168Y80497D03*
X1758568Y79697D03*
X1765068Y80397D03*
X1766278Y93627D03*
X1768483Y166260D03*
X1763731Y283817D03*
X1766725Y282981D03*
X1763731Y279517D03*
X1760398Y279548D03*
X1766765Y279433D03*
X1757439Y279611D03*
X1760398Y283848D03*
X1759509Y292434D03*
X1762549Y286704D03*
X1757439Y283911D03*
X1768045Y295238D03*
X1765053Y295188D03*
X1762285Y295137D03*
X1759629Y295164D03*
X1767309Y290994D03*
X1763045Y289691D03*
X1759529Y289864D03*
X1766655Y286531D03*
X1767455Y302651D03*
X1758563Y310478D03*
X1754963D03*
X1770520Y364148D03*
Y368148D03*
X1767300Y461393D03*
X1765670Y458012D03*
X1767300Y465893D03*
X1764112Y703948D03*
X1761612D03*
X1764112Y695648D03*
X1763570Y693192D03*
X1761612Y695648D03*
X1764072Y720508D03*
X1761572D03*
X1764112Y712248D03*
X1761612D03*
X1760160Y1476032D03*
X1763730Y1483712D03*
Y1480712D03*
X1763830Y1490782D03*
Y1487782D03*
X1785178Y86927D03*
Y89927D03*
X1784238Y150744D03*
X1786690Y234782D03*
Y231782D03*
X1771029Y295164D03*
X1771229Y291064D03*
X1772863Y310478D03*
X1782420Y443987D03*
X1773870Y438222D03*
X1776160Y592792D03*
X1787768Y3010D03*
X1794910Y44573D03*
X1797324Y161465D03*
X1803129Y362293D03*
X1802929Y385293D03*
X1795479Y408056D03*
X1795468Y421334D03*
X1800107Y1256426D03*
X1795484Y1496401D03*
X1792645Y1511423D03*
X1798450Y1524830D03*
X1801450D03*
Y1527830D03*
X1814322Y49388D03*
X1807549Y56415D03*
X1807580Y59397D03*
X1810835Y163986D03*
X1806365Y154032D03*
X1819939Y177243D03*
X1820307Y373829D03*
X1820144Y398052D03*
X1819374Y410432D03*
X1818874Y423932D03*
X1818816Y468872D03*
X1803517Y1495567D03*
X1818410Y1525815D03*
X1812250Y1521830D03*
X1811250Y1524830D03*
Y1527830D03*
X1807850D03*
X1804650D03*
Y1524830D03*
X1807850D03*
X1814370Y1528900D03*
X1814210Y1525815D03*
X1818524Y1528991D03*
X1834322Y49388D03*
X1823508Y158868D03*
X1829026Y367701D03*
X1823426Y1507916D03*
X1831994Y1525977D03*
X1835334Y1520921D03*
X1828510Y1525915D03*
X1821710D03*
X1830466Y1606658D03*
X1838910Y185772D03*
X1843134Y244362D03*
X1836750Y373632D03*
X1838020Y459121D03*
X1854096Y52383D03*
G54D43*
X335349Y985939D03*
X549278Y949619D03*
X1300207Y177799D03*
X1311491Y985939D03*
X1355761Y177798D03*
X1525420Y949619D03*
X1879155Y592848D03*
Y840748D03*
X1889155Y592848D03*
Y840748D03*
X1900275Y964708D03*
X1910275D03*
X1931395Y592868D03*
X1921395D03*
X1952395Y1205248D03*
X1942395D03*
X1963362Y593010D03*
X1973362D03*
X1984482Y1205220D03*
X1994482D03*
X2015452Y593020D03*
X2005452D03*
X2026452Y1205400D03*
X2047419Y593162D03*
X2036452Y1205400D03*
X2057419Y593162D03*
X2078539Y1205372D03*
X2068539D03*
G54D57*
X828780Y1694890D03*
Y1684890D03*
X818780Y1694890D03*
Y1684890D03*
X828780Y1704890D03*
X818780D03*
X828780Y1714890D03*
X818780D03*
X853780Y1694890D03*
Y1684890D03*
Y1704890D03*
Y1714890D03*
X863780Y1694890D03*
Y1684890D03*
Y1704890D03*
Y1714890D03*
X888780Y1684890D03*
Y1694890D03*
Y1704890D03*
Y1714890D03*
X898780Y1684890D03*
Y1694890D03*
Y1704890D03*
Y1714890D03*
X918780Y1704890D03*
X958780Y1694890D03*
Y1684890D03*
Y1704890D03*
Y1714890D03*
X968780Y1694890D03*
Y1684890D03*
Y1704890D03*
Y1714890D03*
X993780Y1684890D03*
Y1694890D03*
X1003780Y1684890D03*
Y1694890D03*
X993780Y1704890D03*
Y1714890D03*
X1003780Y1704890D03*
Y1714890D03*
X1028780Y1684890D03*
Y1694890D03*
X1038780Y1684890D03*
Y1694890D03*
X1028780Y1704890D03*
Y1714890D03*
X1038780Y1704890D03*
Y1714890D03*
G54D16*
X27699Y770144D03*
Y783530D03*
Y776837D03*
Y800263D03*
Y793570D03*
Y820341D03*
Y813648D03*
Y806955D03*
Y830381D03*
Y850459D03*
Y843766D03*
Y837074D03*
Y867192D03*
Y857152D03*
Y880577D03*
Y873885D03*
Y893963D03*
Y887270D03*
Y917389D03*
Y910696D03*
Y904003D03*
Y930774D03*
Y924081D03*
Y947507D03*
Y940814D03*
Y964239D03*
Y954200D03*
Y977625D03*
Y970932D03*
Y991011D03*
Y984318D03*
Y1031168D03*
Y1024475D03*
Y1017782D03*
Y1044554D03*
Y1037861D03*
Y1057940D03*
Y1051247D03*
Y1078018D03*
Y1071326D03*
Y1064633D03*
Y1094751D03*
Y1088058D03*
Y1108137D03*
Y1101444D03*
Y1124869D03*
Y1114829D03*
Y1144948D03*
Y1138255D03*
Y1131562D03*
Y1161680D03*
Y1151641D03*
Y1175066D03*
Y1168373D03*
Y1188452D03*
Y1181759D03*
Y1205184D03*
Y1198491D03*
Y1225263D03*
Y1218570D03*
Y1211877D03*
Y1241995D03*
Y1235302D03*
Y1248688D03*
X43841Y766798D03*
X36399Y770144D03*
X43841Y780184D03*
Y773491D03*
X36399Y783530D03*
Y776837D03*
X43841Y803609D03*
Y796916D03*
Y790223D03*
X36399Y800263D03*
Y793570D03*
X43841Y816995D03*
Y810302D03*
X36399Y820341D03*
Y813648D03*
Y806955D03*
X43841Y833727D03*
Y827034D03*
X36399Y830381D03*
X43841Y847113D03*
Y840420D03*
X36399Y850459D03*
Y843766D03*
Y837074D03*
X43841Y863845D03*
Y853806D03*
X36399Y867192D03*
Y857152D03*
X43841Y883924D03*
Y877231D03*
Y870538D03*
X36399Y880577D03*
Y873885D03*
X43841Y900656D03*
Y890617D03*
X36399Y893963D03*
Y887270D03*
X43841Y914042D03*
Y907349D03*
X36399Y917389D03*
Y910696D03*
Y904003D03*
X43841Y927428D03*
Y920735D03*
X36399Y930774D03*
Y924081D03*
X43841Y944160D03*
Y937467D03*
X36399Y947507D03*
Y940814D03*
X43841Y960892D03*
Y950853D03*
X36399Y964239D03*
Y954200D03*
X43841Y980971D03*
Y974278D03*
Y967585D03*
X36399Y977625D03*
Y970932D03*
X43841Y987664D03*
X36399Y991011D03*
Y984318D03*
X43841Y1027822D03*
Y1017782D03*
X36399Y1031168D03*
Y1024475D03*
Y1017782D03*
X43841Y1047900D03*
Y1041207D03*
Y1034515D03*
X36399Y1044554D03*
Y1037861D03*
X43841Y1061286D03*
Y1054593D03*
X36399Y1057940D03*
Y1051247D03*
X43841Y1074672D03*
Y1067979D03*
X36399Y1078018D03*
Y1071326D03*
Y1064633D03*
X43841Y1091404D03*
Y1084711D03*
X36399Y1094751D03*
Y1088058D03*
X43841Y1111483D03*
Y1104790D03*
Y1098097D03*
X36399Y1108137D03*
Y1101444D03*
X43841Y1128215D03*
Y1121522D03*
X36399Y1124869D03*
Y1114829D03*
X43841Y1141601D03*
Y1134908D03*
X36399Y1144948D03*
Y1138255D03*
Y1131562D03*
X43841Y1158333D03*
Y1148294D03*
X36399Y1161680D03*
Y1151641D03*
X43841Y1171719D03*
Y1165026D03*
X36399Y1175066D03*
Y1168373D03*
X43841Y1185105D03*
Y1178412D03*
X36399Y1188452D03*
Y1181759D03*
X43841Y1208530D03*
Y1201837D03*
Y1195144D03*
X36399Y1205184D03*
Y1198491D03*
X43841Y1221916D03*
Y1215223D03*
X36399Y1225263D03*
Y1218570D03*
Y1211877D03*
X43841Y1238648D03*
Y1231955D03*
X36399Y1241995D03*
Y1235302D03*
X43841Y1245341D03*
X36399Y1248688D03*
X36449Y1257262D03*
X33546Y1273364D03*
X30746D03*
X57399Y770144D03*
X52541Y766798D03*
X57399Y783530D03*
Y776837D03*
X52541Y780184D03*
Y773491D03*
X57399Y800263D03*
Y793570D03*
X52541Y803609D03*
Y796916D03*
Y790223D03*
X57399Y820341D03*
Y813648D03*
Y806955D03*
X52541Y816995D03*
Y810302D03*
X57399Y830381D03*
X52541Y833727D03*
Y827034D03*
X57399Y850459D03*
Y843766D03*
Y837074D03*
X52541Y847113D03*
Y840420D03*
X57399Y867192D03*
Y857152D03*
X52541Y863845D03*
Y853806D03*
X57399Y880577D03*
Y873885D03*
X52541Y883924D03*
Y877231D03*
Y870538D03*
X57399Y893963D03*
Y887270D03*
X52541Y900656D03*
Y890617D03*
X57399Y917389D03*
Y910696D03*
Y904003D03*
X52541Y914042D03*
Y907349D03*
X57399Y930774D03*
Y924081D03*
X52541Y927428D03*
Y920735D03*
X57399Y947507D03*
Y940814D03*
X52541Y944160D03*
Y937467D03*
X57399Y964239D03*
Y954200D03*
X52541Y960892D03*
Y950853D03*
X57399Y977625D03*
Y970932D03*
X52541Y980971D03*
Y974278D03*
Y967585D03*
X57399Y991011D03*
Y984318D03*
X52541Y987664D03*
X57399Y1031168D03*
Y1024475D03*
Y1017782D03*
X52541Y1027822D03*
Y1017782D03*
X57399Y1044554D03*
Y1037861D03*
X52541Y1047900D03*
Y1041207D03*
Y1034515D03*
X57399Y1057940D03*
Y1051247D03*
X52541Y1061286D03*
Y1054593D03*
X57399Y1078018D03*
Y1071326D03*
Y1064633D03*
X52541Y1074672D03*
Y1067979D03*
X57399Y1094751D03*
Y1088058D03*
X52541Y1091404D03*
Y1084711D03*
X57399Y1108137D03*
Y1101444D03*
X52541Y1111483D03*
Y1104790D03*
Y1098097D03*
X57399Y1124869D03*
Y1114829D03*
X52541Y1128215D03*
Y1121522D03*
X57399Y1144948D03*
Y1138255D03*
Y1131562D03*
X52541Y1141601D03*
Y1134908D03*
X57399Y1161680D03*
Y1151641D03*
X52541Y1158333D03*
Y1148294D03*
X57399Y1175066D03*
Y1168373D03*
X52541Y1171719D03*
Y1165026D03*
X57399Y1188452D03*
Y1181759D03*
X52541Y1185105D03*
Y1178412D03*
X57399Y1205184D03*
Y1198491D03*
X52541Y1208530D03*
Y1201837D03*
Y1195144D03*
X57399Y1225263D03*
Y1218570D03*
Y1211877D03*
X52541Y1221916D03*
Y1215223D03*
X57399Y1241995D03*
Y1235302D03*
X52541Y1238648D03*
Y1231955D03*
Y1248688D03*
X57399D03*
X52541Y1245341D03*
X60446Y1273364D03*
X49546D03*
X46746D03*
X73541Y766798D03*
X66099Y770144D03*
X73541Y780184D03*
Y773491D03*
X66099Y783530D03*
Y776837D03*
X73541Y803609D03*
Y796916D03*
Y790223D03*
X66099Y800263D03*
Y793570D03*
X73541Y816995D03*
Y810302D03*
X66099Y820341D03*
Y813648D03*
Y806955D03*
X73541Y833727D03*
Y827034D03*
X66099Y830381D03*
X73541Y847113D03*
Y840420D03*
X66099Y850459D03*
Y843766D03*
Y837074D03*
X73541Y863845D03*
Y853806D03*
X66099Y867192D03*
Y857152D03*
X73541Y883924D03*
Y877231D03*
Y870538D03*
X66099Y880577D03*
Y873885D03*
X73541Y900656D03*
Y890617D03*
X66099Y893963D03*
Y887270D03*
X73541Y914042D03*
Y907349D03*
X66099Y917389D03*
Y910696D03*
Y904003D03*
X73541Y927428D03*
Y920735D03*
X66099Y930774D03*
Y924081D03*
X73541Y944160D03*
Y937467D03*
X66099Y947507D03*
Y940814D03*
X73541Y960892D03*
Y950853D03*
X66099Y964239D03*
Y954200D03*
X73541Y980971D03*
Y974278D03*
Y967585D03*
X66099Y977625D03*
Y970932D03*
X73541Y987664D03*
X66099Y991011D03*
Y984318D03*
X73541Y1027822D03*
Y1017782D03*
X66099Y1031168D03*
Y1024475D03*
Y1017782D03*
X73541Y1047900D03*
Y1041207D03*
Y1034515D03*
X66099Y1044554D03*
Y1037861D03*
X73541Y1061286D03*
Y1054593D03*
X66099Y1057940D03*
Y1051247D03*
X73541Y1074672D03*
Y1067979D03*
X66099Y1078018D03*
Y1071326D03*
Y1064633D03*
X73541Y1091404D03*
Y1084711D03*
X66099Y1094751D03*
Y1088058D03*
X73541Y1111483D03*
Y1104790D03*
Y1098097D03*
X66099Y1108137D03*
Y1101444D03*
X73541Y1128215D03*
Y1121522D03*
X66099Y1124869D03*
Y1114829D03*
X73541Y1141601D03*
Y1134908D03*
X66099Y1144948D03*
Y1138255D03*
Y1131562D03*
X73541Y1158333D03*
Y1148294D03*
X66099Y1161680D03*
Y1151641D03*
X73541Y1171719D03*
Y1165026D03*
X66099Y1175066D03*
Y1168373D03*
X73541Y1185105D03*
Y1178412D03*
X66099Y1188452D03*
Y1181759D03*
X73541Y1208530D03*
Y1201837D03*
Y1195144D03*
X66099Y1205184D03*
Y1198491D03*
X73541Y1221916D03*
Y1215223D03*
X66099Y1225263D03*
Y1218570D03*
Y1211877D03*
X73541Y1238648D03*
Y1231955D03*
X66099Y1241995D03*
Y1235302D03*
X66189Y1257488D03*
X73541Y1245341D03*
X66099Y1248688D03*
X76446Y1273364D03*
X63246D03*
X87099Y770144D03*
X82241Y766798D03*
X87099Y783530D03*
Y776837D03*
X82241Y780184D03*
Y773491D03*
X87099Y800263D03*
Y793570D03*
X82241Y803609D03*
Y796916D03*
Y790223D03*
X87099Y820341D03*
Y813648D03*
Y806955D03*
X82241Y816995D03*
Y810302D03*
X87099Y830381D03*
X82241Y833727D03*
Y827034D03*
X87099Y850459D03*
Y843766D03*
Y837074D03*
X82241Y847113D03*
Y840420D03*
X87099Y867192D03*
Y857152D03*
X82241Y863845D03*
Y853806D03*
X87099Y880577D03*
Y873885D03*
X82241Y883924D03*
Y877231D03*
Y870538D03*
X87099Y893963D03*
Y887270D03*
X82241Y900656D03*
Y890617D03*
X87099Y917389D03*
Y910696D03*
Y904003D03*
X82241Y914042D03*
Y907349D03*
X87099Y930774D03*
Y924081D03*
X82241Y927428D03*
Y920735D03*
X87099Y947507D03*
Y940814D03*
X82241Y944160D03*
Y937467D03*
X87099Y964239D03*
Y954200D03*
X82241Y960892D03*
Y950853D03*
X87099Y977625D03*
Y970932D03*
X82241Y980971D03*
Y974278D03*
Y967585D03*
X87099Y991011D03*
Y984318D03*
X82241Y987664D03*
X87099Y1031168D03*
Y1024475D03*
Y1017782D03*
X82241Y1027822D03*
Y1017782D03*
X87099Y1044554D03*
Y1037861D03*
X82241Y1047900D03*
Y1041207D03*
Y1034515D03*
X87099Y1057940D03*
Y1051247D03*
X82241Y1061286D03*
Y1054593D03*
X87099Y1078018D03*
Y1071326D03*
Y1064633D03*
X82241Y1074672D03*
Y1067979D03*
X87099Y1094751D03*
Y1088058D03*
X82241Y1091404D03*
Y1084711D03*
X87099Y1108137D03*
Y1101444D03*
X82241Y1111483D03*
Y1104790D03*
Y1098097D03*
X87099Y1124869D03*
Y1114829D03*
X82241Y1128215D03*
Y1121522D03*
X87099Y1144948D03*
Y1138255D03*
Y1131562D03*
X82241Y1141601D03*
Y1134908D03*
X87099Y1161680D03*
Y1151641D03*
X82241Y1158333D03*
Y1148294D03*
X87099Y1175066D03*
Y1168373D03*
X82241Y1171719D03*
Y1165026D03*
X87099Y1188452D03*
Y1181759D03*
X82241Y1185105D03*
Y1178412D03*
X87099Y1205184D03*
Y1198491D03*
X82241Y1208530D03*
Y1201837D03*
Y1195144D03*
X87099Y1225263D03*
Y1218570D03*
Y1211877D03*
X82241Y1221916D03*
Y1215223D03*
X87099Y1241995D03*
Y1235302D03*
X82241Y1238648D03*
Y1231955D03*
X87099Y1248688D03*
X82241Y1245341D03*
X92946Y1273364D03*
X90146D03*
X79246D03*
X103241Y766798D03*
X95799Y770144D03*
X103241Y780184D03*
Y773491D03*
X95799Y783530D03*
Y776837D03*
X103241Y803609D03*
Y796916D03*
Y790223D03*
X95799Y800263D03*
Y793570D03*
X103241Y816995D03*
Y810302D03*
X95799Y820341D03*
Y813648D03*
Y806955D03*
X103241Y833727D03*
Y827034D03*
X95799Y830381D03*
X103241Y847113D03*
Y840420D03*
X95799Y850459D03*
Y843766D03*
Y837074D03*
X103241Y863845D03*
Y853806D03*
X95799Y867192D03*
Y857152D03*
X103241Y883924D03*
Y877231D03*
Y870538D03*
X95799Y880577D03*
Y873885D03*
X103241Y900656D03*
Y890617D03*
X95799Y893963D03*
Y887270D03*
X103241Y914042D03*
Y907349D03*
X95799Y917389D03*
Y910696D03*
Y904003D03*
X103241Y927428D03*
Y920735D03*
X95799Y930774D03*
Y924081D03*
X103241Y944160D03*
Y937467D03*
X95799Y947507D03*
Y940814D03*
X103241Y960892D03*
Y950853D03*
X95799Y964239D03*
Y954200D03*
X103241Y980971D03*
Y974278D03*
Y967585D03*
X95799Y977625D03*
Y970932D03*
X103241Y987664D03*
X95799Y991011D03*
Y984318D03*
X103241Y1027822D03*
Y1017782D03*
X95799Y1031168D03*
Y1024475D03*
Y1017782D03*
X103241Y1047900D03*
Y1041207D03*
Y1034515D03*
X95799Y1044554D03*
Y1037861D03*
X103241Y1061286D03*
Y1054593D03*
X95799Y1057940D03*
Y1051247D03*
X103241Y1074672D03*
Y1067979D03*
X95799Y1078018D03*
Y1071326D03*
Y1064633D03*
X103241Y1091404D03*
Y1084711D03*
X95799Y1094751D03*
Y1088058D03*
X103241Y1111483D03*
Y1104790D03*
Y1098097D03*
X95799Y1108137D03*
Y1101444D03*
X103241Y1128215D03*
Y1121522D03*
X95799Y1124869D03*
Y1114829D03*
X103241Y1141601D03*
Y1134908D03*
X95799Y1144948D03*
Y1138255D03*
Y1131562D03*
X103241Y1158333D03*
Y1148294D03*
X95799Y1161680D03*
Y1151641D03*
X103241Y1171719D03*
Y1165026D03*
X95799Y1175066D03*
Y1168373D03*
X103241Y1185105D03*
Y1178412D03*
X95799Y1188452D03*
Y1181759D03*
X103241Y1208530D03*
Y1201837D03*
Y1195144D03*
X95799Y1205184D03*
Y1198491D03*
X103241Y1221916D03*
Y1215223D03*
X95799Y1225263D03*
Y1218570D03*
Y1211877D03*
X103241Y1238648D03*
Y1231955D03*
X95799Y1241995D03*
Y1235302D03*
X95849Y1257262D03*
X103241Y1245341D03*
X95799Y1248688D03*
X108946Y1273364D03*
X106146D03*
X125499Y770144D03*
X116799D03*
X111941Y766798D03*
X125499Y783530D03*
X116799D03*
X125499Y776837D03*
X116799D03*
X111941Y780184D03*
Y773491D03*
X125499Y800263D03*
X116799D03*
X125499Y793570D03*
X116799D03*
X111941Y803609D03*
Y796916D03*
Y790223D03*
X125499Y820341D03*
X116799D03*
X125499Y813648D03*
X116799D03*
X125499Y806955D03*
X116799D03*
X111941Y816995D03*
Y810302D03*
X125499Y830381D03*
X116799D03*
X111941Y833727D03*
Y827034D03*
X125499Y850459D03*
X116799D03*
X125499Y843766D03*
X116799D03*
X125499Y837074D03*
X116799D03*
X111941Y847113D03*
Y840420D03*
X125499Y867192D03*
X116799D03*
X125499Y857152D03*
X116799D03*
X111941Y863845D03*
Y853806D03*
X125499Y880577D03*
X116799D03*
X125499Y873885D03*
X116799D03*
X111941Y883924D03*
Y877231D03*
Y870538D03*
X125499Y893963D03*
X116799D03*
X125499Y887270D03*
X116799D03*
X111941Y900656D03*
Y890617D03*
X125499Y917389D03*
X116799D03*
X125499Y910696D03*
X116799D03*
X125499Y904003D03*
X116799D03*
X111941Y914042D03*
Y907349D03*
X125499Y930774D03*
X116799D03*
X125499Y924081D03*
X116799D03*
X111941Y927428D03*
Y920735D03*
X125499Y947507D03*
X116799D03*
X125499Y940814D03*
X116799D03*
X111941Y944160D03*
Y937467D03*
X125499Y964239D03*
X116799D03*
X125499Y954200D03*
X116799D03*
X111941Y960892D03*
Y950853D03*
X125499Y977625D03*
X116799D03*
X125499Y970932D03*
X116799D03*
X111941Y980971D03*
Y974278D03*
Y967585D03*
X125499Y991011D03*
X116799D03*
X125499Y984318D03*
X116799D03*
X111941Y987664D03*
X125499Y1031168D03*
X116799D03*
X125499Y1024475D03*
X116799D03*
X125499Y1017782D03*
X116799D03*
X111941Y1027822D03*
Y1017782D03*
X125499Y1044554D03*
X116799D03*
X125499Y1037861D03*
X116799D03*
X111941Y1047900D03*
Y1041207D03*
Y1034515D03*
X125499Y1057940D03*
X116799D03*
X125499Y1051247D03*
X116799D03*
X111941Y1061286D03*
Y1054593D03*
X125499Y1078018D03*
X116799D03*
X125499Y1071326D03*
X116799D03*
X125499Y1064633D03*
X116799D03*
X111941Y1074672D03*
Y1067979D03*
X125499Y1094751D03*
X116799D03*
X125499Y1088058D03*
X116799D03*
X111941Y1091404D03*
Y1084711D03*
X125499Y1108137D03*
X116799D03*
X125499Y1101444D03*
X116799D03*
X111941Y1111483D03*
Y1104790D03*
Y1098097D03*
X125499Y1124869D03*
X116799D03*
X125499Y1114829D03*
X116799D03*
X111941Y1128215D03*
Y1121522D03*
X125499Y1144948D03*
X116799D03*
X125499Y1138255D03*
X116799D03*
X125499Y1131562D03*
X116799D03*
X111941Y1141601D03*
Y1134908D03*
X125499Y1161680D03*
X116799D03*
X125499Y1151641D03*
X116799D03*
X111941Y1158333D03*
Y1148294D03*
X125499Y1175066D03*
X116799D03*
X125499Y1168373D03*
X116799D03*
X111941Y1171719D03*
Y1165026D03*
X125499Y1188452D03*
X116799D03*
X125499Y1181759D03*
X116799D03*
X111941Y1185105D03*
Y1178412D03*
X125499Y1205184D03*
X116799D03*
X125499Y1198491D03*
X116799D03*
X111941Y1208530D03*
Y1201837D03*
Y1195144D03*
X125499Y1225263D03*
X116799D03*
X125499Y1218570D03*
X116799D03*
X125499Y1211877D03*
X116799D03*
X111941Y1221916D03*
Y1215223D03*
X125499Y1241995D03*
X116799D03*
X125499Y1235302D03*
X116799D03*
X111941Y1238648D03*
Y1231955D03*
X125412Y1257102D03*
X125499Y1248688D03*
X116799D03*
X111941Y1245341D03*
X119846Y1273364D03*
X122646D03*
X141641Y766798D03*
X132941D03*
X141641Y773491D03*
X132941D03*
X141641Y780184D03*
X132941D03*
X141641Y803609D03*
X132941D03*
X141641Y790223D03*
X132941D03*
X141641Y796916D03*
X132941D03*
X141641Y816995D03*
X132941D03*
X141641Y810302D03*
X132941D03*
X141641Y833727D03*
X132941D03*
X141641Y827034D03*
X132941D03*
X141641Y840420D03*
X132941D03*
X141641Y847113D03*
X132941D03*
Y863845D03*
X141641D03*
Y853806D03*
X132941D03*
Y883924D03*
X141641D03*
X132941Y870538D03*
X141641D03*
X132941Y877231D03*
X141641D03*
X132941Y900656D03*
X141641D03*
X132941Y890617D03*
X141641D03*
X132941Y907349D03*
X141641D03*
X132941Y914042D03*
X141641D03*
X132941Y920735D03*
X141641D03*
X132941Y927428D03*
X141641D03*
X132941Y937467D03*
X141641D03*
X132941Y944160D03*
X141641D03*
X132941Y960892D03*
X141641D03*
X132941Y950853D03*
X141641D03*
X132941Y980971D03*
X141641D03*
X132941Y974278D03*
X141641D03*
X132941Y967585D03*
X141641D03*
X132941Y987664D03*
X141641D03*
X132941Y1027822D03*
X141641D03*
X132941Y1017782D03*
X141641D03*
X132941Y1047900D03*
X141641D03*
X132941Y1041207D03*
X141641D03*
X132941Y1034515D03*
X141641D03*
Y1061286D03*
X132941D03*
X141641Y1054593D03*
X132941D03*
X141641Y1074672D03*
X132941D03*
X141641Y1067979D03*
X132941D03*
X141641Y1091404D03*
X132941D03*
X141641Y1084711D03*
X132941D03*
X141641Y1111483D03*
X132941D03*
X141641Y1104790D03*
X132941D03*
X141641Y1098097D03*
X132941D03*
X141641Y1128215D03*
X132941D03*
X141641Y1121522D03*
X132941D03*
X141641Y1141601D03*
X132941D03*
X141641Y1134908D03*
X132941D03*
X141641Y1158333D03*
X132941D03*
X141641Y1148294D03*
X132941D03*
X141641Y1171719D03*
X132941D03*
X141641Y1165026D03*
X132941D03*
X141641Y1185105D03*
X132941D03*
X141641Y1178412D03*
X132941D03*
X141641Y1208530D03*
X132941D03*
X141641Y1201837D03*
X132941D03*
X141641Y1195144D03*
X132941D03*
Y1221916D03*
X141641D03*
X132941Y1215223D03*
X141641D03*
X132941Y1238648D03*
X141641D03*
X132941Y1231955D03*
X141641D03*
X132941Y1245341D03*
X141641D03*
X135846Y1273364D03*
X138646D03*
X146499Y770144D03*
X155199D03*
X146499Y783530D03*
X155199D03*
X146499Y776837D03*
X155199D03*
X146499Y800263D03*
X155199D03*
X146499Y793570D03*
X155199D03*
X146499Y820341D03*
X155199D03*
X146499Y813648D03*
X155199D03*
X146499Y806955D03*
X155199D03*
X146499Y830381D03*
X155199D03*
X146499Y850459D03*
X155199D03*
X146499Y843766D03*
X155199D03*
X146499Y837074D03*
X155199D03*
Y867192D03*
X146499D03*
Y857152D03*
X155199D03*
Y880577D03*
X146499D03*
X155199Y873885D03*
X146499D03*
X155199Y893963D03*
X146499D03*
X155199Y887270D03*
X146499D03*
X155199Y917389D03*
X146499D03*
X155199Y910696D03*
X146499D03*
X155199Y904003D03*
X146499D03*
X155199Y930774D03*
X146499D03*
X155199Y924081D03*
X146499D03*
X155199Y947507D03*
X146499D03*
X155199Y940814D03*
X146499D03*
X155199Y964239D03*
X146499D03*
X155199Y954200D03*
X146499D03*
X155199Y977625D03*
X146499D03*
X155199Y970932D03*
X146499D03*
X155199Y991011D03*
X146499D03*
X155199Y984318D03*
X146499D03*
X155199Y1031168D03*
X146499D03*
X155199Y1024475D03*
X146499D03*
X155199Y1017782D03*
X146499D03*
X155199Y1044554D03*
X146499D03*
X155199Y1037861D03*
X146499D03*
X155199Y1057940D03*
X146499D03*
X155199Y1051247D03*
X146499D03*
X155199Y1078018D03*
X146499D03*
X155199Y1071326D03*
X146499D03*
X155199Y1064633D03*
X146499D03*
X155199Y1094751D03*
X146499D03*
X155199Y1088058D03*
X146499D03*
X155199Y1108137D03*
X146499D03*
X155199Y1101444D03*
X146499D03*
X155199Y1124869D03*
X146499D03*
X155199Y1114829D03*
X146499D03*
X155199Y1144948D03*
X146499D03*
X155199Y1138255D03*
X146499D03*
X155199Y1131562D03*
X146499D03*
X155199Y1161680D03*
X146499D03*
X155199Y1151641D03*
X146499D03*
X155199Y1175066D03*
X146499D03*
X155199Y1168373D03*
X146499D03*
X155199Y1188452D03*
X146499D03*
X155199Y1181759D03*
X146499D03*
X155199Y1205184D03*
X146499D03*
X155199Y1198491D03*
X146499D03*
X155199Y1225263D03*
X146499D03*
X155199Y1218570D03*
X146499D03*
X155199Y1211877D03*
X146499D03*
X155199Y1241995D03*
X146499D03*
X155199Y1235302D03*
X146499D03*
X155135Y1257134D03*
X155199Y1248688D03*
X146499D03*
X149546Y1273364D03*
X152346D03*
X176199Y770144D03*
X162641Y766798D03*
X171341D03*
X176199Y783530D03*
Y776837D03*
X162641Y780184D03*
X171341D03*
Y773491D03*
X162641D03*
X176199Y800263D03*
X162641Y803609D03*
X171341D03*
X176199Y793570D03*
X162641Y796916D03*
X171341D03*
X162641Y790223D03*
X171341D03*
X176199Y820341D03*
X162641Y816995D03*
X171341D03*
X176199Y813648D03*
Y806955D03*
X162641Y810302D03*
X171341D03*
X162641Y833727D03*
X171341D03*
X176199Y830381D03*
X162641Y827034D03*
X171341D03*
X176199Y850459D03*
Y843766D03*
Y837074D03*
X162641Y847113D03*
X171341D03*
X162641Y840420D03*
X171341D03*
X176199Y867192D03*
X171341Y863845D03*
X162641D03*
X176199Y857152D03*
X162641Y853806D03*
X171341D03*
Y883924D03*
X162641D03*
X176199Y880577D03*
Y873885D03*
X171341Y877231D03*
X162641D03*
X171341Y870538D03*
X162641D03*
X171341Y900656D03*
X162641D03*
X176199Y893963D03*
Y887270D03*
X171341Y890617D03*
X162641D03*
X176199Y917389D03*
Y910696D03*
Y904003D03*
X171341Y914042D03*
X162641D03*
X171341Y907349D03*
X162641D03*
X176199Y930774D03*
Y924081D03*
X171341Y927428D03*
X162641D03*
X171341Y920735D03*
X162641D03*
X176199Y947507D03*
Y940814D03*
X171341Y944160D03*
X162641D03*
X171341Y937467D03*
X162641D03*
X176199Y964239D03*
Y954200D03*
X171341Y960892D03*
X162641D03*
X171341Y950853D03*
X162641D03*
X171341Y980971D03*
X162641D03*
X176199Y977625D03*
Y970932D03*
X171341Y974278D03*
X162641D03*
X171341Y967585D03*
X162641D03*
X176199Y991011D03*
Y984318D03*
X171341Y987664D03*
X162641D03*
X176199Y1031168D03*
Y1024475D03*
Y1017782D03*
X171341Y1027822D03*
X162641D03*
X171341Y1017782D03*
X162641D03*
X171341Y1047900D03*
X162641D03*
X176199Y1044554D03*
Y1037861D03*
X171341Y1041207D03*
X162641D03*
X171341Y1034515D03*
X162641D03*
X176199Y1057940D03*
Y1051247D03*
X171341Y1061286D03*
X162641D03*
X171341Y1054593D03*
X162641D03*
X176199Y1078018D03*
Y1071326D03*
Y1064633D03*
X171341Y1074672D03*
X162641D03*
X171341Y1067979D03*
X162641D03*
X176199Y1094751D03*
Y1088058D03*
X171341Y1091404D03*
X162641D03*
X171341Y1084711D03*
X162641D03*
X171341Y1111483D03*
X162641D03*
X176199Y1108137D03*
Y1101444D03*
X171341Y1104790D03*
X162641D03*
X171341Y1098097D03*
X162641D03*
X171341Y1128215D03*
X162641D03*
X176199Y1124869D03*
Y1114829D03*
X171341Y1121522D03*
X162641D03*
X176199Y1144948D03*
Y1138255D03*
Y1131562D03*
X171341Y1141601D03*
X162641D03*
X171341Y1134908D03*
X162641D03*
X176199Y1161680D03*
Y1151641D03*
X171341Y1158333D03*
X162641D03*
X171341Y1148294D03*
X162641D03*
X176199Y1175066D03*
Y1168373D03*
X171341Y1171719D03*
X162641D03*
X171341Y1165026D03*
X162641D03*
X176199Y1188452D03*
Y1181759D03*
X171341Y1185105D03*
X162641D03*
X171341Y1178412D03*
X162641D03*
X176199Y1205184D03*
Y1198491D03*
X171341Y1208530D03*
X162641D03*
X171341Y1201837D03*
X162641D03*
X171341Y1195144D03*
X162641D03*
X176199Y1225263D03*
Y1218570D03*
Y1211877D03*
X162641Y1221916D03*
X171341D03*
Y1215223D03*
X162641D03*
X176199Y1241995D03*
Y1235302D03*
X171341Y1238648D03*
X162641D03*
X171341Y1231955D03*
X162641D03*
X176199Y1248688D03*
X171341Y1245341D03*
X162641D03*
X165546Y1273364D03*
X168346D03*
X192341Y766798D03*
X184899Y770144D03*
X192341Y780184D03*
Y773491D03*
X184899Y783530D03*
Y776837D03*
X192341Y803609D03*
Y796916D03*
Y790223D03*
X184899Y800263D03*
Y793570D03*
X192341Y816995D03*
Y810302D03*
X184899Y820341D03*
Y813648D03*
Y806955D03*
X192341Y833727D03*
X191491Y827034D03*
X184899Y830381D03*
X192341Y847113D03*
Y840420D03*
X184899Y850459D03*
Y843766D03*
Y837074D03*
X191491Y863845D03*
X184899Y867192D03*
X192341Y853806D03*
X184899Y857152D03*
X192341Y883924D03*
Y877231D03*
Y870538D03*
X184899Y880577D03*
Y873885D03*
X192341Y900656D03*
Y890617D03*
X184899Y893963D03*
Y887270D03*
X192341Y914042D03*
Y907349D03*
X184899Y917389D03*
Y910696D03*
Y904003D03*
X191491Y927428D03*
X192341Y920735D03*
X184899Y930774D03*
Y924081D03*
X192341Y937467D03*
Y944160D03*
X184899Y947507D03*
Y940814D03*
X192341Y960892D03*
Y950853D03*
X184899Y964239D03*
Y954200D03*
X192341Y974278D03*
Y980971D03*
Y967585D03*
X184899Y977625D03*
Y970932D03*
X192341Y987664D03*
X184899Y991011D03*
Y984318D03*
X192341Y1027822D03*
Y1017782D03*
X184899Y1031168D03*
Y1024475D03*
Y1017782D03*
X192341Y1047900D03*
Y1041207D03*
Y1034515D03*
X184899Y1044554D03*
Y1037861D03*
X192341Y1054593D03*
Y1061286D03*
X184899Y1057940D03*
Y1051247D03*
X192341Y1074672D03*
Y1067979D03*
X184899Y1078018D03*
Y1071326D03*
Y1064633D03*
X192341Y1091404D03*
X191491Y1084711D03*
X184899Y1094751D03*
Y1088058D03*
X192341Y1111483D03*
Y1104790D03*
Y1098097D03*
X184899Y1108137D03*
Y1101444D03*
X192341Y1128215D03*
Y1121522D03*
X184899Y1124869D03*
Y1114829D03*
X192341Y1141601D03*
Y1134908D03*
X184899Y1144948D03*
Y1138255D03*
Y1131562D03*
X191491Y1158333D03*
X192341Y1148294D03*
X184899Y1161680D03*
Y1151641D03*
X192341Y1171719D03*
Y1165026D03*
X184899Y1175066D03*
Y1168373D03*
X192341Y1185105D03*
Y1178412D03*
X184899Y1188452D03*
Y1181759D03*
X192341Y1208530D03*
Y1201837D03*
Y1195144D03*
X184899Y1205184D03*
Y1198491D03*
X192341Y1221916D03*
Y1215223D03*
X184899Y1225263D03*
Y1218570D03*
Y1211877D03*
X192341Y1238648D03*
X191491Y1231955D03*
X184899Y1241995D03*
Y1235302D03*
X184923Y1258871D03*
X192341Y1245341D03*
X184899Y1248688D03*
X192594Y1271262D03*
X192605Y1268774D03*
X182046Y1273364D03*
X179246D03*
X186697Y1578182D03*
Y1590094D03*
X191997Y1602380D03*
Y1614292D03*
X205899Y770144D03*
X201041Y766798D03*
X205899Y783530D03*
Y776837D03*
X201041Y780184D03*
Y773491D03*
X205899Y800263D03*
Y793570D03*
X201041Y803609D03*
Y796916D03*
Y790223D03*
X205899Y813648D03*
Y806955D03*
X205049Y820341D03*
X201041Y816995D03*
Y810302D03*
X205049Y830381D03*
X201041Y833727D03*
Y827034D03*
X205899Y850459D03*
Y837074D03*
Y843766D03*
X201041Y847113D03*
Y840420D03*
X205049Y867192D03*
X201041Y863845D03*
X205049Y857152D03*
X201041Y853806D03*
X205899Y873885D03*
Y880577D03*
X201041Y883924D03*
Y877231D03*
Y870538D03*
X205899Y893963D03*
Y887270D03*
X201041Y900656D03*
Y890617D03*
X205899Y917389D03*
Y910696D03*
Y904003D03*
X201041Y914042D03*
Y907349D03*
X205049Y930774D03*
Y924081D03*
X201041Y927428D03*
Y920735D03*
X205899Y940814D03*
Y947507D03*
X201041Y937467D03*
Y944160D03*
X205899Y964239D03*
Y954200D03*
X201041Y960892D03*
Y950853D03*
X205899Y970932D03*
Y977625D03*
X201041Y974278D03*
Y980971D03*
Y967585D03*
X205899Y991011D03*
Y984318D03*
X201041Y987664D03*
X205899Y1031168D03*
Y1017782D03*
Y1024475D03*
X201041Y1027822D03*
Y1017782D03*
X205899Y1044554D03*
Y1037861D03*
X201041Y1047900D03*
Y1041207D03*
Y1034515D03*
X205899Y1057940D03*
Y1051247D03*
X201041Y1054593D03*
Y1061286D03*
X205049Y1078018D03*
X205899Y1071326D03*
Y1064633D03*
X201041Y1074672D03*
Y1067979D03*
X205899Y1094751D03*
X205049Y1088058D03*
X201041Y1091404D03*
Y1084711D03*
X205899Y1101444D03*
Y1108137D03*
X201041Y1111483D03*
Y1104790D03*
Y1098097D03*
X205899Y1114829D03*
Y1124869D03*
X201041Y1128215D03*
Y1121522D03*
X205899Y1144948D03*
Y1138255D03*
Y1131562D03*
X201041Y1141601D03*
Y1134908D03*
X205049Y1161680D03*
Y1151641D03*
X201041Y1158333D03*
Y1148294D03*
X205899Y1168373D03*
Y1175066D03*
X201041Y1171719D03*
Y1165026D03*
X205899Y1188452D03*
Y1181759D03*
X201041Y1185105D03*
Y1178412D03*
X205899Y1205184D03*
Y1198491D03*
X201041Y1208530D03*
Y1201837D03*
Y1195144D03*
X205049Y1225263D03*
X205899Y1211877D03*
Y1218570D03*
X201041Y1221916D03*
Y1215223D03*
X205899Y1241995D03*
X205049Y1235302D03*
X201041Y1238648D03*
Y1231955D03*
X205899Y1248688D03*
X201041Y1245341D03*
X206268Y1271348D03*
X206337Y1268720D03*
X194497Y1578182D03*
X206557D03*
X198757D03*
X194497Y1590094D03*
X206557D03*
X198757D03*
X199797Y1614292D03*
Y1602380D03*
X204057Y1614292D03*
Y1602380D03*
X222041Y766798D03*
X214599Y770144D03*
X222041Y780184D03*
Y773491D03*
X214599Y783530D03*
Y776837D03*
X222041Y803609D03*
Y796916D03*
Y790223D03*
X214599Y800263D03*
Y793570D03*
X222041Y810302D03*
X221191Y816995D03*
X214599Y813648D03*
Y806955D03*
X215449Y820341D03*
X222041Y833727D03*
X221191Y827034D03*
X215449Y830381D03*
X222041Y847113D03*
Y840420D03*
X214599Y850459D03*
Y837074D03*
Y843766D03*
X221191Y863845D03*
X215449Y867192D03*
X222041Y853806D03*
X215449Y857152D03*
X222041Y877231D03*
X221191Y870538D03*
X222041Y883924D03*
X214599Y873885D03*
Y880577D03*
X222041Y900656D03*
Y890617D03*
X214599Y893963D03*
Y887270D03*
X222041Y914042D03*
Y907349D03*
X214599Y917389D03*
Y910696D03*
Y904003D03*
X221241Y927428D03*
X222041Y920735D03*
X215449Y930774D03*
Y924081D03*
X222041Y944160D03*
X221191Y937467D03*
X214599Y940814D03*
Y947507D03*
X222041Y960892D03*
Y950853D03*
X214599Y964239D03*
Y954200D03*
X222041Y980971D03*
Y974278D03*
Y967585D03*
X214599Y970932D03*
Y977625D03*
Y991011D03*
Y984318D03*
X222041Y987664D03*
Y1027822D03*
Y1017782D03*
X214599Y1031168D03*
Y1017782D03*
Y1024475D03*
X222041Y1047900D03*
Y1041207D03*
Y1034515D03*
X214599Y1044554D03*
Y1037861D03*
X222041Y1054593D03*
Y1061286D03*
X214599Y1057940D03*
Y1051247D03*
X222041Y1067979D03*
X221191Y1074672D03*
X215449Y1078018D03*
X214599Y1071326D03*
Y1064633D03*
X222041Y1091404D03*
X221191Y1084711D03*
X214599Y1094751D03*
X215449Y1088058D03*
X222041Y1111483D03*
Y1098097D03*
Y1104790D03*
X214599Y1101444D03*
Y1108137D03*
X222041Y1128215D03*
Y1121522D03*
X214599Y1114829D03*
Y1124869D03*
X222041Y1141601D03*
X221191Y1134908D03*
X214599Y1144948D03*
Y1138255D03*
Y1131562D03*
X222041Y1158333D03*
X221191Y1148294D03*
X215449Y1161680D03*
Y1151641D03*
X222041Y1165026D03*
Y1171719D03*
X214599Y1168373D03*
Y1175066D03*
X222041Y1185105D03*
Y1178412D03*
X214599Y1188452D03*
Y1181759D03*
X222041Y1208530D03*
Y1201837D03*
Y1195144D03*
X214599Y1205184D03*
Y1198491D03*
X222041Y1221916D03*
Y1215223D03*
X215449Y1225263D03*
X214599Y1211877D03*
Y1218570D03*
X221191Y1231955D03*
Y1238648D03*
X214599Y1241995D03*
X215449Y1235302D03*
X222041Y1245341D03*
X214824Y1258711D03*
X214599Y1248688D03*
X224987Y1273535D03*
X218617Y1578182D03*
X210817D03*
X222877D03*
X218617Y1590094D03*
X210817D03*
X222877D03*
X211857Y1614292D03*
Y1602380D03*
X223917Y1614292D03*
X216117D03*
X223917Y1602380D03*
X216117D03*
X235599Y770144D03*
X230741Y766798D03*
X235599Y783530D03*
Y776837D03*
X230741Y780184D03*
Y773491D03*
X235599Y800263D03*
Y793570D03*
X230741Y803609D03*
Y796916D03*
Y790223D03*
X234749Y820341D03*
Y813648D03*
X235599Y806955D03*
X230741Y810302D03*
X231006Y817554D03*
X235599Y830381D03*
X230741Y833727D03*
X231591Y827034D03*
X235599Y850459D03*
Y837074D03*
Y843766D03*
X230741Y847113D03*
Y840420D03*
X234749Y867492D03*
X231591Y863845D03*
X234749Y857152D03*
X230741Y853806D03*
X235599Y874185D03*
Y880577D03*
X230741Y877231D03*
X231059Y871084D03*
X230741Y883924D03*
X235599Y893963D03*
Y887270D03*
X230741Y900656D03*
Y890617D03*
X235599Y917389D03*
Y910696D03*
Y904003D03*
X230741Y914042D03*
Y907349D03*
X235599Y930774D03*
Y924081D03*
X231541Y927428D03*
X230741Y920735D03*
X235599Y947507D03*
X234859Y940814D03*
X230741Y944660D03*
X231591Y937467D03*
X235599Y964239D03*
Y954200D03*
X230741Y960892D03*
Y950853D03*
X235599Y977625D03*
Y970932D03*
X230741Y980971D03*
Y974278D03*
Y967585D03*
X235599Y991011D03*
X230741Y987664D03*
X235599Y984318D03*
Y1031168D03*
X230741Y1027822D03*
Y1017782D03*
X235599D03*
Y1024475D03*
Y1044554D03*
Y1037861D03*
X230741Y1047900D03*
Y1041207D03*
Y1034515D03*
X235599Y1051247D03*
Y1057940D03*
X230741Y1054593D03*
Y1061286D03*
X234749Y1078018D03*
X235599Y1071326D03*
Y1064633D03*
X230741Y1067979D03*
X231591Y1074672D03*
X235599Y1094751D03*
X234749Y1088058D03*
X230741Y1091404D03*
Y1084711D03*
X235599Y1108137D03*
Y1101444D03*
X230741Y1111483D03*
Y1098097D03*
Y1104790D03*
X234749Y1124869D03*
X235599Y1114829D03*
X230741Y1128215D03*
Y1121522D03*
X235599Y1144948D03*
Y1138255D03*
X234749Y1131562D03*
X230741Y1141601D03*
X231591Y1134908D03*
X235599Y1151641D03*
Y1161680D03*
X230741Y1158333D03*
X231591Y1148294D03*
X235599Y1175066D03*
Y1168373D03*
X230741Y1165026D03*
Y1171719D03*
X235599Y1188452D03*
Y1181759D03*
X230741Y1185105D03*
Y1178412D03*
X235599Y1205184D03*
Y1198491D03*
X230741Y1208530D03*
Y1201837D03*
Y1195144D03*
X234749Y1225263D03*
X235599Y1218570D03*
Y1211877D03*
X230741Y1221916D03*
Y1215223D03*
X235599Y1241995D03*
X235186Y1234977D03*
X231591Y1231955D03*
Y1238648D03*
X235599Y1248688D03*
X230741Y1245341D03*
X227746Y1273364D03*
X240966Y1273143D03*
X238971Y1274353D03*
X230677Y1578182D03*
X234937D03*
X230677Y1590094D03*
X234937D03*
X228177Y1614292D03*
X235977D03*
X228177Y1602380D03*
X235977D03*
X240237D03*
Y1614292D03*
X233268Y1679920D03*
Y1675383D03*
X241142Y1679320D03*
X233268Y1698627D03*
Y1694093D03*
Y1689556D03*
Y1684454D03*
X241142Y1683857D03*
Y1688391D03*
Y1693493D03*
Y1698030D03*
X233268Y1712800D03*
Y1708266D03*
Y1703729D03*
X241142Y1702564D03*
Y1707666D03*
Y1712203D03*
X233268Y1717903D03*
Y1722440D03*
Y1726974D03*
X241142Y1716737D03*
Y1730911D03*
Y1726377D03*
Y1721840D03*
X251741Y766798D03*
X244299Y770144D03*
X251741Y780184D03*
Y773491D03*
X244299Y783530D03*
Y776837D03*
X251741Y803609D03*
Y796916D03*
Y790223D03*
X244299Y800263D03*
Y793570D03*
X250891Y816995D03*
X251741Y810302D03*
X245149Y820341D03*
Y813648D03*
X244299Y806955D03*
X251741Y833727D03*
X250891Y827034D03*
X244299Y830381D03*
X251741Y847113D03*
Y840420D03*
X244299Y850459D03*
Y837074D03*
Y843766D03*
X250891Y863845D03*
Y853806D03*
X245149Y867192D03*
Y857152D03*
X251741Y870538D03*
Y883924D03*
Y877231D03*
X244299Y873885D03*
Y880577D03*
X250891Y900656D03*
X251741Y890617D03*
X244299Y893963D03*
Y887270D03*
X251741Y914042D03*
Y907349D03*
X244299Y917389D03*
Y910696D03*
Y904003D03*
X250891Y927428D03*
X251741Y920735D03*
X245149Y930774D03*
X244299Y924081D03*
X251741Y944160D03*
X250891Y937467D03*
X244299Y947507D03*
X245149Y940814D03*
X251741Y960892D03*
Y950853D03*
X244299Y964239D03*
Y954200D03*
X251741Y980971D03*
Y974278D03*
Y967585D03*
X244299Y977625D03*
Y970932D03*
X251741Y987664D03*
X244299Y991011D03*
Y984318D03*
Y1031168D03*
X251741Y1027822D03*
Y1017782D03*
X244299D03*
Y1024475D03*
X251741Y1047900D03*
Y1041207D03*
Y1034515D03*
X244299Y1044554D03*
Y1037861D03*
X251741Y1061286D03*
Y1054593D03*
X244299Y1051247D03*
Y1057940D03*
X250891Y1074672D03*
Y1067979D03*
X245149Y1078018D03*
X244299Y1071326D03*
Y1064633D03*
X251741Y1091404D03*
Y1084711D03*
X244299Y1094751D03*
X245149Y1088058D03*
X251741Y1104790D03*
X250891Y1111483D03*
X251741Y1098097D03*
X244299Y1108137D03*
Y1101444D03*
X251741Y1128215D03*
X250891Y1121522D03*
X245149Y1124869D03*
X244299Y1114829D03*
X251741Y1134908D03*
Y1141601D03*
X244299Y1144948D03*
Y1138255D03*
X245149Y1131562D03*
X251741Y1158333D03*
Y1148294D03*
X244299Y1151641D03*
Y1161680D03*
X251741Y1171719D03*
Y1165026D03*
X244299Y1175066D03*
Y1168373D03*
X251741Y1185105D03*
Y1178412D03*
X244299Y1188452D03*
Y1181759D03*
X251741Y1208530D03*
Y1201837D03*
X250891Y1195144D03*
X244299Y1205184D03*
Y1198491D03*
X250891Y1221916D03*
X251741Y1215223D03*
X245149Y1225263D03*
X244299Y1218570D03*
Y1211877D03*
X250891Y1231955D03*
X244299Y1241995D03*
X245149Y1235302D03*
X251741Y1238648D03*
X244299Y1248688D03*
X251741Y1245341D03*
X244789Y1260093D03*
X254897Y1274040D03*
X257197Y1273640D03*
X242737Y1578182D03*
X246997D03*
X254797D03*
X242737Y1590094D03*
X246997D03*
X254797D03*
X248037Y1602380D03*
Y1614292D03*
X252297Y1602380D03*
Y1614292D03*
X249016Y1675383D03*
Y1679920D03*
X256890Y1679320D03*
X249016Y1684454D03*
Y1689556D03*
Y1694093D03*
Y1698627D03*
X256890Y1683857D03*
Y1688391D03*
Y1693493D03*
Y1698030D03*
X249016Y1703729D03*
Y1708266D03*
Y1712800D03*
X256890Y1702564D03*
Y1707666D03*
Y1712203D03*
X249016Y1726974D03*
Y1722440D03*
Y1717903D03*
X256890Y1716737D03*
Y1730911D03*
Y1726377D03*
Y1721840D03*
X260441Y766798D03*
Y780184D03*
Y773491D03*
Y803609D03*
Y796916D03*
Y790223D03*
X261291Y816995D03*
X260441Y810302D03*
Y833727D03*
X261291Y827034D03*
X260441Y847113D03*
Y840420D03*
X261291Y863845D03*
Y853806D03*
X260441Y870538D03*
Y883924D03*
Y877231D03*
Y900656D03*
Y890617D03*
Y914042D03*
Y907349D03*
X261291Y927428D03*
X260441Y920735D03*
Y944160D03*
X261291Y937467D03*
X260441Y960892D03*
Y950853D03*
Y980971D03*
Y974278D03*
Y967585D03*
Y987664D03*
Y1027822D03*
Y1017782D03*
Y1047900D03*
Y1041207D03*
Y1034515D03*
Y1061286D03*
Y1054593D03*
X261291Y1074672D03*
Y1067979D03*
X260441Y1091404D03*
Y1084711D03*
Y1104790D03*
X261291Y1111483D03*
X260441Y1098097D03*
Y1128215D03*
X261291Y1121522D03*
X260441Y1134908D03*
Y1141601D03*
Y1158333D03*
Y1148294D03*
Y1171719D03*
Y1165026D03*
Y1185105D03*
Y1178412D03*
Y1208530D03*
Y1201837D03*
Y1195144D03*
X261291Y1221916D03*
X260441Y1215223D03*
X261291Y1231955D03*
X260441Y1238648D03*
Y1245341D03*
X266857Y1578182D03*
X259057D03*
X271117D03*
X266857Y1590094D03*
X259057D03*
X271117D03*
X260097Y1602380D03*
Y1614292D03*
X272157Y1602380D03*
Y1614292D03*
X264357D03*
Y1602380D03*
X264764Y1675383D03*
Y1679920D03*
X272638Y1679320D03*
X264764Y1684454D03*
Y1689556D03*
Y1694093D03*
Y1698627D03*
X272638Y1683857D03*
Y1688391D03*
Y1693493D03*
Y1698030D03*
X264764Y1703729D03*
Y1708266D03*
Y1712800D03*
X272638Y1702564D03*
Y1707666D03*
Y1712203D03*
X264764Y1726974D03*
Y1722440D03*
Y1717903D03*
X272638Y1716737D03*
Y1730911D03*
Y1726377D03*
Y1721840D03*
X278917Y1578182D03*
X283177D03*
X278917Y1590094D03*
X283177D03*
X284217Y1602380D03*
Y1614292D03*
X276417D03*
Y1602380D03*
X288477Y1614292D03*
Y1602380D03*
X280512Y1675383D03*
Y1679920D03*
Y1684454D03*
Y1689556D03*
Y1694093D03*
Y1698627D03*
Y1703729D03*
Y1708266D03*
Y1712800D03*
Y1726974D03*
Y1722440D03*
Y1717903D03*
X290977Y1578182D03*
X295237D03*
X303037D03*
X290977Y1590094D03*
X295237D03*
X303037D03*
X296277Y1614292D03*
Y1602380D03*
X300537D03*
Y1614292D03*
X300197Y1679920D03*
Y1675383D03*
Y1698627D03*
Y1694093D03*
Y1689556D03*
Y1684454D03*
Y1712800D03*
Y1708266D03*
Y1703729D03*
Y1717903D03*
Y1722440D03*
Y1726974D03*
X315097Y1578182D03*
X307297D03*
X319357D03*
X315097Y1590094D03*
X307297D03*
X319357D03*
X308337Y1602380D03*
Y1614292D03*
X320397D03*
X312597D03*
X320397Y1602380D03*
X312597D03*
X308071Y1679320D03*
X315945Y1679920D03*
Y1675383D03*
X308071Y1683857D03*
Y1698030D03*
Y1693493D03*
Y1688391D03*
X315945Y1698627D03*
Y1694093D03*
Y1689556D03*
Y1684454D03*
X308071Y1702564D03*
Y1712203D03*
Y1707666D03*
X315945Y1712800D03*
Y1708266D03*
Y1703729D03*
X308071Y1716737D03*
Y1721840D03*
Y1726377D03*
Y1730911D03*
X315945Y1717903D03*
Y1722440D03*
Y1726974D03*
X327157Y1578182D03*
X331417D03*
X327157Y1590094D03*
X331417D03*
X324657Y1602380D03*
X332457D03*
X324657Y1614292D03*
X332457D03*
X336717Y1602380D03*
Y1614292D03*
X323819Y1679320D03*
X331693Y1679920D03*
Y1675383D03*
X323819Y1683857D03*
Y1698030D03*
Y1693493D03*
Y1688391D03*
X331693Y1698627D03*
Y1694093D03*
Y1689556D03*
Y1684454D03*
X323819Y1702564D03*
Y1712203D03*
Y1707666D03*
X331693Y1712800D03*
Y1708266D03*
Y1703729D03*
X323819Y1716737D03*
Y1721840D03*
Y1726377D03*
Y1730911D03*
X331693Y1717903D03*
Y1722440D03*
Y1726974D03*
X352579Y854584D03*
X347029Y870606D03*
Y889832D03*
X343707Y1091513D03*
X339217Y1578182D03*
X343477D03*
X351277D03*
X339217Y1590094D03*
X343477D03*
X351277D03*
X344517Y1602380D03*
Y1614292D03*
X348777Y1602380D03*
Y1614292D03*
X339567Y1679320D03*
X347441Y1679920D03*
Y1675383D03*
X355315Y1679320D03*
X339567Y1683857D03*
Y1698030D03*
Y1693493D03*
Y1688391D03*
X347441Y1698627D03*
Y1694093D03*
Y1689556D03*
Y1684454D03*
X355315Y1683857D03*
Y1698030D03*
Y1693493D03*
Y1688391D03*
X339567Y1702564D03*
Y1712203D03*
Y1707666D03*
X347441Y1712800D03*
Y1708266D03*
Y1703729D03*
X355315Y1702564D03*
Y1712203D03*
Y1707666D03*
X339567Y1716737D03*
Y1721840D03*
Y1726377D03*
Y1730911D03*
X347441Y1717903D03*
Y1722440D03*
Y1726974D03*
X355315Y1716737D03*
Y1721840D03*
Y1726377D03*
Y1730911D03*
X359979Y841467D03*
X367379D03*
X365529Y851380D03*
X369229D03*
X359979Y880219D03*
Y899445D03*
X371078D03*
X359979Y918670D03*
X365529Y941100D03*
X359979Y937896D03*
X371078D03*
X369662Y1006093D03*
X365962Y1076587D03*
X363337Y1578088D03*
X355537Y1578182D03*
X367597D03*
X363337Y1590094D03*
X355537D03*
X367597D03*
X356577Y1602380D03*
Y1614292D03*
X368637D03*
X360837D03*
X368637Y1602286D03*
X360837Y1602380D03*
X382179Y841467D03*
X374779D03*
X380329Y851380D03*
X376629D03*
X372929D03*
X384029D03*
X387729D03*
X378478Y931488D03*
X378911Y1060565D03*
X375397Y1578182D03*
Y1590094D03*
X372897Y1602380D03*
X380697D03*
X372897Y1614292D03*
X380697D03*
X389579Y841467D03*
X396978Y899445D03*
Y937896D03*
X415185Y985580D03*
X417575D03*
X415185Y1014540D03*
X417575D03*
X435829Y851380D03*
Y864197D03*
Y877014D03*
Y889832D03*
Y902649D03*
X428429Y921875D03*
X430279Y937897D03*
X433979D03*
X433980Y944305D03*
Y957123D03*
Y950714D03*
Y963531D03*
Y976348D03*
Y969940D03*
Y982757D03*
X434411Y1009298D03*
X434412Y1002889D03*
X434411Y1028524D03*
Y1022115D03*
X434412Y1015706D03*
Y1034932D03*
X434411Y1092608D03*
X450629Y851380D03*
Y877014D03*
X437678Y912262D03*
X441379Y937897D03*
X445079D03*
X437679D03*
X446929Y941101D03*
X446930Y947510D03*
Y960327D03*
Y953918D03*
Y966736D03*
Y979553D03*
Y973144D03*
X447362Y1006094D03*
Y999685D03*
Y1012502D03*
Y1025319D03*
Y1018911D03*
Y1031728D03*
X456178Y912262D03*
X461729Y921875D03*
X462261Y942152D03*
X464561D03*
X466861D03*
X454423Y949139D03*
X454393Y963829D03*
Y966129D03*
X463874Y956540D03*
X466272D03*
X454423Y951439D03*
X466272Y971100D03*
X463874Y971140D03*
X454263Y981209D03*
Y978909D03*
X454463Y995299D03*
Y992999D03*
X466272Y985580D03*
X463874D03*
X466272Y1014540D03*
X463874D03*
X454443Y1009409D03*
Y1007109D03*
X466272Y1000060D03*
X463874D03*
X468895Y1014550D03*
X465862Y1057361D03*
X458462Y1063770D03*
X465862D03*
X456611Y1073383D03*
X454762Y1070178D03*
X467711Y1073383D03*
Y1066974D03*
X474678Y899445D03*
Y912262D03*
X480229Y921875D03*
X471204Y1014540D03*
X475111Y1060565D03*
X484361Y1057361D03*
X475111Y1066974D03*
X473262Y1070178D03*
X478811Y1073383D03*
X484361Y1076587D03*
X482512Y1066974D03*
X478812Y1079791D03*
X475111D03*
X482911Y1578182D03*
X478651D03*
X470851D03*
X482911Y1590094D03*
X478651D03*
X470851D03*
X483951Y1614292D03*
Y1602380D03*
X476151D03*
Y1614292D03*
X489478Y912262D03*
X495462Y1057361D03*
X499162Y1063770D03*
X495462Y1076587D03*
X493612Y1073383D03*
X486211D03*
X497311Y1066974D03*
X495462Y1108630D03*
X493611Y1111834D03*
X494971Y1578182D03*
X490711D03*
X494971Y1590094D03*
X490711D03*
X500271Y1614292D03*
Y1602380D03*
X488211Y1614292D03*
Y1602380D03*
X496011D03*
Y1614292D03*
X497441Y1675383D03*
Y1679920D03*
Y1684454D03*
Y1689556D03*
Y1694093D03*
Y1698627D03*
Y1703729D03*
Y1708266D03*
Y1712800D03*
Y1726974D03*
Y1722440D03*
Y1717903D03*
X507978Y937896D03*
X509829Y947509D03*
X510262Y1057361D03*
X506562Y1063770D03*
X510262Y1076587D03*
X512111Y1073383D03*
X508411Y1066974D03*
X515811D03*
X508411Y1079791D03*
X515811Y1086200D03*
X507031Y1578182D03*
X514831D03*
X502771D03*
X507031Y1590094D03*
X514831D03*
X502771D03*
X512331Y1614292D03*
Y1602380D03*
X508071Y1614292D03*
Y1602380D03*
X513189Y1675383D03*
Y1679920D03*
X505315Y1679320D03*
X513189Y1684454D03*
Y1689556D03*
Y1694093D03*
Y1698627D03*
X505315Y1688391D03*
Y1693493D03*
Y1698030D03*
Y1683857D03*
X513189Y1703729D03*
Y1708266D03*
Y1712800D03*
X505315Y1707666D03*
Y1712203D03*
Y1702564D03*
X513189Y1726974D03*
Y1722440D03*
Y1717903D03*
X505315Y1730911D03*
Y1726377D03*
Y1721840D03*
Y1716737D03*
X521362Y1057361D03*
X525061Y1063770D03*
X532462D03*
X521362Y1076587D03*
X519512Y1073383D03*
X523211Y1066974D03*
X534311D03*
X531151Y1578182D03*
X519091D03*
X526891D03*
X531151Y1590094D03*
X519091D03*
X526891D03*
X532191Y1614292D03*
Y1602380D03*
X524391Y1614292D03*
Y1602380D03*
X520131D03*
Y1614292D03*
X528937Y1675383D03*
Y1679920D03*
X521063Y1679320D03*
X528937Y1684454D03*
Y1689556D03*
Y1694093D03*
Y1698627D03*
X521063Y1688391D03*
Y1693493D03*
Y1698030D03*
Y1683857D03*
X528937Y1703729D03*
Y1708266D03*
Y1712800D03*
X521063Y1707666D03*
Y1712203D03*
Y1702564D03*
X528937Y1726974D03*
Y1722440D03*
Y1717903D03*
X521063Y1730911D03*
Y1726377D03*
Y1721840D03*
Y1716737D03*
X543129Y928283D03*
X539429D03*
X537578Y925079D03*
X535729Y928283D03*
X548678Y925079D03*
X537578Y944304D03*
X548678D03*
X536161Y1057361D03*
X549422Y1064850D03*
X541711Y1073383D03*
X545411Y1066974D03*
X536161Y1076587D03*
X536162Y1070178D03*
X538011Y1073383D03*
X547262Y1070178D03*
X543211Y1578182D03*
X538951D03*
X543211Y1590094D03*
X538951D03*
X548511Y1614292D03*
Y1602380D03*
X536451D03*
Y1614292D03*
X544251Y1602380D03*
Y1614292D03*
X544685Y1675383D03*
Y1679920D03*
X536811Y1679320D03*
X544685Y1684454D03*
Y1689556D03*
Y1694093D03*
Y1698627D03*
X536811Y1688391D03*
Y1693493D03*
Y1698030D03*
Y1683857D03*
X544685Y1703729D03*
Y1708266D03*
Y1712800D03*
X536811Y1707666D03*
Y1712203D03*
Y1702564D03*
X544685Y1726974D03*
Y1722440D03*
Y1717903D03*
X536811Y1730911D03*
Y1726377D03*
Y1721840D03*
Y1716737D03*
X555271Y1578182D03*
X563071D03*
X551011D03*
X555271Y1590094D03*
X563071D03*
X551011D03*
X560571Y1602380D03*
X556311Y1614292D03*
Y1602380D03*
X552559Y1679320D03*
X564370Y1675383D03*
Y1679920D03*
X552559Y1688391D03*
Y1693493D03*
Y1698030D03*
Y1683857D03*
X564370Y1684454D03*
Y1689556D03*
Y1694093D03*
Y1698627D03*
X552559Y1707666D03*
Y1712203D03*
Y1702564D03*
X564370Y1703729D03*
Y1708266D03*
Y1712800D03*
X552559Y1730911D03*
Y1726377D03*
Y1721840D03*
Y1716737D03*
X564370Y1726974D03*
Y1722440D03*
Y1717903D03*
X579391Y1578182D03*
X567331D03*
X575131D03*
X579391Y1590094D03*
X567331D03*
X575131D03*
X580431Y1614292D03*
X572631D03*
Y1602380D03*
X568371D03*
Y1614292D03*
X580118Y1675383D03*
Y1679920D03*
X572244Y1679320D03*
X580118Y1684454D03*
Y1689556D03*
Y1694093D03*
Y1698627D03*
X572244Y1688391D03*
Y1693493D03*
Y1698030D03*
Y1683857D03*
X580118Y1703729D03*
Y1708266D03*
Y1712800D03*
X572244Y1707666D03*
Y1712203D03*
Y1702564D03*
X580118Y1726974D03*
Y1722440D03*
Y1717903D03*
X572244Y1730911D03*
Y1726377D03*
Y1721840D03*
Y1716737D03*
X599251Y1578182D03*
X591451D03*
X587191D03*
X599251Y1590094D03*
X591451D03*
X587191D03*
X596751Y1614292D03*
Y1602380D03*
X584691D03*
Y1614292D03*
X592491Y1602380D03*
Y1614292D03*
X595866Y1675383D03*
Y1679920D03*
X587992Y1679320D03*
X595866Y1684454D03*
Y1689556D03*
Y1694093D03*
Y1698627D03*
X587992Y1688391D03*
Y1693493D03*
Y1698030D03*
Y1683857D03*
X595866Y1703729D03*
Y1708266D03*
Y1712800D03*
X587992Y1707666D03*
Y1712203D03*
Y1702564D03*
X595866Y1726974D03*
Y1722440D03*
Y1717903D03*
X587992Y1730911D03*
Y1726377D03*
Y1721840D03*
Y1716737D03*
X615571Y1578182D03*
X603511D03*
X611311D03*
X615571Y1590094D03*
X603511D03*
X611311D03*
X608811Y1602380D03*
Y1614292D03*
X604551Y1602380D03*
Y1614292D03*
X611614Y1675383D03*
Y1679920D03*
X603740Y1679320D03*
X611614Y1684454D03*
Y1689556D03*
Y1694093D03*
Y1698627D03*
X603740Y1688391D03*
Y1693493D03*
Y1698030D03*
Y1683857D03*
X611614Y1703729D03*
Y1708266D03*
Y1712800D03*
X603740Y1707666D03*
Y1712203D03*
Y1702564D03*
X611614Y1726974D03*
Y1722440D03*
Y1717903D03*
X603740Y1730911D03*
Y1726377D03*
Y1721840D03*
Y1716737D03*
X629599Y770144D03*
X620899D03*
X629599Y783530D03*
X620899D03*
X629599Y776837D03*
X620899D03*
X620846Y800263D03*
X629599D03*
Y793570D03*
X620899D03*
Y820341D03*
X629599D03*
X620076Y813648D03*
X630593D03*
X619632Y806955D03*
X630792D03*
X620899Y830381D03*
X629599D03*
X620005Y850459D03*
X630754D03*
X620899Y843766D03*
X629599D03*
Y837074D03*
X620899D03*
Y867192D03*
X629599D03*
X620058Y857152D03*
X630481D03*
X620899Y880577D03*
X629599D03*
X620899Y873885D03*
X629599D03*
X630756Y893963D03*
X620899D03*
X629599Y887270D03*
X620899D03*
Y910696D03*
X629599D03*
Y917389D03*
X620899D03*
X629599Y904003D03*
X620899D03*
X630399Y930697D03*
X619905Y930774D03*
X620899Y924081D03*
X629599D03*
Y947507D03*
X620899D03*
X619964Y940814D03*
X630777D03*
X629599Y964239D03*
X620899D03*
X629599Y954200D03*
X620899D03*
Y977625D03*
X629599D03*
Y970932D03*
X620899D03*
Y991011D03*
X629599D03*
Y984318D03*
X620899D03*
Y1031168D03*
X629599D03*
X620899Y1017782D03*
X629599D03*
X620899Y1024475D03*
X629599D03*
X620899Y1044554D03*
X629599D03*
X620899Y1037861D03*
X629599D03*
X620899Y1057940D03*
X629599D03*
Y1051247D03*
X620899D03*
Y1078018D03*
X629599D03*
X630399Y1071326D03*
X619999D03*
X620899Y1064633D03*
X629599D03*
X620899Y1088058D03*
X629599D03*
Y1094751D03*
X620899D03*
Y1108137D03*
X629599D03*
Y1101444D03*
X620899D03*
X630363Y1124674D03*
X620369Y1124969D03*
X630399Y1114829D03*
X620099D03*
X620899Y1131562D03*
X629599D03*
Y1144948D03*
X620899D03*
X629599Y1138255D03*
X620899D03*
X620511Y1161680D03*
X629833Y1161581D03*
X629599Y1151641D03*
X620899D03*
X629599Y1175066D03*
X620899D03*
X629599Y1168373D03*
X620899D03*
X630623Y1188452D03*
X620899D03*
X629599Y1181759D03*
X620899D03*
X629599Y1205184D03*
X620899D03*
Y1198491D03*
X629599D03*
X620899Y1225263D03*
X629599D03*
Y1218570D03*
X620899D03*
X629599Y1211877D03*
X620899D03*
X629599Y1241995D03*
X620899D03*
X630922Y1235302D03*
X620036D03*
X620899Y1248688D03*
X629599D03*
X625246Y1273164D03*
X627646D03*
X627631Y1578182D03*
X623371D03*
X627631Y1590094D03*
X623371D03*
X628671Y1602380D03*
Y1614292D03*
X620871D03*
Y1602380D03*
X616611Y1614292D03*
Y1602380D03*
X619488Y1679320D03*
Y1688391D03*
Y1693493D03*
Y1698030D03*
Y1683857D03*
Y1707666D03*
Y1712203D03*
Y1702564D03*
Y1730911D03*
Y1726377D03*
Y1721840D03*
Y1716737D03*
X637041Y766798D03*
X645741D03*
Y773491D03*
X637041D03*
X645741Y780184D03*
X637041D03*
Y803609D03*
X645741D03*
X637041Y796916D03*
X645741D03*
Y790223D03*
X637041D03*
X636221Y810302D03*
X646844D03*
X646774Y816995D03*
X637041D03*
X645741Y833727D03*
X637041D03*
Y827034D03*
X645741D03*
X637041Y847113D03*
X645801D03*
X637041Y840420D03*
X645741D03*
X646819Y853806D03*
X636332Y853955D03*
X645918Y863845D03*
X636266D03*
X637041Y877231D03*
X645741D03*
X637041Y870538D03*
X645741D03*
Y883924D03*
X637041D03*
Y900656D03*
X645741D03*
X637041Y890617D03*
X645741D03*
X637041Y914042D03*
X645741D03*
Y907349D03*
X637041D03*
X646393Y927526D03*
X636026Y927428D03*
X645741Y920735D03*
X637041D03*
X645741Y944160D03*
X637041D03*
X636170Y937467D03*
X646703D03*
X645741Y960892D03*
X637041D03*
Y950853D03*
X645741D03*
X637041Y980971D03*
X645741D03*
X637041Y974278D03*
X645741D03*
X637041Y967585D03*
X645741D03*
X637041Y987664D03*
X645741D03*
X637041Y1027822D03*
X645741D03*
Y1017782D03*
X637041D03*
X645741Y1047900D03*
X637041D03*
Y1041207D03*
X645741D03*
X637041Y1034515D03*
X645741D03*
X637041Y1061286D03*
X645741D03*
Y1054593D03*
X637041D03*
X636141Y1074672D03*
X646541D03*
X645741Y1067979D03*
X636841D03*
X637041Y1091404D03*
X645741D03*
Y1084711D03*
X636241D03*
X645741Y1111483D03*
X637041D03*
X645741Y1098097D03*
X637041D03*
X645741Y1104790D03*
X637041D03*
Y1121522D03*
X645741D03*
X637041Y1128915D03*
X645741Y1128215D03*
X646584Y1135108D03*
X635744Y1134908D03*
X645741Y1141601D03*
X637041D03*
X645741Y1148294D03*
X637041D03*
X645741Y1158333D03*
X637041D03*
Y1171719D03*
X645741D03*
Y1165026D03*
X637041D03*
Y1185105D03*
X645741D03*
Y1178412D03*
X637041D03*
X645741Y1208530D03*
X637041D03*
X645741Y1201837D03*
X637041D03*
Y1195144D03*
X645741D03*
X636005Y1221916D03*
X646570D03*
X645741Y1215223D03*
X637041D03*
X645741Y1238648D03*
X637041D03*
X635995Y1231862D03*
X646539Y1231955D03*
X645741Y1245341D03*
X637041D03*
X634213Y1258679D03*
X642746Y1273364D03*
X639946D03*
X647491Y1578088D03*
X639691Y1578182D03*
X635431D03*
X647491Y1590094D03*
X639691D03*
X635431D03*
X644991Y1614292D03*
Y1602380D03*
X632931D03*
Y1614292D03*
X640731D03*
Y1602380D03*
X650599Y770144D03*
X659299D03*
X650599Y783530D03*
X659299D03*
X650599Y776837D03*
X659299D03*
Y800263D03*
X650599D03*
Y793570D03*
X659299D03*
Y806955D03*
X650599D03*
X660432Y813648D03*
X650599D03*
X660199Y820341D03*
X650599D03*
X659299Y830381D03*
X650599D03*
X659299Y850459D03*
X650599D03*
X659299Y843766D03*
X650599D03*
Y837074D03*
X659299D03*
Y857152D03*
X650599D03*
X649563Y867192D03*
X660299D03*
X659299Y873885D03*
X650599D03*
Y880577D03*
X659299D03*
X650599Y893963D03*
X659299D03*
X650599Y887270D03*
X659299D03*
Y917389D03*
X650599D03*
X659299Y910696D03*
X650599D03*
Y904003D03*
X659299D03*
X660504Y924081D03*
X650599D03*
X660174Y930774D03*
X649661D03*
X659299Y947507D03*
X650599D03*
X659299Y940814D03*
X650599D03*
X659299Y964239D03*
X650599D03*
Y954200D03*
X659299D03*
Y977625D03*
X650599D03*
X659299Y970932D03*
X650599D03*
X659299Y991011D03*
X650599D03*
X659299Y984318D03*
X650599D03*
X659299Y1031168D03*
X650599D03*
X659299Y1017782D03*
X650599D03*
X659299Y1024475D03*
X650599D03*
X659299Y1044554D03*
X650599D03*
X659299Y1037861D03*
X650599D03*
X659299Y1051247D03*
X650599D03*
Y1057940D03*
X659299D03*
X660099Y1078018D03*
X649799D03*
X659299Y1071326D03*
X650599D03*
X659299Y1064633D03*
X650599D03*
X659299Y1094751D03*
X650599D03*
X660099Y1088058D03*
X649799D03*
X650599Y1108137D03*
X659299D03*
X650599Y1101444D03*
X659299D03*
X660199Y1124869D03*
X649932Y1124640D03*
X659299Y1114829D03*
X650599D03*
X659299Y1130762D03*
X650599D03*
X659299Y1138255D03*
X650599D03*
X659299Y1144948D03*
X650599D03*
X659299Y1151641D03*
X650599D03*
Y1161680D03*
X659299D03*
X650599Y1175066D03*
X659299D03*
X650599Y1168373D03*
X659299D03*
X650599Y1188452D03*
X659299D03*
X650599Y1181759D03*
X659299D03*
X650599Y1205184D03*
X659299D03*
X650599Y1198491D03*
X659299D03*
X660070Y1225263D03*
X649913D03*
X659299Y1218570D03*
X650599D03*
X659299Y1211877D03*
X650599D03*
X659299Y1241995D03*
X650599D03*
X660234Y1235302D03*
X649701D03*
X650599Y1248688D03*
X659299D03*
X659546Y1257664D03*
X656446Y1273364D03*
X653646D03*
X651751Y1578182D03*
X659551D03*
X651751Y1590094D03*
X659551D03*
X657051Y1602380D03*
Y1614292D03*
X652791Y1602286D03*
Y1614292D03*
X680299Y770144D03*
X675441Y766798D03*
X666741D03*
X680299Y783530D03*
Y776837D03*
X666741Y773491D03*
X675441D03*
X666741Y780184D03*
X675441D03*
Y803609D03*
X666741D03*
X680299Y800263D03*
Y793570D03*
X666741Y796916D03*
X675441D03*
X666741Y790223D03*
X675441D03*
X676403Y816995D03*
X665803D03*
X675441Y810302D03*
X666741D03*
X680299Y820341D03*
Y813648D03*
Y806955D03*
X675441Y833727D03*
X666741D03*
X676625Y827034D03*
X665876D03*
X680299Y830381D03*
X675441Y847113D03*
X666741D03*
X680299Y850459D03*
Y843766D03*
Y837074D03*
X666741Y840420D03*
X675441D03*
X676417Y853806D03*
X665890D03*
X680299Y867192D03*
Y857152D03*
X665916Y863845D03*
X676600D03*
X675441Y877231D03*
X666741D03*
X675441Y870538D03*
X666741D03*
Y883924D03*
X675441D03*
X680299Y880577D03*
Y873885D03*
X666741Y900656D03*
X675441D03*
X680299Y893963D03*
Y887270D03*
X666741Y890617D03*
X675441D03*
Y914042D03*
X666741D03*
X680299Y917389D03*
Y910696D03*
Y904003D03*
X666741Y907349D03*
X675441D03*
X676488Y927428D03*
X665896D03*
X675441Y920735D03*
X666741D03*
X680299Y930774D03*
Y924081D03*
X675441Y944160D03*
X666741D03*
X676359Y937467D03*
X665923D03*
X680299Y947507D03*
Y940814D03*
Y964239D03*
X675441Y960892D03*
X666741D03*
X680299Y954200D03*
X666741Y950853D03*
X675441D03*
Y980971D03*
X666741D03*
X680299Y970932D03*
X675441Y974278D03*
X666741D03*
X675441Y967585D03*
X666741D03*
X680299Y977625D03*
X675441Y987664D03*
X666741D03*
X680299Y991011D03*
Y984318D03*
Y1031168D03*
Y1024475D03*
X675441Y1027822D03*
X666741D03*
X675441Y1017782D03*
X666741D03*
X680299D03*
X675441Y1047900D03*
X666741D03*
X680299Y1037861D03*
X675441Y1041207D03*
X666741D03*
X675441Y1034515D03*
X666741D03*
X680299Y1044554D03*
Y1057940D03*
Y1051247D03*
X675441Y1054593D03*
X666741D03*
Y1061286D03*
X675441D03*
X676341Y1074672D03*
X665841D03*
X675441Y1067979D03*
X666741D03*
X680299Y1078018D03*
Y1071326D03*
Y1064633D03*
X675441Y1091404D03*
X666741D03*
X676241Y1084711D03*
X665941D03*
X680299Y1094751D03*
Y1088058D03*
X666741Y1111483D03*
X675441D03*
X680299Y1108137D03*
Y1101444D03*
X666741Y1104790D03*
X675441D03*
X666741Y1098097D03*
X675441D03*
X666741Y1128215D03*
X675441D03*
X680299Y1124869D03*
Y1114829D03*
X666741Y1121522D03*
X675441D03*
X680299Y1144948D03*
Y1138255D03*
Y1131562D03*
X666741Y1141601D03*
X675441D03*
X666741Y1134908D03*
X675441D03*
X676652Y1148294D03*
X665602D03*
X676241Y1158333D03*
X665941D03*
X680299Y1161680D03*
Y1151641D03*
X675441Y1165026D03*
X666741D03*
X680299Y1175066D03*
Y1168373D03*
X666741Y1171719D03*
X675441D03*
X680299Y1188452D03*
Y1181759D03*
X666741Y1185105D03*
X675441D03*
X666741Y1178412D03*
X675441D03*
X680299Y1205184D03*
Y1198491D03*
X666741Y1208530D03*
X675441D03*
X666741Y1201837D03*
X675441D03*
X666741Y1195144D03*
X675441D03*
X680299Y1218570D03*
Y1225263D03*
X676448Y1221916D03*
X665651D03*
X675441Y1215223D03*
X666741D03*
X680299Y1211877D03*
X675441Y1238648D03*
X666741D03*
X676462Y1231955D03*
X665912D03*
X680299Y1241995D03*
Y1235302D03*
X675441Y1245341D03*
X666741D03*
X676046Y1257964D03*
X680299Y1248688D03*
X672446Y1273364D03*
X669646D03*
X664851Y1602380D03*
Y1614292D03*
X696441Y766798D03*
X688999Y770144D03*
X696441Y773491D03*
Y780184D03*
X688999Y783530D03*
Y776837D03*
X696441Y803609D03*
Y796916D03*
Y790223D03*
X688999Y800263D03*
Y793570D03*
X696441Y816995D03*
Y810302D03*
X689888Y820341D03*
X688999Y813648D03*
Y806955D03*
X696441Y833727D03*
Y827034D03*
X688999Y830381D03*
X696441Y847113D03*
X688999Y850459D03*
X696441Y840420D03*
X688999Y843766D03*
Y837074D03*
X696441Y863845D03*
Y853806D03*
X688999Y867192D03*
X689896Y857152D03*
X696441Y883924D03*
Y877231D03*
Y870538D03*
X688999Y880577D03*
Y873885D03*
X696441Y900656D03*
Y890617D03*
X688999Y893963D03*
Y887270D03*
X696441Y914042D03*
Y907349D03*
X688999Y917389D03*
Y910696D03*
Y904003D03*
X696441Y927428D03*
Y920735D03*
X690104Y930774D03*
X688999Y924081D03*
X696441Y944160D03*
Y937467D03*
X688999Y947507D03*
Y940814D03*
X696441Y960892D03*
Y950853D03*
X688999Y964239D03*
Y954200D03*
X696441Y980971D03*
Y974278D03*
Y967585D03*
X688999Y970932D03*
Y977625D03*
X696441Y987664D03*
X688999Y991011D03*
Y984318D03*
X696441Y1027822D03*
Y1017782D03*
X688999Y1031168D03*
Y1024475D03*
Y1017782D03*
X696441Y1047900D03*
Y1041207D03*
Y1034515D03*
X688999Y1037861D03*
Y1044554D03*
X696441Y1054593D03*
Y1061286D03*
X688999Y1057940D03*
X696441Y1074672D03*
Y1067979D03*
X688999Y1077118D03*
Y1071326D03*
Y1064633D03*
X696441Y1091404D03*
Y1084711D03*
X688999Y1094751D03*
Y1088058D03*
X696441Y1111483D03*
Y1104790D03*
Y1098097D03*
X688999Y1108137D03*
Y1101444D03*
X696441Y1128215D03*
Y1121522D03*
X688999Y1124869D03*
Y1114829D03*
X696441Y1141601D03*
Y1134908D03*
X688999Y1144948D03*
Y1138255D03*
Y1131562D03*
X696441Y1158333D03*
Y1148294D03*
X688999Y1161680D03*
X689999Y1151641D03*
X696441Y1171719D03*
Y1165026D03*
X688999Y1175066D03*
Y1168373D03*
X696441Y1185105D03*
Y1178412D03*
X688999Y1188452D03*
Y1181759D03*
X696441Y1208530D03*
Y1201837D03*
Y1195144D03*
X688999Y1205184D03*
Y1198491D03*
X696441Y1221916D03*
Y1215223D03*
X688999Y1218570D03*
X689799Y1225263D03*
X688999Y1211877D03*
X696441Y1238648D03*
Y1231955D03*
X688999Y1241995D03*
Y1235302D03*
X688916Y1256964D03*
X696441Y1245341D03*
X688999Y1248688D03*
X686146Y1273364D03*
X683346D03*
X709999Y770144D03*
X705141Y766798D03*
X709999Y783530D03*
Y776837D03*
X705141Y773491D03*
Y780184D03*
X709999Y800263D03*
Y793570D03*
X705141Y803609D03*
Y796916D03*
Y790223D03*
X709999Y820341D03*
Y813648D03*
Y806955D03*
X705141Y816995D03*
Y810302D03*
X709999Y830381D03*
X705141Y833727D03*
Y827034D03*
Y847113D03*
X709999Y850459D03*
Y843766D03*
Y837074D03*
X705141Y840420D03*
Y863845D03*
Y853806D03*
X709999Y867192D03*
Y857152D03*
X705141Y883924D03*
Y877231D03*
Y870538D03*
X709999Y880577D03*
Y873885D03*
X705141Y900656D03*
Y890617D03*
X709999Y893963D03*
Y887270D03*
X705141Y914042D03*
Y907349D03*
X709999Y917389D03*
Y910696D03*
Y904003D03*
X705141Y927428D03*
Y920735D03*
X709999Y930774D03*
Y924081D03*
X705141Y944160D03*
Y937467D03*
X709999Y947507D03*
Y940814D03*
X705141Y960892D03*
Y950853D03*
X709999Y964239D03*
Y954200D03*
X705141Y980971D03*
Y974278D03*
Y967585D03*
X709999Y977625D03*
Y970932D03*
X705141Y987664D03*
X709999Y991011D03*
Y984318D03*
X705141Y1027822D03*
Y1017782D03*
X709999Y1031168D03*
Y1024475D03*
Y1017782D03*
X705141Y1047900D03*
Y1041207D03*
Y1034515D03*
X709999Y1044554D03*
Y1037861D03*
X705141Y1054593D03*
Y1061286D03*
X709999Y1057940D03*
Y1051247D03*
X705141Y1074672D03*
Y1067979D03*
X709999Y1078018D03*
Y1071326D03*
Y1064633D03*
X705141Y1091404D03*
Y1084711D03*
X709999Y1094751D03*
Y1088058D03*
X705141Y1111483D03*
Y1104790D03*
Y1098097D03*
X709999Y1108137D03*
Y1101444D03*
X705141Y1128215D03*
Y1121522D03*
X709999Y1124869D03*
Y1114829D03*
X705141Y1141601D03*
Y1134908D03*
X709999Y1144948D03*
Y1138255D03*
Y1131562D03*
X705141Y1158333D03*
Y1148294D03*
X709999Y1161680D03*
Y1151641D03*
X705141Y1171719D03*
Y1165026D03*
X709999Y1175066D03*
Y1168373D03*
X705141Y1185105D03*
Y1178412D03*
X709999Y1188452D03*
Y1181759D03*
X705141Y1208530D03*
Y1201837D03*
Y1195144D03*
X709999Y1205184D03*
Y1198491D03*
X705141Y1221916D03*
Y1215223D03*
X709999Y1225263D03*
Y1218570D03*
Y1211877D03*
X705141Y1238648D03*
Y1231955D03*
X709999Y1241995D03*
Y1235302D03*
X705141Y1245341D03*
X709999Y1248688D03*
X713046Y1273364D03*
X702146D03*
X699346D03*
X726141Y766798D03*
X718699Y770144D03*
X726141Y773491D03*
Y780184D03*
X718699Y783530D03*
Y776837D03*
X726141Y803609D03*
Y796916D03*
Y790223D03*
X718699Y800263D03*
Y793570D03*
X726141Y816995D03*
Y810302D03*
X718699Y820341D03*
Y813648D03*
Y806955D03*
X726141Y833727D03*
Y827034D03*
X718699Y830381D03*
X726141Y847113D03*
Y840420D03*
X718699Y850459D03*
Y843766D03*
Y837074D03*
X726141Y863845D03*
Y853806D03*
X718699Y867192D03*
Y857152D03*
X726141Y883924D03*
Y877231D03*
Y870538D03*
X718699Y880577D03*
Y873885D03*
X726141Y900656D03*
Y890617D03*
X718699Y893963D03*
Y887270D03*
X726141Y914042D03*
Y907349D03*
X718699Y917389D03*
Y910696D03*
Y904003D03*
X726141Y927428D03*
Y920735D03*
X718699Y930774D03*
Y924081D03*
X726141Y944160D03*
Y937467D03*
X718699Y947507D03*
Y940814D03*
X726141Y960892D03*
Y950853D03*
X718699Y964239D03*
Y954200D03*
X726141Y980971D03*
Y974278D03*
Y967585D03*
X718699Y977625D03*
Y970932D03*
X726141Y987664D03*
X718699Y991011D03*
Y984318D03*
X726141Y1027822D03*
Y1017782D03*
X718699Y1031168D03*
Y1024475D03*
Y1017782D03*
X726141Y1047900D03*
Y1041207D03*
Y1034515D03*
X718699Y1044554D03*
Y1037861D03*
X726141Y1061286D03*
Y1054593D03*
X718699Y1057940D03*
Y1051247D03*
X726141Y1074672D03*
Y1067979D03*
X718699Y1078018D03*
Y1071326D03*
Y1064633D03*
X726141Y1091404D03*
Y1084711D03*
X718699Y1094751D03*
Y1088058D03*
X726141Y1111483D03*
Y1104790D03*
Y1098097D03*
X718699Y1108137D03*
Y1101444D03*
X726141Y1128215D03*
Y1121522D03*
X718699Y1124869D03*
Y1114829D03*
X726141Y1141601D03*
Y1134908D03*
X718699Y1144948D03*
Y1138255D03*
Y1131562D03*
X726141Y1158333D03*
Y1148294D03*
X718699Y1161680D03*
Y1151641D03*
X726141Y1171719D03*
Y1165026D03*
X718699Y1175066D03*
Y1168373D03*
X726141Y1185105D03*
Y1178412D03*
X718699Y1188452D03*
Y1181759D03*
X726141Y1208530D03*
Y1201837D03*
Y1195144D03*
X718699Y1205184D03*
Y1198491D03*
X726141Y1221916D03*
Y1215223D03*
X718699Y1225263D03*
Y1218570D03*
Y1211877D03*
X726141Y1238648D03*
Y1231955D03*
X718699Y1241995D03*
Y1235302D03*
X726141Y1245341D03*
X719046Y1257064D03*
X718699Y1248688D03*
X729046Y1273364D03*
X715846D03*
X739699Y770144D03*
X734841Y766798D03*
X739699Y783530D03*
Y776837D03*
X734841Y773491D03*
Y780184D03*
X739699Y800263D03*
Y793570D03*
X734841Y803609D03*
Y796916D03*
Y790223D03*
X739699Y820341D03*
Y813648D03*
Y806955D03*
X734841Y816995D03*
Y810302D03*
X739699Y830381D03*
X734841Y833727D03*
Y827034D03*
X739699Y850459D03*
Y843766D03*
Y837074D03*
X734841Y847113D03*
Y840420D03*
X739699Y867192D03*
Y857152D03*
X734841Y863845D03*
Y853806D03*
X739699Y880577D03*
Y873885D03*
X734841Y883924D03*
Y877231D03*
Y870538D03*
X739699Y893963D03*
Y887270D03*
X734841Y900656D03*
Y890617D03*
X739699Y917389D03*
Y910696D03*
Y904003D03*
X734841Y914042D03*
Y907349D03*
X739699Y930774D03*
Y924081D03*
X734841Y927428D03*
Y920735D03*
X739699Y947507D03*
Y940814D03*
X734841Y944160D03*
Y937467D03*
X739699Y964239D03*
Y954200D03*
X734841Y960892D03*
Y950853D03*
X739699Y977625D03*
Y970932D03*
X734841Y980971D03*
Y974278D03*
Y967585D03*
X739699Y991011D03*
Y984318D03*
X734841Y987664D03*
X739699Y1031168D03*
Y1024475D03*
Y1017782D03*
X734841Y1027822D03*
Y1017782D03*
X739699Y1044554D03*
Y1037861D03*
X734841Y1047900D03*
Y1041207D03*
Y1034515D03*
X739699Y1057940D03*
Y1051247D03*
X734841Y1061286D03*
Y1054593D03*
X739699Y1078018D03*
Y1071326D03*
Y1064633D03*
X734841Y1074672D03*
Y1067979D03*
X739699Y1094751D03*
Y1088058D03*
X734841Y1091404D03*
Y1084711D03*
X739699Y1108137D03*
Y1101444D03*
X734841Y1111483D03*
Y1104790D03*
Y1098097D03*
X739699Y1124869D03*
Y1114829D03*
X734841Y1128215D03*
Y1121522D03*
X739699Y1144948D03*
Y1138255D03*
Y1131562D03*
X734841Y1141601D03*
Y1134908D03*
X739699Y1161680D03*
Y1151641D03*
X734841Y1158333D03*
Y1148294D03*
X739699Y1175066D03*
Y1168373D03*
X734841Y1171719D03*
Y1165026D03*
X739699Y1188452D03*
Y1181759D03*
X734841Y1185105D03*
Y1178412D03*
X739699Y1205184D03*
Y1198491D03*
X734841Y1208530D03*
Y1201837D03*
Y1195144D03*
X739699Y1225263D03*
Y1218570D03*
Y1211877D03*
X734841Y1221916D03*
Y1215223D03*
X739699Y1241995D03*
Y1235302D03*
X734841Y1238648D03*
Y1231955D03*
X739699Y1248688D03*
X734841Y1245341D03*
X745546Y1273364D03*
X742746D03*
X731372Y1273464D03*
X755841Y766798D03*
X748399Y770144D03*
X755841Y780184D03*
Y773491D03*
X748399Y783530D03*
Y776837D03*
X755841Y803609D03*
Y796916D03*
Y790223D03*
X748399Y800263D03*
Y793570D03*
X755841Y816995D03*
Y810302D03*
X748399Y820341D03*
Y813648D03*
Y806955D03*
X755841Y833727D03*
Y827034D03*
X748399Y830381D03*
X755841Y847113D03*
Y840420D03*
X748399Y850459D03*
Y843766D03*
Y837074D03*
X755841Y863845D03*
Y853806D03*
X748399Y867192D03*
Y857152D03*
X755841Y883924D03*
Y877231D03*
Y870538D03*
X748399Y880577D03*
Y873885D03*
X755841Y900656D03*
Y890617D03*
X748399Y893963D03*
Y887270D03*
X755841Y914042D03*
Y907349D03*
X748399Y917389D03*
Y910696D03*
Y904003D03*
X755841Y927428D03*
Y920735D03*
X748399Y930774D03*
Y924081D03*
X755841Y944160D03*
Y937467D03*
X748399Y947507D03*
Y940814D03*
X755841Y960892D03*
Y950853D03*
X748399Y964239D03*
Y954200D03*
X755841Y980971D03*
Y974278D03*
Y967585D03*
X748399Y977625D03*
Y970932D03*
X755841Y987664D03*
X748399Y991011D03*
Y984318D03*
X755841Y1027822D03*
Y1017782D03*
X748399Y1031168D03*
Y1024475D03*
Y1017782D03*
X755841Y1047900D03*
Y1041207D03*
Y1034515D03*
X748399Y1044554D03*
Y1037861D03*
X755841Y1054593D03*
Y1061286D03*
X748399Y1057940D03*
X755841Y1067979D03*
Y1074672D03*
X748399Y1078018D03*
Y1071326D03*
Y1064633D03*
X755841Y1084711D03*
Y1091404D03*
X748399Y1094751D03*
Y1088058D03*
X755841Y1111483D03*
Y1104790D03*
Y1098097D03*
X748399Y1108137D03*
Y1101444D03*
X755841Y1128215D03*
Y1121522D03*
X748399Y1124869D03*
Y1114829D03*
X755841Y1141601D03*
Y1134908D03*
X748399Y1144948D03*
Y1138255D03*
Y1131562D03*
X755841Y1158333D03*
Y1148294D03*
X748399Y1161680D03*
Y1151641D03*
X755841Y1171719D03*
Y1165026D03*
X748399Y1175066D03*
Y1168373D03*
X755841Y1185105D03*
Y1178412D03*
X748399Y1188452D03*
Y1181759D03*
X755841Y1208530D03*
Y1201837D03*
Y1195144D03*
X748399Y1205184D03*
Y1198491D03*
X755841Y1221916D03*
Y1215223D03*
X748399Y1225263D03*
Y1218570D03*
Y1211877D03*
X755841Y1238648D03*
Y1231955D03*
X748399Y1241995D03*
Y1235302D03*
X755841Y1245341D03*
X748283Y1256964D03*
X748399Y1248688D03*
X758746Y1273364D03*
X761546D03*
X769399Y770144D03*
X778099D03*
X764541Y766798D03*
X769399Y783530D03*
X778099D03*
X769399Y776837D03*
X778099D03*
X764541Y780184D03*
Y773491D03*
X769399Y800263D03*
X778099D03*
X769399Y793570D03*
X778099D03*
X764541Y803609D03*
Y796916D03*
Y790223D03*
X769399Y820341D03*
X778099D03*
X769399Y813648D03*
X778099D03*
X769399Y806955D03*
X778099D03*
X764541Y816995D03*
Y810302D03*
X769399Y830381D03*
X778099D03*
X764541Y833727D03*
Y827034D03*
X769399Y850459D03*
X778099D03*
Y843766D03*
X769399D03*
Y837074D03*
X778099D03*
X764541Y847113D03*
Y840420D03*
X778099Y867192D03*
X769399D03*
Y857152D03*
X778099D03*
X764541Y863845D03*
Y853806D03*
X769399Y880577D03*
X778099D03*
X769399Y873885D03*
X778099D03*
X764541Y883924D03*
Y877231D03*
Y870538D03*
X778099Y893963D03*
X769399D03*
Y887270D03*
X778099D03*
X764541Y900656D03*
Y890617D03*
X769399Y917389D03*
X778099D03*
X769399Y910696D03*
X778099D03*
X769399Y904003D03*
X778099D03*
X764541Y914042D03*
Y907349D03*
X769399Y930774D03*
X778099D03*
X769399Y924081D03*
X778099D03*
X764541Y927428D03*
Y920735D03*
X769399Y947507D03*
X778099D03*
X769399Y940814D03*
X778099D03*
X764541Y944160D03*
Y937467D03*
X769399Y964239D03*
X778099D03*
X769399Y954200D03*
X778099D03*
X764541Y960892D03*
Y950853D03*
X769399Y977625D03*
X778099D03*
X769399Y970932D03*
X778099D03*
X764541Y980971D03*
Y974278D03*
Y967585D03*
X769399Y991011D03*
X778099D03*
X769399Y984318D03*
X778099D03*
X764541Y987664D03*
X769399Y1031168D03*
X778099D03*
X769399Y1024475D03*
X778099D03*
X769399Y1017782D03*
X778099D03*
X764541Y1027822D03*
Y1017782D03*
X778099Y1044554D03*
X769399D03*
Y1037861D03*
X778099D03*
X764541Y1047900D03*
Y1041207D03*
Y1034515D03*
X769399Y1057940D03*
X778099D03*
X769399Y1051247D03*
X778099D03*
X764541Y1054593D03*
Y1061286D03*
X778099Y1078018D03*
X769399D03*
X778099Y1071326D03*
X769399D03*
Y1064633D03*
X778099D03*
X764541Y1067979D03*
Y1074672D03*
X778099Y1094751D03*
X769399D03*
X778099Y1088058D03*
X769399D03*
X764541Y1084711D03*
Y1091404D03*
X778099Y1108137D03*
X769399D03*
X778099Y1101444D03*
X769399D03*
X764541Y1111483D03*
Y1104790D03*
Y1098097D03*
X778099Y1124869D03*
X769399D03*
X778099Y1114829D03*
X769399D03*
X764541Y1128215D03*
Y1121522D03*
X778099Y1144948D03*
X769399D03*
X778099Y1138255D03*
X769399D03*
X778099Y1131562D03*
X769399D03*
X764541Y1141601D03*
Y1134908D03*
X778099Y1161680D03*
X769399D03*
X778099Y1151641D03*
X769399D03*
X764541Y1158333D03*
Y1148294D03*
X778099Y1175066D03*
X769399D03*
X778099Y1168373D03*
X769399D03*
X764541Y1171719D03*
Y1165026D03*
X778099Y1188452D03*
X769399D03*
X778099Y1181759D03*
X769399D03*
X764541Y1185105D03*
Y1178412D03*
X769399Y1205184D03*
X778099D03*
Y1198491D03*
X769399D03*
X764541Y1208530D03*
Y1201837D03*
Y1195144D03*
X778099Y1225263D03*
X769399D03*
X778099Y1218570D03*
X769399D03*
Y1211877D03*
X778099D03*
X764541Y1221916D03*
Y1215223D03*
X778099Y1241995D03*
X769399D03*
X778099Y1235302D03*
X769399D03*
X764541Y1238648D03*
Y1231955D03*
X778346Y1257264D03*
X778099Y1248688D03*
X769399D03*
X764541Y1245341D03*
X772446Y1273364D03*
X775246D03*
X785541Y766798D03*
X794241D03*
X785541Y773491D03*
X794241D03*
X785541Y780184D03*
X794241D03*
X785541Y803609D03*
X794241D03*
X785541Y790223D03*
X794241D03*
X785541Y796916D03*
X794241D03*
X785541Y816995D03*
X794241D03*
X785541Y810302D03*
X794241D03*
X785541Y833727D03*
X794241D03*
X785541Y827034D03*
X794241D03*
X785541Y840420D03*
X794241D03*
X785541Y847113D03*
X794241D03*
X785541Y853806D03*
X794241D03*
X785541Y863845D03*
X794241D03*
X785541Y883924D03*
X794241D03*
X785541Y870538D03*
X794241D03*
X785541Y877231D03*
X794241D03*
X785541Y900656D03*
X794241D03*
X785541Y890617D03*
X794241D03*
X785541Y907349D03*
X794241D03*
X785541Y914042D03*
X794241D03*
X785541Y920735D03*
X794241D03*
X785541Y927428D03*
X794241D03*
X785541Y937467D03*
X794241D03*
X785541Y944160D03*
X794241D03*
X785541Y960892D03*
X794241D03*
X785541Y950853D03*
X794241D03*
X785541Y980971D03*
X794241D03*
X785541Y974278D03*
X794241D03*
X785541Y967585D03*
X794241D03*
X785541Y987664D03*
X794241D03*
X785541Y1027822D03*
X794241D03*
X785541Y1017782D03*
X794241D03*
X785541Y1047900D03*
X794241D03*
X785541Y1041207D03*
X794241D03*
X785541Y1034515D03*
X794241D03*
X785541Y1054593D03*
X794241D03*
X785541Y1061286D03*
X794241D03*
X785541Y1074672D03*
X794241D03*
X785541Y1067979D03*
X794241D03*
X785541Y1091404D03*
X794241D03*
X785541Y1084711D03*
X794241D03*
X785541Y1111483D03*
X794241D03*
X785541Y1104790D03*
X794241D03*
X785541Y1098097D03*
X794241D03*
X785541Y1128215D03*
X794241D03*
X785541Y1121522D03*
X794241D03*
X785541Y1141601D03*
X794241D03*
X785541Y1134908D03*
X794241D03*
X785541Y1158333D03*
X794241D03*
X785541Y1148294D03*
X794241D03*
X785541Y1171719D03*
X794241D03*
X785541Y1165026D03*
X794241D03*
X785541Y1178412D03*
X794241D03*
X785541Y1185105D03*
X794241D03*
X785541Y1208530D03*
X794241D03*
X785541Y1195144D03*
X794241D03*
X785541Y1201837D03*
X794241D03*
X785541Y1221916D03*
X794241D03*
X785541Y1215223D03*
X794241D03*
X785541Y1238648D03*
X794241D03*
X785541Y1231955D03*
X794241D03*
X785541Y1245341D03*
X794241D03*
X788446Y1273364D03*
X791246D03*
X799099Y770144D03*
X807799D03*
X799099Y783530D03*
X807799D03*
X799099Y776837D03*
X807799D03*
X799099Y800263D03*
X807799D03*
X799099Y793570D03*
X807799D03*
X799099Y820341D03*
X807799D03*
X799099Y806955D03*
X807799D03*
X799099Y813648D03*
X807799D03*
X799099Y830381D03*
X807799D03*
X799099Y850459D03*
X807799D03*
X799099Y837074D03*
X807799D03*
X799099Y843766D03*
X807799D03*
X799099Y867192D03*
X807799D03*
X799099Y857152D03*
X807799D03*
X799099Y873885D03*
X807799D03*
X799099Y880577D03*
X807799D03*
X799099Y887270D03*
X807799D03*
X799099Y893963D03*
X807799D03*
X799099Y917389D03*
X807799D03*
X799099Y904003D03*
X807799D03*
X799099Y910696D03*
X807799D03*
X799099Y930774D03*
X807799D03*
X799099Y924081D03*
X807799D03*
X799099Y947507D03*
X807799D03*
X799099Y940814D03*
X807799D03*
X799099Y964239D03*
X807799D03*
X799099Y954200D03*
X807799D03*
X799099Y970932D03*
X807799D03*
X799099Y977625D03*
X807799D03*
X799099Y991011D03*
X807799D03*
X799099Y984318D03*
X807799D03*
X799099Y1031168D03*
X807799D03*
X799099Y1024475D03*
X807799D03*
X799099Y1017782D03*
X807799D03*
X799099Y1037861D03*
X807799D03*
X799099Y1044554D03*
X807799D03*
X799099Y1057940D03*
X807799D03*
X799099Y1051247D03*
X807799D03*
X799099Y1078018D03*
X807799D03*
X799099Y1071326D03*
X807799D03*
X799099Y1064633D03*
X807799D03*
X799099Y1094751D03*
X807799D03*
X799099Y1088058D03*
X807799D03*
X799099Y1108137D03*
X807799D03*
X799099Y1101444D03*
X807799D03*
X799099Y1124869D03*
X807799D03*
X799099Y1114829D03*
X807799D03*
X799099Y1144948D03*
X807799D03*
X799099Y1138255D03*
X807799D03*
X799099Y1131562D03*
X807799D03*
X799099Y1161680D03*
X807799D03*
X799099Y1151641D03*
X807799D03*
X799099Y1175066D03*
X807799D03*
X799099Y1168373D03*
X807799D03*
X799099Y1188452D03*
X807799D03*
X799099Y1181759D03*
X807799D03*
X799099Y1205184D03*
X807799D03*
X799099Y1198491D03*
X807799D03*
X799099Y1225263D03*
X807799D03*
X799099Y1211877D03*
X807799D03*
X799099Y1218570D03*
X807799D03*
X799099Y1241995D03*
X807799D03*
X799099Y1235302D03*
X807799D03*
X799099Y1248688D03*
X807799D03*
X808046Y1257664D03*
X804946Y1273364D03*
X802146D03*
X815241Y766798D03*
X823941D03*
X815241Y773491D03*
X823941D03*
X815241Y780184D03*
X823941D03*
X815241Y803609D03*
X823941D03*
X815241Y790223D03*
X823941D03*
X815241Y796916D03*
X823941D03*
X815241Y816995D03*
X823941D03*
X815241Y810302D03*
X823941D03*
X815241Y833727D03*
X823941D03*
X815241Y827034D03*
X823941D03*
X815241Y840420D03*
X823941D03*
X815241Y847113D03*
X823941D03*
X815241Y853806D03*
X823941D03*
X815241Y863845D03*
X823941D03*
X815241Y883924D03*
X823941D03*
X815241Y870538D03*
X823941D03*
X815241Y877231D03*
X823941D03*
X815241Y900656D03*
X823941D03*
X815241Y890617D03*
X823941D03*
X815241Y907349D03*
X823941D03*
X815241Y914042D03*
X823941D03*
X815241Y920735D03*
X823941D03*
X815241Y927428D03*
X823941D03*
X815241Y937467D03*
X823941D03*
X815241Y944160D03*
X823941D03*
X815241Y960892D03*
X823941D03*
X815241Y950853D03*
X823941D03*
X815241Y980971D03*
X823941D03*
X815241Y974278D03*
X823941D03*
X815241Y967585D03*
X823941D03*
X815241Y987664D03*
X823941D03*
X815241Y1027822D03*
X823941D03*
X815241Y1017782D03*
X823941D03*
X815241Y1047900D03*
X823941D03*
X815241Y1041207D03*
X823941D03*
X815241Y1034515D03*
X823941D03*
X815241Y1054593D03*
X823941D03*
X815241Y1061286D03*
X823941D03*
X815241Y1074672D03*
X823941D03*
X815241Y1067979D03*
X823941D03*
X815241Y1091404D03*
X823941D03*
X815241Y1084711D03*
X823941D03*
X815241Y1111483D03*
X823941D03*
X815241Y1104790D03*
X823941D03*
X815241Y1098097D03*
X823941D03*
X815241Y1128215D03*
X823941D03*
X815241Y1121522D03*
X823941D03*
X815241Y1141601D03*
X823941D03*
X815241Y1134908D03*
X823941D03*
X815241Y1158333D03*
X823941D03*
X815241Y1148294D03*
X823941D03*
X815241Y1171719D03*
X823941D03*
X815241Y1165026D03*
X823941D03*
X815241Y1178412D03*
X823941D03*
X815241Y1185105D03*
X823941D03*
X815241Y1208530D03*
X823941D03*
X815241Y1195144D03*
X823941D03*
X815241Y1201837D03*
X823941D03*
X815241Y1221916D03*
X823941D03*
X815241Y1215223D03*
X823941D03*
X815241Y1238648D03*
X823941D03*
X815241Y1231955D03*
X823941D03*
X815241Y1245341D03*
X823941D03*
X820946Y1273364D03*
X818146D03*
X828799Y770144D03*
X837499D03*
X828799Y783530D03*
X837499D03*
X828799Y776837D03*
X837499D03*
Y800263D03*
X828799D03*
X837499Y793570D03*
X828799D03*
Y820341D03*
X837499D03*
X828799Y813648D03*
X837499D03*
X828799Y806955D03*
X837499D03*
X828799Y830381D03*
X837499D03*
X828799Y850459D03*
X837499D03*
X828799Y843766D03*
X837499D03*
X828799Y837074D03*
X837499D03*
X828799Y867192D03*
X837499D03*
X828799Y857152D03*
X837499D03*
X828799Y880577D03*
X837499D03*
X828799Y873885D03*
X837499D03*
X828799Y893963D03*
X837499D03*
X828799Y887270D03*
X837499D03*
X828799Y917389D03*
X837499D03*
Y904003D03*
X828799D03*
X837499Y910696D03*
X828799D03*
Y930774D03*
X837499D03*
X828799Y924081D03*
X837499D03*
X828799Y947507D03*
X837499D03*
X828799Y940814D03*
X837499D03*
X828799Y964239D03*
X837499D03*
X828799Y954200D03*
X837499D03*
X828799Y977625D03*
X837499D03*
X828799Y970932D03*
X837499D03*
X828799Y991011D03*
X837499D03*
X828799Y984318D03*
X837499D03*
X828799Y1031168D03*
X837499D03*
X828799Y1024475D03*
X837499D03*
X828799Y1017782D03*
X837499D03*
X828799Y1044554D03*
X837499D03*
X828799Y1037861D03*
X837499D03*
X828799Y1057940D03*
X837499D03*
X828799Y1051247D03*
X837499D03*
X828799Y1078018D03*
X837499D03*
X828799Y1071326D03*
X837499D03*
X828799Y1064633D03*
X837499D03*
X828799Y1094751D03*
X837499D03*
Y1088058D03*
X828799D03*
X837499Y1108137D03*
X828799D03*
Y1101444D03*
X837499D03*
Y1124869D03*
X828799D03*
X837499Y1114829D03*
X828799D03*
X837499Y1144948D03*
X828799D03*
X837499Y1138255D03*
X828799D03*
X837499Y1131562D03*
X828799D03*
X837499Y1161680D03*
X828799D03*
X837499Y1151641D03*
X828799D03*
X837499Y1175066D03*
X828799D03*
X837499Y1168373D03*
X828799D03*
Y1188452D03*
X837499D03*
Y1181759D03*
X828799D03*
X837499Y1205184D03*
X828799D03*
X837499Y1198491D03*
X828799D03*
X837499Y1225263D03*
X828799D03*
X837499Y1218570D03*
X828799D03*
X837499Y1211877D03*
X828799D03*
X837499Y1241995D03*
X828799D03*
X837499Y1235302D03*
X828799D03*
X837499Y1248688D03*
X828799D03*
X837846Y1256964D03*
X839246Y1273064D03*
X842046D03*
X831846Y1273364D03*
X834646D03*
X844941Y766798D03*
X853641D03*
X844941Y780184D03*
X853641D03*
X844941Y773491D03*
X853641D03*
X844941Y803609D03*
X853641D03*
X844941Y796916D03*
X853641D03*
X844941Y790223D03*
X853641D03*
X844941Y816995D03*
X853641D03*
X844941Y810302D03*
X853641D03*
X844941Y833727D03*
X853641D03*
X844941Y827034D03*
X853641D03*
X844941Y847113D03*
X853641D03*
X844941Y840420D03*
X853641D03*
X844941Y863845D03*
X853641D03*
X844941Y853806D03*
X853641D03*
X844941Y883924D03*
X853641D03*
X844941Y877231D03*
X853641D03*
X844941Y870538D03*
X853641D03*
X844941Y900656D03*
X853641D03*
X844941Y890617D03*
X853641D03*
X844941Y914042D03*
X853641D03*
X844941Y907349D03*
X853641D03*
X844941Y927428D03*
X853641D03*
X844941Y920735D03*
X853641D03*
X844941Y944160D03*
X853641D03*
X844941Y937467D03*
X853641D03*
X844941Y960892D03*
X853641D03*
X844941Y950853D03*
X853641D03*
X844941Y980971D03*
X853641D03*
X844941Y974278D03*
X853641D03*
X844941Y967585D03*
X853641D03*
X844941Y987664D03*
X853641D03*
X844941Y1027822D03*
X853641D03*
X844941Y1017782D03*
X853641D03*
X844941Y1047900D03*
X853641D03*
X844941Y1041207D03*
X853641D03*
X844941Y1034515D03*
X853641D03*
X844941Y1061286D03*
X853641D03*
X844941Y1054593D03*
X853641D03*
X844941Y1074672D03*
X853641D03*
X844941Y1067979D03*
X853641D03*
X844941Y1091404D03*
X853641D03*
X844941Y1084711D03*
X853641D03*
X844941Y1111483D03*
X853641D03*
X844941Y1104790D03*
X853641D03*
X844941Y1098097D03*
X853641D03*
X844941Y1128215D03*
X853641D03*
X844941Y1121522D03*
X853641D03*
X844941Y1141601D03*
X853641D03*
X844941Y1134908D03*
X853641D03*
X844941Y1158333D03*
X853641D03*
X844941Y1148294D03*
X853641D03*
X844941Y1171719D03*
X853641D03*
X844941Y1165026D03*
X853641D03*
X844941Y1185105D03*
X853641D03*
X844941Y1178412D03*
X853641D03*
X844941Y1208530D03*
X853641D03*
X844941Y1201837D03*
X853641D03*
X844941Y1195144D03*
X853641D03*
X844941Y1221916D03*
X853641D03*
X844941Y1215223D03*
X853641D03*
X844941Y1238648D03*
X853641D03*
X844941Y1231955D03*
X853641D03*
X844941Y1245341D03*
X853641D03*
X1003841Y770144D03*
Y783530D03*
Y776837D03*
Y800263D03*
Y793570D03*
Y820341D03*
Y813648D03*
Y806955D03*
Y830381D03*
Y850459D03*
Y843766D03*
Y837074D03*
Y867192D03*
Y857152D03*
Y880577D03*
Y873885D03*
Y893963D03*
Y887270D03*
Y917389D03*
Y910696D03*
Y904003D03*
Y930774D03*
Y924081D03*
Y947507D03*
Y940814D03*
Y964239D03*
Y954200D03*
Y977625D03*
Y970932D03*
Y991011D03*
Y984318D03*
Y1031168D03*
Y1024475D03*
Y1017782D03*
Y1044554D03*
Y1037861D03*
Y1057940D03*
Y1051247D03*
Y1078018D03*
Y1071326D03*
Y1064633D03*
Y1094751D03*
Y1088058D03*
Y1108137D03*
Y1101444D03*
Y1124869D03*
Y1114829D03*
Y1144948D03*
Y1138255D03*
Y1131562D03*
Y1161680D03*
Y1151641D03*
Y1175066D03*
Y1168373D03*
Y1188452D03*
Y1181759D03*
Y1205184D03*
Y1198491D03*
Y1225263D03*
Y1218570D03*
Y1211877D03*
Y1241995D03*
Y1235302D03*
Y1248688D03*
X1019983Y766798D03*
X1012541Y770144D03*
X1019983Y780184D03*
Y773491D03*
X1012541Y783530D03*
Y776837D03*
X1019983Y803609D03*
Y796916D03*
Y790223D03*
X1012541Y800263D03*
Y793570D03*
X1019983Y816995D03*
Y810302D03*
X1012541Y820341D03*
Y813648D03*
Y806955D03*
X1019983Y833727D03*
Y827034D03*
X1012541Y830381D03*
X1019983Y847113D03*
Y840420D03*
X1012541Y850459D03*
Y843766D03*
Y837074D03*
X1019983Y863845D03*
Y853806D03*
X1012541Y867192D03*
Y857152D03*
X1019983Y883924D03*
Y877231D03*
Y870538D03*
X1012541Y880577D03*
Y873885D03*
X1019983Y900656D03*
Y890617D03*
X1012541Y893963D03*
Y887270D03*
X1019983Y914042D03*
Y907349D03*
X1012541Y917389D03*
Y910696D03*
Y904003D03*
X1019983Y927428D03*
Y920735D03*
X1012541Y930774D03*
Y924081D03*
X1019983Y944160D03*
Y937467D03*
X1012541Y947507D03*
Y940814D03*
X1019983Y960892D03*
Y950853D03*
X1012541Y964239D03*
Y954200D03*
X1019983Y980971D03*
Y974278D03*
Y967585D03*
X1012541Y977625D03*
Y970932D03*
X1019983Y987664D03*
X1012541Y991011D03*
Y984318D03*
X1019983Y1027822D03*
Y1017782D03*
X1012541Y1031168D03*
Y1024475D03*
Y1017782D03*
X1019983Y1047900D03*
Y1041207D03*
Y1034515D03*
X1012541Y1044554D03*
Y1037861D03*
X1019983Y1061286D03*
Y1054593D03*
X1012541Y1057940D03*
Y1051247D03*
X1019983Y1067979D03*
Y1074672D03*
X1012541Y1078018D03*
Y1071326D03*
Y1064633D03*
X1019983Y1091404D03*
Y1084711D03*
X1012541Y1094751D03*
Y1088058D03*
X1019983Y1111483D03*
Y1104790D03*
Y1098097D03*
X1012541Y1108137D03*
Y1101444D03*
X1019983Y1128215D03*
Y1121522D03*
X1012541Y1124869D03*
Y1114829D03*
X1019983Y1141601D03*
Y1134908D03*
X1012541Y1144948D03*
Y1138255D03*
Y1131562D03*
X1019983Y1158333D03*
Y1148294D03*
X1012541Y1161680D03*
Y1151641D03*
X1019983Y1171719D03*
Y1165026D03*
X1012541Y1175066D03*
Y1168373D03*
X1019983Y1185105D03*
Y1178412D03*
X1012541Y1188452D03*
Y1181759D03*
X1019983Y1208530D03*
Y1201837D03*
Y1195144D03*
X1012541Y1205184D03*
Y1198491D03*
X1019983Y1221916D03*
Y1215223D03*
X1012541Y1225263D03*
Y1218570D03*
Y1211877D03*
X1019983Y1238648D03*
Y1231955D03*
X1012541Y1241995D03*
Y1235302D03*
X1012543Y1257198D03*
X1019983Y1245341D03*
X1012541Y1248688D03*
X1017111Y1273299D03*
X1014111D03*
X1033541Y770144D03*
X1028683Y766798D03*
X1033541Y783530D03*
Y776837D03*
X1028683Y780184D03*
Y773491D03*
X1033541Y800263D03*
Y793570D03*
X1028683Y803609D03*
Y796916D03*
Y790223D03*
X1033541Y820341D03*
Y813648D03*
Y806955D03*
X1028683Y816995D03*
Y810302D03*
X1033541Y830381D03*
X1028683Y833727D03*
Y827034D03*
X1033541Y850459D03*
Y843766D03*
Y837074D03*
X1028683Y847113D03*
Y840420D03*
X1033541Y867192D03*
Y857152D03*
X1028683Y863845D03*
Y853806D03*
X1033541Y880577D03*
Y873885D03*
X1028683Y883924D03*
Y877231D03*
Y870538D03*
X1033541Y893963D03*
Y887270D03*
X1028683Y900656D03*
Y890617D03*
X1033541Y917389D03*
Y910696D03*
Y904003D03*
X1028683Y914042D03*
Y907349D03*
X1033541Y930774D03*
Y924081D03*
X1028683Y927428D03*
Y920735D03*
X1033541Y947507D03*
Y940814D03*
X1028683Y944160D03*
Y937467D03*
X1033541Y964239D03*
Y954200D03*
X1028683Y960892D03*
Y950853D03*
X1033541Y977625D03*
Y970932D03*
X1028683Y980971D03*
Y974278D03*
Y967585D03*
X1033541Y991011D03*
Y984318D03*
X1028683Y987664D03*
X1033541Y1031168D03*
Y1017782D03*
Y1024475D03*
X1028683Y1027822D03*
Y1017782D03*
X1033541Y1044554D03*
Y1037861D03*
X1028683Y1047900D03*
Y1041207D03*
Y1034515D03*
X1033541Y1057940D03*
Y1051247D03*
X1028683Y1061286D03*
Y1054593D03*
X1033541Y1078018D03*
Y1071326D03*
Y1064633D03*
X1028683Y1067979D03*
Y1074672D03*
X1033541Y1094751D03*
Y1088058D03*
X1028683Y1091404D03*
Y1084711D03*
X1033541Y1108137D03*
Y1101444D03*
X1028683Y1111483D03*
Y1104790D03*
Y1098097D03*
X1033541Y1114829D03*
Y1124869D03*
X1028683Y1128215D03*
Y1121522D03*
X1033541Y1144948D03*
Y1138255D03*
Y1131562D03*
X1028683Y1141601D03*
Y1134908D03*
X1033541Y1161680D03*
Y1151641D03*
X1028683Y1158333D03*
Y1148294D03*
X1033541Y1175066D03*
Y1168373D03*
X1028683Y1171719D03*
Y1165026D03*
X1033541Y1188452D03*
Y1181759D03*
X1028683Y1185105D03*
Y1178412D03*
X1033541Y1205184D03*
Y1198491D03*
X1028683Y1208530D03*
Y1201837D03*
Y1195144D03*
X1033541Y1225263D03*
Y1218570D03*
Y1211877D03*
X1028683Y1221916D03*
Y1215223D03*
X1033541Y1241995D03*
Y1235302D03*
X1028683Y1238648D03*
Y1231955D03*
X1033541Y1248688D03*
X1028683Y1245341D03*
X1036588Y1273344D03*
X1022888D03*
X1025688D03*
X1049683Y766798D03*
X1042241Y770144D03*
X1049683Y780184D03*
Y773491D03*
X1042241Y783530D03*
Y776837D03*
X1049683Y803609D03*
Y796916D03*
Y790223D03*
X1042241Y800263D03*
Y793570D03*
X1049683Y816995D03*
Y810302D03*
X1042241Y820341D03*
Y813648D03*
Y806955D03*
X1049683Y833727D03*
Y827034D03*
X1042241Y830381D03*
X1049683Y847113D03*
Y840420D03*
X1042241Y850459D03*
Y843766D03*
Y837074D03*
X1049683Y863845D03*
Y853806D03*
X1042241Y867192D03*
Y857152D03*
X1049683Y883924D03*
Y877231D03*
Y870538D03*
X1042241Y880577D03*
Y873885D03*
X1049683Y900656D03*
Y890617D03*
X1042241Y893963D03*
Y887270D03*
X1049683Y914042D03*
Y907349D03*
X1042241Y917389D03*
Y910696D03*
Y904003D03*
X1049683Y927428D03*
Y920735D03*
X1042241Y930774D03*
Y924081D03*
X1049683Y944160D03*
Y937467D03*
X1042241Y947507D03*
Y940814D03*
X1049683Y960892D03*
Y950853D03*
X1042241Y964239D03*
Y954200D03*
X1049683Y980971D03*
Y974278D03*
Y967585D03*
X1042241Y977625D03*
Y970932D03*
X1049683Y987664D03*
X1042241Y991011D03*
Y984318D03*
X1049683Y1027822D03*
Y1017782D03*
X1042241Y1031168D03*
Y1017782D03*
Y1024475D03*
X1049683Y1047900D03*
Y1041207D03*
Y1034515D03*
X1042241Y1044554D03*
Y1037861D03*
X1049683Y1061286D03*
Y1054593D03*
X1042241Y1057940D03*
Y1051247D03*
X1049683Y1074672D03*
Y1067979D03*
X1042241Y1078018D03*
Y1071326D03*
Y1064633D03*
X1049683Y1091404D03*
Y1084711D03*
X1042241Y1094751D03*
Y1088058D03*
X1049683Y1111483D03*
Y1104790D03*
Y1098097D03*
X1042241Y1108137D03*
Y1101444D03*
Y1114829D03*
X1049683Y1128215D03*
Y1121522D03*
X1042241Y1124869D03*
X1049683Y1141601D03*
Y1134908D03*
X1042241Y1144948D03*
Y1138255D03*
Y1131562D03*
Y1161680D03*
X1049683Y1158333D03*
Y1148294D03*
X1042241Y1151641D03*
X1049683Y1171719D03*
Y1165026D03*
X1042241Y1175066D03*
Y1168373D03*
X1049683Y1185105D03*
Y1178412D03*
X1042241Y1188452D03*
Y1181759D03*
X1049683Y1208530D03*
Y1201837D03*
Y1195144D03*
X1042241Y1205184D03*
Y1198491D03*
X1049683Y1215223D03*
Y1221916D03*
X1042241Y1225263D03*
Y1218570D03*
Y1211877D03*
X1049683Y1238648D03*
Y1231955D03*
X1042241Y1241995D03*
Y1235302D03*
X1042331Y1257488D03*
X1049683Y1245341D03*
X1042241Y1248688D03*
X1052588Y1273344D03*
X1039388D03*
X1063241Y770144D03*
X1058383Y766798D03*
X1063241Y783530D03*
Y776837D03*
X1058383Y780184D03*
Y773491D03*
X1063241Y800263D03*
Y793570D03*
X1058383Y803609D03*
Y796916D03*
Y790223D03*
X1063241Y820341D03*
Y813648D03*
Y806955D03*
X1058383Y816995D03*
Y810302D03*
X1063241Y830381D03*
X1058383Y833727D03*
Y827034D03*
X1063241Y850459D03*
Y843766D03*
Y837074D03*
X1058383Y847113D03*
Y840420D03*
X1063241Y867192D03*
Y857152D03*
X1058383Y863845D03*
Y853806D03*
X1063241Y880577D03*
Y873885D03*
X1058383Y883924D03*
Y877231D03*
Y870538D03*
X1063241Y893963D03*
Y887270D03*
X1058383Y900656D03*
Y890617D03*
X1063241Y917389D03*
Y910696D03*
Y904003D03*
X1058383Y914042D03*
Y907349D03*
X1063241Y930774D03*
Y924081D03*
X1058383Y927428D03*
Y920735D03*
X1063241Y947507D03*
Y940814D03*
X1058383Y944160D03*
Y937467D03*
X1063241Y964239D03*
Y954200D03*
X1058383Y960892D03*
Y950853D03*
X1063241Y977625D03*
Y970932D03*
X1058383Y980971D03*
Y974278D03*
Y967585D03*
X1063241Y991011D03*
Y984318D03*
X1058383Y987664D03*
X1063241Y1031168D03*
Y1024475D03*
Y1017782D03*
X1058383Y1027822D03*
Y1017782D03*
X1063241Y1044554D03*
Y1037861D03*
X1058383Y1047900D03*
Y1041207D03*
Y1034515D03*
X1063241Y1057940D03*
Y1051247D03*
X1058383Y1061286D03*
Y1054593D03*
X1063241Y1078018D03*
Y1071326D03*
Y1064633D03*
X1058383Y1074672D03*
Y1067979D03*
X1063241Y1094751D03*
Y1088058D03*
X1058383Y1091404D03*
Y1084711D03*
X1063241Y1108137D03*
Y1101444D03*
X1058383Y1111483D03*
Y1104790D03*
Y1098097D03*
X1063241Y1124869D03*
Y1114829D03*
X1058383Y1128215D03*
Y1121522D03*
X1063241Y1144948D03*
Y1138255D03*
Y1131562D03*
X1058383Y1141601D03*
Y1134908D03*
X1063241Y1161680D03*
Y1151641D03*
X1058383Y1158333D03*
Y1148294D03*
X1063241Y1175066D03*
Y1168373D03*
X1058383Y1171719D03*
Y1165026D03*
X1063241Y1188452D03*
Y1181759D03*
X1058383Y1185105D03*
Y1178412D03*
X1063241Y1205184D03*
Y1198491D03*
X1058383Y1208530D03*
Y1201837D03*
Y1195144D03*
X1063241Y1225263D03*
Y1218570D03*
Y1211877D03*
X1058383Y1215223D03*
Y1221916D03*
X1063241Y1241995D03*
Y1235302D03*
X1058383Y1238648D03*
Y1231955D03*
X1063241Y1248688D03*
X1058383Y1245341D03*
X1069088Y1273344D03*
X1066288D03*
X1055388D03*
X1079383Y766798D03*
X1071941Y770144D03*
X1079383Y780184D03*
Y773491D03*
X1071941Y783530D03*
Y776837D03*
X1079383Y803609D03*
Y796916D03*
Y790223D03*
X1071941Y800263D03*
Y793570D03*
X1079383Y816995D03*
Y810302D03*
X1071941Y820341D03*
Y813648D03*
Y806955D03*
X1079383Y833727D03*
Y827034D03*
X1071941Y830381D03*
X1079383Y847113D03*
Y840420D03*
X1071941Y850459D03*
Y843766D03*
Y837074D03*
X1079383Y863845D03*
Y853806D03*
X1071941Y867192D03*
Y857152D03*
X1079383Y883924D03*
Y877231D03*
Y870538D03*
X1071941Y880577D03*
Y873885D03*
X1079383Y900656D03*
Y890617D03*
X1071941Y893963D03*
Y887270D03*
X1079383Y914042D03*
Y907349D03*
X1071941Y917389D03*
Y910696D03*
Y904003D03*
X1079383Y927428D03*
Y920735D03*
X1071941Y930774D03*
Y924081D03*
X1079383Y944160D03*
Y937467D03*
X1071941Y947507D03*
Y940814D03*
X1079383Y960892D03*
Y950853D03*
X1071941Y964239D03*
Y954200D03*
X1079383Y980971D03*
Y974278D03*
Y967585D03*
X1071941Y977625D03*
Y970932D03*
X1079383Y987664D03*
X1071941Y991011D03*
Y984318D03*
X1079383Y1027822D03*
Y1017782D03*
X1071941Y1031168D03*
Y1024475D03*
Y1017782D03*
X1079383Y1047900D03*
Y1041207D03*
Y1034515D03*
X1071941Y1044554D03*
Y1037861D03*
X1079383Y1061286D03*
Y1054593D03*
X1071941Y1057940D03*
Y1051247D03*
X1079383Y1074672D03*
Y1067979D03*
X1071941Y1078018D03*
Y1071326D03*
Y1064633D03*
X1079383Y1091404D03*
Y1084711D03*
X1071941Y1094751D03*
Y1088058D03*
X1079383Y1111483D03*
Y1104790D03*
Y1098097D03*
X1071941Y1108137D03*
Y1101444D03*
X1079383Y1128215D03*
Y1121522D03*
X1071941Y1124869D03*
Y1114829D03*
X1079383Y1141601D03*
Y1134908D03*
X1071941Y1144948D03*
Y1138255D03*
Y1131562D03*
X1079383Y1158333D03*
Y1148294D03*
X1071941Y1161680D03*
Y1151641D03*
X1079383Y1171719D03*
Y1165026D03*
X1071941Y1175066D03*
Y1168373D03*
X1079383Y1185105D03*
Y1178412D03*
X1071941Y1188452D03*
Y1181759D03*
X1079383Y1208530D03*
Y1201837D03*
Y1195144D03*
X1071941Y1205184D03*
Y1198491D03*
X1079383Y1221916D03*
Y1215223D03*
X1071941Y1225263D03*
Y1218570D03*
Y1211877D03*
X1079383Y1238648D03*
Y1231955D03*
X1071941Y1241995D03*
Y1235302D03*
X1071991Y1257262D03*
X1079383Y1245341D03*
X1071941Y1248688D03*
X1085088Y1273344D03*
X1082288D03*
X1092941Y770144D03*
X1101641D03*
X1088083Y766798D03*
X1092941Y783530D03*
X1101641D03*
X1092941Y776837D03*
X1101641D03*
X1088083Y780184D03*
Y773491D03*
X1101641Y800263D03*
X1092941D03*
X1101641Y793570D03*
X1092941D03*
X1088083Y803609D03*
Y796916D03*
Y790223D03*
X1101641Y820341D03*
X1092941D03*
X1101641Y813648D03*
X1092941D03*
X1101641Y806955D03*
X1092941D03*
X1088083Y816995D03*
Y810302D03*
X1101641Y830381D03*
X1092941D03*
X1088083Y833727D03*
Y827034D03*
X1101641Y850459D03*
X1092941D03*
X1101641Y843766D03*
X1092941D03*
X1101641Y837074D03*
X1092941D03*
X1088083Y847113D03*
Y840420D03*
X1101641Y867192D03*
X1092941D03*
X1101641Y857152D03*
X1092941D03*
X1088083Y863845D03*
Y853806D03*
X1101641Y880577D03*
X1092941D03*
X1101641Y873885D03*
X1092941D03*
X1088083Y883924D03*
Y877231D03*
Y870538D03*
X1101641Y893963D03*
X1092941D03*
X1101641Y887270D03*
X1092941D03*
X1088083Y900656D03*
Y890617D03*
X1101641Y917389D03*
X1092941D03*
X1101641Y910696D03*
X1092941D03*
X1101641Y904003D03*
X1092941D03*
X1088083Y914042D03*
Y907349D03*
X1101641Y930774D03*
X1092941D03*
X1101641Y924081D03*
X1092941D03*
X1088083Y927428D03*
Y920735D03*
X1101641Y947507D03*
X1092941D03*
X1101641Y940814D03*
X1092941D03*
X1088083Y944160D03*
Y937467D03*
X1101641Y964239D03*
X1092941D03*
X1101641Y954200D03*
X1092941D03*
X1088083Y960892D03*
Y950853D03*
X1101641Y977625D03*
X1092941D03*
X1101641Y970932D03*
X1092941D03*
X1088083Y980971D03*
Y974278D03*
Y967585D03*
X1101641Y991011D03*
X1092941D03*
X1101641Y984318D03*
X1092941D03*
X1088083Y987664D03*
X1101641Y1031168D03*
X1092941D03*
X1101641Y1024475D03*
X1092941D03*
X1101641Y1017782D03*
X1092941D03*
X1088083Y1027822D03*
Y1017782D03*
X1101641Y1044554D03*
X1092941D03*
X1101641Y1037861D03*
X1092941D03*
X1088083Y1047900D03*
Y1041207D03*
Y1034515D03*
X1101641Y1057940D03*
X1092941D03*
X1101641Y1051247D03*
X1092941D03*
X1088083Y1061286D03*
Y1054593D03*
X1101641Y1078018D03*
X1092941D03*
X1101641Y1071326D03*
X1092941D03*
X1101641Y1064633D03*
X1092941D03*
X1088083Y1074672D03*
Y1067979D03*
X1101641Y1094751D03*
X1092941D03*
X1101641Y1088058D03*
X1092941D03*
X1088083Y1091404D03*
Y1084711D03*
X1101641Y1108137D03*
X1092941D03*
X1101641Y1101444D03*
X1092941D03*
X1088083Y1111483D03*
Y1104790D03*
Y1098097D03*
X1101641Y1124869D03*
X1092941D03*
X1101641Y1114829D03*
X1092941D03*
X1088083Y1128215D03*
Y1121522D03*
X1101641Y1144948D03*
X1092941D03*
X1101641Y1138255D03*
X1092941D03*
X1101641Y1131562D03*
X1092941D03*
X1088083Y1141601D03*
Y1134908D03*
X1092941Y1161680D03*
X1101641D03*
Y1151641D03*
X1092941D03*
X1088083Y1158333D03*
Y1148294D03*
X1101641Y1175066D03*
X1092941D03*
X1101641Y1168373D03*
X1092941D03*
X1088083Y1171719D03*
Y1165026D03*
X1101641Y1181759D03*
X1092941D03*
Y1188452D03*
X1101641D03*
X1088083Y1185105D03*
Y1178412D03*
X1092941Y1205184D03*
X1101641D03*
X1092941Y1198491D03*
X1101641D03*
X1088083Y1208530D03*
Y1201837D03*
Y1195144D03*
X1101641Y1225263D03*
X1092941D03*
X1101641Y1218570D03*
X1092941D03*
Y1211877D03*
X1101641D03*
X1088083Y1221916D03*
Y1215223D03*
X1101641Y1241995D03*
X1092941D03*
X1101641Y1235302D03*
X1092941D03*
X1088083Y1238648D03*
Y1231955D03*
X1101554Y1257102D03*
X1101641Y1248688D03*
X1092941D03*
X1088083Y1245341D03*
X1098788Y1273344D03*
X1095988D03*
X1109083Y766798D03*
X1117783D03*
Y780184D03*
X1109083D03*
X1117783Y773491D03*
X1109083D03*
X1117783Y803609D03*
X1109083D03*
X1117783Y796916D03*
X1109083D03*
Y790223D03*
X1117783D03*
Y816995D03*
X1109083D03*
X1117783Y810302D03*
X1109083D03*
X1117783Y833727D03*
X1109083D03*
X1117783Y827034D03*
X1109083D03*
X1117783Y847113D03*
X1109083D03*
X1117783Y840420D03*
X1109083D03*
X1117783Y863845D03*
X1109083D03*
X1117783Y853806D03*
X1109083D03*
X1117783Y883924D03*
X1109083D03*
X1117783Y877231D03*
X1109083D03*
X1117783Y870538D03*
X1109083D03*
X1117783Y900656D03*
X1109083D03*
X1117783Y890617D03*
X1109083D03*
X1117783Y914042D03*
X1109083D03*
X1117783Y907349D03*
X1109083D03*
X1117783Y927428D03*
X1109083D03*
X1117783Y920735D03*
X1109083D03*
X1117783Y944160D03*
X1109083D03*
X1117783Y937467D03*
X1109083D03*
X1117783Y960892D03*
X1109083D03*
X1117783Y950853D03*
X1109083D03*
X1117783Y980971D03*
X1109083D03*
X1117783Y974278D03*
X1109083D03*
X1117783Y967585D03*
X1109083D03*
X1117783Y987664D03*
X1109083D03*
X1117783Y1027822D03*
X1109083D03*
X1117783Y1017782D03*
X1109083D03*
X1117783Y1047900D03*
X1109083D03*
X1117783Y1041207D03*
X1109083D03*
X1117783Y1034515D03*
X1109083D03*
X1117783Y1061286D03*
X1109083D03*
X1117783Y1054593D03*
X1109083D03*
X1117783Y1074672D03*
X1109083D03*
X1117783Y1067979D03*
X1109083D03*
X1117783Y1091404D03*
X1109083D03*
X1117783Y1084711D03*
X1109083D03*
X1117783Y1111483D03*
X1109083D03*
X1117783Y1104790D03*
X1109083D03*
X1117783Y1098097D03*
X1109083D03*
X1117783Y1128215D03*
X1109083D03*
X1117783Y1121522D03*
X1109083D03*
X1117783Y1141601D03*
X1109083D03*
X1117783Y1134908D03*
X1109083D03*
X1117783Y1158333D03*
X1109083D03*
X1117783Y1148294D03*
X1109083D03*
X1117783Y1171719D03*
X1109083D03*
X1117783Y1165026D03*
X1109083D03*
X1117783Y1185105D03*
X1109083D03*
X1117783Y1178412D03*
X1109083D03*
X1117783Y1208530D03*
X1109083D03*
X1117783Y1201837D03*
X1109083D03*
X1117783Y1195144D03*
X1109083D03*
X1117783Y1221916D03*
X1109083D03*
X1117783Y1215223D03*
X1109083D03*
X1117783Y1238648D03*
X1109083D03*
X1117783Y1231955D03*
X1109083D03*
X1117783Y1245341D03*
X1109083D03*
X1111988Y1273344D03*
X1114788D03*
X1131341Y770144D03*
X1122641D03*
X1131341Y783530D03*
X1122641D03*
X1131341Y776837D03*
X1122641D03*
X1131341Y800263D03*
X1122641D03*
X1131341Y793570D03*
X1122641D03*
X1131341Y820341D03*
X1122641D03*
X1131341Y813648D03*
X1122641D03*
X1131341Y806955D03*
X1122641D03*
X1131341Y830381D03*
X1122641D03*
X1131341Y850459D03*
X1122641D03*
X1131341Y843766D03*
X1122641D03*
X1131341Y837074D03*
X1122641D03*
X1131341Y867192D03*
X1122641D03*
X1131341Y857152D03*
X1122641D03*
X1131341Y880577D03*
X1122641D03*
X1131341Y873885D03*
X1122641D03*
X1131341Y893963D03*
X1122641D03*
X1131341Y887270D03*
X1122641D03*
X1131341Y917389D03*
X1122641D03*
X1131341Y910696D03*
X1122641D03*
X1131341Y904003D03*
X1122641D03*
X1131341Y930774D03*
X1122641D03*
X1131341Y924081D03*
X1122641D03*
Y947507D03*
X1131341D03*
Y940814D03*
X1122641D03*
X1131341Y964239D03*
X1122641D03*
X1131341Y954200D03*
X1122641D03*
X1131341Y977625D03*
X1122641D03*
X1131341Y970932D03*
X1122641D03*
X1131341Y991011D03*
X1122641D03*
X1131341Y984318D03*
X1122641D03*
X1131341Y1031168D03*
X1122641D03*
X1131341Y1024475D03*
X1122641D03*
X1131341Y1017782D03*
X1122641D03*
X1131341Y1044554D03*
X1122641D03*
X1131341Y1037861D03*
X1122641D03*
X1131341Y1057940D03*
X1122641D03*
X1131341Y1051247D03*
X1122641D03*
X1131341Y1078018D03*
X1122641D03*
X1131341Y1071326D03*
X1122641D03*
X1131341Y1064633D03*
X1122641D03*
X1131341Y1094751D03*
X1122641D03*
X1131341Y1088058D03*
X1122641D03*
X1131341Y1108137D03*
X1122641D03*
X1131341Y1101444D03*
X1122641D03*
X1131341Y1124869D03*
X1122641D03*
X1131341Y1114829D03*
X1122641D03*
X1131341Y1144948D03*
X1122641D03*
X1131341Y1138255D03*
X1122641D03*
X1131341Y1131562D03*
X1122641D03*
X1131341Y1161680D03*
X1122641D03*
X1131341Y1151641D03*
X1122641D03*
X1131341Y1175066D03*
X1122641D03*
X1131341Y1168373D03*
X1122641D03*
X1131341Y1188452D03*
X1122641D03*
X1131341Y1181759D03*
X1122641D03*
X1131341Y1205184D03*
X1122641D03*
X1131341Y1198491D03*
X1122641D03*
X1131341Y1225263D03*
X1122641D03*
X1131341Y1218570D03*
X1122641D03*
X1131341Y1211877D03*
X1122641D03*
X1131341Y1241995D03*
X1122641D03*
X1131341Y1235302D03*
X1122641D03*
X1131434Y1257291D03*
X1122641Y1248688D03*
X1131341D03*
X1126188Y1273344D03*
X1128988D03*
X1152341Y770144D03*
X1147483Y766798D03*
X1138783D03*
X1152341Y783530D03*
Y776837D03*
X1147483Y780184D03*
X1138783D03*
Y773491D03*
X1147483D03*
X1152341Y800263D03*
X1147483Y803609D03*
X1138783D03*
X1152341Y793570D03*
X1147483Y796916D03*
X1138783D03*
X1147483Y790223D03*
X1138783D03*
X1152341Y820341D03*
X1147483Y816995D03*
X1138783D03*
X1152341Y813648D03*
Y806955D03*
X1147483Y810302D03*
X1138783D03*
X1147483Y833727D03*
X1138783D03*
X1152341Y830381D03*
X1147483Y827034D03*
X1138783D03*
X1152341Y850459D03*
Y843766D03*
Y837074D03*
X1147483Y847113D03*
X1138783D03*
X1147483Y840420D03*
X1138783D03*
X1152341Y867192D03*
Y857152D03*
X1147483Y863845D03*
X1138783D03*
X1147483Y853806D03*
X1138783D03*
X1152341Y880577D03*
Y873885D03*
X1147483Y883924D03*
X1138783D03*
X1147483Y877231D03*
X1138783D03*
X1147483Y870538D03*
X1138783D03*
X1152341Y893963D03*
Y887270D03*
X1138783Y900656D03*
X1147483D03*
X1138783Y890617D03*
X1147483D03*
X1152341Y917389D03*
Y910696D03*
Y904003D03*
X1147483Y914042D03*
X1138783D03*
X1147483Y907349D03*
X1138783D03*
X1152341Y930774D03*
Y924081D03*
X1147483Y927428D03*
X1138783D03*
X1147483Y920735D03*
X1138783D03*
X1152341Y947507D03*
Y940814D03*
X1147483Y944160D03*
X1138783D03*
X1147483Y937467D03*
X1138783D03*
X1152341Y964239D03*
Y954200D03*
X1147483Y960892D03*
X1138783D03*
X1147483Y950853D03*
X1138783D03*
X1152341Y977625D03*
Y970932D03*
X1147483Y980971D03*
X1138783D03*
X1147483Y974278D03*
X1138783D03*
X1147483Y967585D03*
X1138783D03*
X1152341Y991011D03*
Y984318D03*
X1147483Y987664D03*
X1138783D03*
X1152341Y1031168D03*
Y1024475D03*
Y1017782D03*
X1147483Y1027822D03*
X1138783D03*
X1147483Y1017782D03*
X1138783D03*
X1152341Y1044554D03*
Y1037861D03*
X1138783Y1047900D03*
X1147483D03*
Y1041207D03*
X1138783D03*
X1147483Y1034515D03*
X1138783D03*
X1152341Y1057940D03*
Y1051247D03*
X1147483Y1061286D03*
X1138783D03*
X1147483Y1054593D03*
X1138783D03*
X1152341Y1078018D03*
Y1071326D03*
Y1064633D03*
X1147483Y1074672D03*
X1138783D03*
X1147483Y1067979D03*
X1138783D03*
X1152341Y1094751D03*
Y1088058D03*
X1147483Y1091404D03*
X1138783D03*
X1147483Y1084711D03*
X1138783D03*
X1152341Y1108137D03*
Y1101444D03*
X1147483Y1111483D03*
X1138783D03*
X1147483Y1104790D03*
X1138783D03*
X1147483Y1098097D03*
X1138783D03*
X1152341Y1124869D03*
Y1114829D03*
X1147483Y1128215D03*
X1138783D03*
X1147483Y1121522D03*
X1138783D03*
X1152341Y1144948D03*
Y1138255D03*
Y1131562D03*
X1147483Y1141601D03*
X1138783D03*
X1147483Y1134908D03*
X1138783D03*
X1152341Y1161680D03*
Y1151641D03*
X1147483Y1158333D03*
X1138783D03*
Y1148294D03*
X1147483D03*
X1152341Y1175066D03*
Y1168373D03*
X1147483Y1171719D03*
X1138783D03*
X1147483Y1165026D03*
X1138783D03*
X1152341Y1188452D03*
Y1181759D03*
X1147483Y1185105D03*
X1138783D03*
X1147483Y1178412D03*
X1138783D03*
X1152341Y1205184D03*
Y1198491D03*
X1147483Y1208530D03*
X1138783D03*
X1147483Y1201837D03*
X1138783D03*
X1147483Y1195144D03*
X1138783D03*
X1152341Y1225263D03*
Y1218570D03*
Y1211877D03*
X1147483Y1221916D03*
X1138783D03*
X1147483Y1215223D03*
X1138783D03*
X1152341Y1241995D03*
Y1235302D03*
X1147483Y1238648D03*
X1138783D03*
X1147483Y1231955D03*
X1138783D03*
X1152341Y1248688D03*
X1147483Y1245341D03*
X1138783D03*
X1152381Y1269684D03*
X1147681D03*
X1138201Y1270277D03*
X1168483Y766798D03*
X1161041Y770144D03*
X1168483Y780184D03*
Y773491D03*
X1161041Y783530D03*
Y776837D03*
X1168483Y803609D03*
Y796916D03*
Y790223D03*
X1161041Y800263D03*
Y793570D03*
X1168483Y816995D03*
Y810302D03*
X1161041Y820341D03*
Y813648D03*
Y806955D03*
X1168483Y833727D03*
X1167633Y827034D03*
X1161041Y830381D03*
X1168483Y847113D03*
Y840420D03*
X1161041Y850459D03*
Y843766D03*
Y837074D03*
X1167633Y863845D03*
X1161041Y867192D03*
X1168483Y853806D03*
X1161041Y857152D03*
X1168483Y883924D03*
Y877231D03*
Y870538D03*
X1161041Y880577D03*
Y873885D03*
X1168483Y900656D03*
Y890617D03*
X1161041Y893963D03*
Y887270D03*
X1168483Y914042D03*
Y907349D03*
X1161041Y917389D03*
Y910696D03*
Y904003D03*
X1167633Y927428D03*
X1168483Y920735D03*
X1161041Y930774D03*
Y924081D03*
X1168483Y937467D03*
Y944160D03*
X1161041Y947507D03*
Y940814D03*
X1168483Y960892D03*
Y950853D03*
X1161041Y964239D03*
Y954200D03*
X1168483Y974278D03*
Y980971D03*
Y967585D03*
X1161041Y977625D03*
Y970932D03*
X1168483Y987664D03*
X1161041Y991011D03*
Y984318D03*
X1168483Y1027822D03*
Y1017782D03*
X1161041Y1031168D03*
Y1024475D03*
Y1017782D03*
X1168483Y1047900D03*
Y1041207D03*
Y1034515D03*
X1161041Y1044554D03*
Y1037861D03*
X1168483Y1054593D03*
Y1061286D03*
X1161041Y1057940D03*
Y1051247D03*
X1168483Y1074672D03*
Y1067979D03*
X1161041Y1078018D03*
Y1071326D03*
Y1064633D03*
X1168483Y1091404D03*
X1167633Y1084711D03*
X1161041Y1094751D03*
Y1088058D03*
X1168483Y1111483D03*
Y1104790D03*
Y1098097D03*
X1161041Y1108137D03*
Y1101444D03*
X1168483Y1128215D03*
Y1121522D03*
X1161041Y1124869D03*
Y1114829D03*
X1168483Y1141601D03*
Y1134908D03*
X1161041Y1144948D03*
Y1138255D03*
Y1131562D03*
X1167633Y1158333D03*
X1168483Y1148294D03*
X1161041Y1161680D03*
Y1151641D03*
X1168483Y1171719D03*
Y1165026D03*
X1161041Y1175066D03*
Y1168373D03*
X1168483Y1185105D03*
Y1178412D03*
X1161041Y1188452D03*
Y1181759D03*
X1168483Y1208530D03*
Y1201837D03*
Y1195144D03*
X1161041Y1205184D03*
Y1198491D03*
X1168483Y1221916D03*
Y1215223D03*
X1161041Y1225263D03*
Y1218570D03*
Y1211877D03*
X1168483Y1238648D03*
X1167633Y1231955D03*
X1161041Y1241995D03*
Y1235302D03*
X1161065Y1258871D03*
X1168483Y1245341D03*
X1161041Y1248688D03*
X1161781Y1269684D03*
X1182041Y770144D03*
X1177183Y766798D03*
X1182041Y783530D03*
Y776837D03*
X1177183Y780184D03*
Y773491D03*
X1182041Y800263D03*
Y793570D03*
X1177183Y803609D03*
Y796916D03*
Y790223D03*
X1182041Y813648D03*
Y806955D03*
X1181191Y820341D03*
X1177183Y816995D03*
Y810302D03*
X1181191Y830381D03*
X1177183Y833727D03*
Y827034D03*
X1182041Y850459D03*
Y837074D03*
Y843766D03*
X1177183Y847113D03*
Y840420D03*
X1181191Y867192D03*
X1177183Y863845D03*
X1181191Y857152D03*
X1177183Y853806D03*
X1182041Y873885D03*
Y880577D03*
X1177183Y883924D03*
Y877231D03*
Y870538D03*
X1182041Y893963D03*
Y887270D03*
X1177183Y900656D03*
Y890617D03*
X1182041Y917389D03*
Y910696D03*
Y904003D03*
X1177183Y914042D03*
Y907349D03*
X1181191Y930774D03*
Y924081D03*
X1177183Y927428D03*
Y920735D03*
X1182041Y940814D03*
Y947507D03*
X1177183Y937467D03*
Y944160D03*
X1182041Y964239D03*
Y954200D03*
X1177183Y960892D03*
Y950853D03*
X1182041Y970932D03*
Y977625D03*
X1177183Y974278D03*
Y980971D03*
Y967585D03*
X1182041Y991011D03*
Y984318D03*
X1177183Y987664D03*
X1182041Y1031168D03*
Y1017782D03*
Y1024475D03*
X1177183Y1027822D03*
Y1017782D03*
X1182041Y1044554D03*
Y1037861D03*
X1177183Y1047900D03*
Y1041207D03*
Y1034515D03*
X1182041Y1057940D03*
Y1051247D03*
X1177183Y1054593D03*
Y1061286D03*
X1181191Y1078018D03*
X1182041Y1071326D03*
Y1064633D03*
X1177183Y1074672D03*
Y1067979D03*
X1182041Y1094751D03*
X1181191Y1088058D03*
X1177183Y1091404D03*
Y1084711D03*
X1182041Y1101444D03*
Y1108137D03*
X1177183Y1111483D03*
Y1104790D03*
Y1098097D03*
X1182041Y1114829D03*
Y1124869D03*
X1177183Y1128215D03*
Y1121522D03*
X1182041Y1144948D03*
Y1138255D03*
Y1131562D03*
X1177183Y1141601D03*
Y1134908D03*
X1181191Y1161680D03*
Y1151641D03*
X1177183Y1158333D03*
Y1148294D03*
X1182041Y1168373D03*
Y1175066D03*
X1177183Y1171719D03*
Y1165026D03*
X1182041Y1188452D03*
Y1181759D03*
X1177183Y1185105D03*
Y1178412D03*
X1182041Y1205184D03*
Y1198491D03*
X1177183Y1208530D03*
Y1201837D03*
Y1195144D03*
X1181191Y1225263D03*
X1182041Y1211877D03*
Y1218570D03*
X1177183Y1221916D03*
Y1215223D03*
X1182041Y1241995D03*
X1181191Y1235302D03*
X1177183Y1238648D03*
Y1231955D03*
X1182041Y1248688D03*
X1177183Y1245341D03*
X1176867Y1270029D03*
X1198183Y766798D03*
X1190741Y770144D03*
X1198183Y780184D03*
Y773491D03*
X1190741Y783530D03*
Y776837D03*
X1198183Y803609D03*
Y796916D03*
Y790223D03*
X1190741Y800263D03*
Y793570D03*
X1197333Y816995D03*
X1198183Y810302D03*
X1190741Y813648D03*
Y806955D03*
X1191591Y820341D03*
X1198183Y833727D03*
X1197333Y827034D03*
X1191591Y830381D03*
X1198183Y847113D03*
Y840420D03*
X1190741Y850459D03*
Y837074D03*
Y843766D03*
X1197333Y863845D03*
X1191591Y867192D03*
X1198183Y853806D03*
X1191591Y857152D03*
X1198183Y877231D03*
X1197333Y870538D03*
X1198183Y883924D03*
X1190741Y873885D03*
Y880577D03*
X1198183Y900656D03*
Y890617D03*
X1190741Y893963D03*
Y887270D03*
X1198183Y914042D03*
Y907349D03*
X1190741Y917389D03*
Y910696D03*
Y904003D03*
X1197383Y927428D03*
X1198183Y920735D03*
X1191591Y930774D03*
Y924081D03*
X1198183Y944160D03*
X1197333Y937467D03*
X1190741Y940814D03*
Y947507D03*
X1198183Y960892D03*
Y950853D03*
X1190741Y964239D03*
Y954200D03*
X1198183Y980971D03*
Y974278D03*
Y967585D03*
X1190741Y970932D03*
Y977625D03*
X1198183Y987664D03*
X1190741Y991011D03*
Y984318D03*
X1198183Y1027822D03*
Y1017782D03*
X1190741Y1031168D03*
Y1017782D03*
Y1024475D03*
X1198183Y1047900D03*
Y1041207D03*
Y1034515D03*
X1190741Y1044554D03*
Y1037861D03*
X1198183Y1054593D03*
Y1061286D03*
X1190741Y1057940D03*
Y1051247D03*
X1197333Y1074672D03*
X1198183Y1067979D03*
X1191591Y1078018D03*
X1190741Y1071326D03*
Y1064633D03*
X1198183Y1091404D03*
X1197333Y1084711D03*
X1190741Y1094751D03*
X1191591Y1088058D03*
X1198183Y1111483D03*
Y1098097D03*
Y1104790D03*
X1190741Y1101444D03*
Y1108137D03*
X1198183Y1128215D03*
Y1121522D03*
X1190741Y1114829D03*
Y1124869D03*
X1198183Y1141601D03*
X1197333Y1134908D03*
X1190741Y1144948D03*
Y1138255D03*
Y1131562D03*
X1198183Y1158333D03*
X1197333Y1148294D03*
X1191591Y1161680D03*
Y1151641D03*
X1198183Y1165026D03*
Y1171719D03*
X1190741Y1168373D03*
Y1175066D03*
X1198183Y1185105D03*
Y1178412D03*
X1190741Y1188452D03*
Y1181759D03*
X1198183Y1208530D03*
Y1201837D03*
Y1195144D03*
X1190741Y1205184D03*
Y1198491D03*
X1198183Y1221916D03*
Y1215223D03*
X1191591Y1225263D03*
X1190741Y1211877D03*
Y1218570D03*
X1197333Y1238648D03*
Y1231955D03*
X1190741Y1241995D03*
X1191591Y1235302D03*
X1198183Y1245341D03*
X1190966Y1258711D03*
X1190741Y1248688D03*
X1191538Y1270004D03*
X1194572Y1578182D03*
Y1590094D03*
X1199872Y1614292D03*
Y1602380D03*
X1211741Y770144D03*
X1206883Y766798D03*
X1211741Y783530D03*
Y776837D03*
X1206883Y780184D03*
Y773491D03*
X1211741Y800263D03*
Y793570D03*
X1206883Y803609D03*
Y796916D03*
Y790223D03*
X1210891Y820341D03*
Y813648D03*
X1211741Y806955D03*
X1207148Y817554D03*
X1206883Y810302D03*
X1211741Y830381D03*
X1206883Y833727D03*
X1207733Y827034D03*
X1211741Y850459D03*
Y837074D03*
Y843766D03*
X1206883Y847113D03*
Y840420D03*
X1210891Y867492D03*
X1207733Y863845D03*
X1210891Y857152D03*
X1206883Y853806D03*
X1211741Y874185D03*
Y880577D03*
X1206883Y877231D03*
X1207201Y871084D03*
X1206883Y883924D03*
X1211741Y893963D03*
Y887270D03*
X1206883Y900656D03*
Y890617D03*
X1211741Y917389D03*
Y910696D03*
Y904003D03*
X1206883Y914042D03*
Y907349D03*
X1211741Y930774D03*
Y924081D03*
X1207683Y927428D03*
X1206883Y920735D03*
X1211741Y947507D03*
X1211001Y940814D03*
X1206883Y944660D03*
X1207733Y937467D03*
X1211741Y964239D03*
Y954200D03*
X1206883Y960892D03*
Y950853D03*
X1211741Y977625D03*
Y970932D03*
X1206883Y980971D03*
Y974278D03*
Y967585D03*
X1211741Y991011D03*
X1206883Y987664D03*
X1211741Y984318D03*
Y1031168D03*
X1206883Y1027822D03*
Y1017782D03*
X1211741D03*
Y1024475D03*
Y1044554D03*
Y1037861D03*
X1206883Y1047900D03*
Y1041207D03*
Y1034515D03*
X1211741Y1051247D03*
Y1057940D03*
X1206883Y1054593D03*
Y1061286D03*
X1210891Y1078018D03*
X1211741Y1064633D03*
Y1071326D03*
X1207733Y1074672D03*
X1206883Y1067979D03*
X1211741Y1094751D03*
X1210891Y1088058D03*
X1206883Y1091404D03*
Y1084711D03*
X1211741Y1108137D03*
Y1101444D03*
X1206883Y1111483D03*
Y1098097D03*
Y1104790D03*
X1210891Y1124869D03*
X1211741Y1114829D03*
X1206883Y1128215D03*
Y1121522D03*
X1211741Y1144948D03*
Y1138255D03*
X1210891Y1131562D03*
X1206883Y1141601D03*
X1207733Y1134908D03*
X1211741Y1151641D03*
Y1161680D03*
X1206883Y1158333D03*
X1207733Y1148294D03*
X1211741Y1175066D03*
Y1168373D03*
X1206883Y1165026D03*
Y1171719D03*
X1211741Y1188452D03*
Y1181759D03*
X1206883Y1185105D03*
Y1178412D03*
X1211741Y1205184D03*
Y1198491D03*
X1206883Y1208530D03*
Y1201837D03*
Y1195144D03*
X1210891Y1225263D03*
X1211741Y1218570D03*
Y1211877D03*
X1206883Y1221916D03*
Y1215223D03*
X1211741Y1241995D03*
X1211328Y1234977D03*
X1207733Y1238648D03*
Y1231955D03*
X1206883Y1245341D03*
X1211741Y1248688D03*
X1204608Y1273119D03*
X1202043Y1273123D03*
X1202372Y1578182D03*
X1214432D03*
X1206632D03*
X1202372Y1590094D03*
X1214432D03*
X1206632D03*
X1207672Y1602380D03*
Y1614292D03*
X1211932D03*
Y1602380D03*
X1227883Y766798D03*
X1220441Y770144D03*
X1227883Y780184D03*
Y773491D03*
X1220441Y783530D03*
Y776837D03*
X1227883Y803609D03*
Y796916D03*
Y790223D03*
X1220441Y800263D03*
Y793570D03*
X1227033Y816995D03*
X1227883Y810302D03*
X1221291Y820341D03*
Y813648D03*
X1220441Y806955D03*
X1227883Y833727D03*
X1227033Y827034D03*
X1220441Y830381D03*
X1227883Y847113D03*
Y840420D03*
X1220441Y850459D03*
Y837074D03*
Y843766D03*
X1227033Y863845D03*
X1221291Y867192D03*
X1227033Y853806D03*
X1221291Y857152D03*
X1227883Y870538D03*
Y883924D03*
Y877231D03*
X1220441Y873885D03*
Y880577D03*
X1227033Y900656D03*
X1227883Y890617D03*
X1220441Y893963D03*
Y887270D03*
X1227883Y914042D03*
Y907349D03*
X1220441Y917389D03*
Y910696D03*
Y904003D03*
X1227033Y927428D03*
X1227883Y920735D03*
X1221291Y930774D03*
X1220441Y924081D03*
X1227883Y944160D03*
X1227033Y937467D03*
X1220441Y947507D03*
X1221291Y940814D03*
X1227883Y960892D03*
Y950853D03*
X1220441Y964239D03*
Y954200D03*
X1227883Y974278D03*
Y967585D03*
X1220441Y977625D03*
Y970932D03*
X1227883Y980971D03*
Y987664D03*
X1220441Y991011D03*
Y984318D03*
X1227883Y1027822D03*
X1220441Y1031168D03*
X1227883Y1017782D03*
X1220441D03*
Y1024475D03*
X1227883Y1047900D03*
Y1041207D03*
Y1034515D03*
X1220441Y1044554D03*
Y1037861D03*
X1227883Y1061286D03*
Y1054593D03*
X1220441Y1051247D03*
Y1057940D03*
X1227033Y1074672D03*
Y1067979D03*
X1221291Y1078018D03*
X1220441Y1064633D03*
Y1071326D03*
X1227883Y1091404D03*
Y1084711D03*
X1220441Y1094751D03*
X1221291Y1088058D03*
X1227883Y1104790D03*
X1227033Y1111483D03*
X1227883Y1098097D03*
X1220441Y1108137D03*
Y1101444D03*
X1227883Y1128215D03*
X1227033Y1121522D03*
X1221291Y1124869D03*
X1220441Y1114829D03*
X1227883Y1134908D03*
Y1141601D03*
X1220441Y1144948D03*
Y1138255D03*
X1221291Y1131562D03*
X1227883Y1158333D03*
Y1148294D03*
X1220441Y1151641D03*
Y1161680D03*
X1227883Y1171719D03*
Y1165026D03*
X1220441Y1175066D03*
Y1168373D03*
X1227883Y1185105D03*
Y1178412D03*
X1220441Y1188452D03*
Y1181759D03*
X1227883Y1208530D03*
Y1201837D03*
X1227033Y1195144D03*
X1220441Y1205184D03*
Y1198491D03*
X1227033Y1221916D03*
X1227883Y1215223D03*
X1221291Y1225263D03*
X1220441Y1218570D03*
Y1211877D03*
X1227883Y1238648D03*
X1227033Y1231955D03*
X1220441Y1241995D03*
X1221291Y1235302D03*
X1220441Y1248688D03*
X1227883Y1245341D03*
X1220601Y1269684D03*
X1220931Y1260093D03*
X1233327Y1274515D03*
X1231377Y1275855D03*
X1218692Y1578182D03*
X1226492D03*
X1230752D03*
X1218692Y1590094D03*
X1226492D03*
X1230752D03*
X1219732Y1614292D03*
Y1602380D03*
X1231792Y1614292D03*
Y1602380D03*
X1223992D03*
Y1614292D03*
X1236583Y766798D03*
Y780184D03*
Y773491D03*
Y803609D03*
Y796916D03*
Y790223D03*
X1237433Y816995D03*
X1236583Y810302D03*
Y833727D03*
X1237433Y827034D03*
X1236583Y847113D03*
Y840420D03*
X1237433Y863845D03*
Y853806D03*
X1236583Y870538D03*
Y883924D03*
Y877231D03*
Y900656D03*
Y890617D03*
Y914042D03*
Y907349D03*
X1237433Y927428D03*
X1236583Y920735D03*
Y944160D03*
X1237433Y937467D03*
X1236583Y960892D03*
Y950853D03*
Y974278D03*
Y967585D03*
Y980971D03*
Y987664D03*
Y1027822D03*
Y1017782D03*
Y1047900D03*
Y1041207D03*
Y1034515D03*
Y1061286D03*
Y1054593D03*
X1237433Y1074672D03*
Y1067979D03*
X1236583Y1091404D03*
Y1084711D03*
Y1104790D03*
X1237433Y1111483D03*
X1236583Y1098097D03*
Y1128215D03*
X1237433Y1121522D03*
X1236583Y1134908D03*
Y1141601D03*
Y1158333D03*
Y1148294D03*
Y1171719D03*
Y1165026D03*
Y1185105D03*
Y1178412D03*
Y1208530D03*
Y1201837D03*
Y1195144D03*
X1237433Y1221916D03*
X1236583Y1215223D03*
Y1238648D03*
X1237433Y1231955D03*
X1236583Y1245341D03*
X1238552Y1578182D03*
X1242812D03*
X1238552Y1590094D03*
X1242812D03*
X1236052Y1602380D03*
Y1614292D03*
X1243852D03*
Y1602380D03*
X1248112D03*
Y1614292D03*
X1241142Y1675383D03*
Y1679920D03*
X1249016Y1679320D03*
X1241142Y1684454D03*
Y1689556D03*
Y1694093D03*
Y1698627D03*
X1249016Y1688391D03*
Y1693493D03*
Y1698030D03*
Y1683857D03*
X1241142Y1703729D03*
Y1708266D03*
Y1712800D03*
X1249016Y1707666D03*
Y1712203D03*
Y1702564D03*
X1241142Y1726974D03*
Y1722440D03*
Y1717903D03*
X1249016Y1730911D03*
Y1726377D03*
Y1721840D03*
Y1716737D03*
X1250612Y1578182D03*
X1262672D03*
X1254872D03*
X1250612Y1590094D03*
X1262672D03*
X1254872D03*
X1255912Y1614292D03*
Y1602380D03*
X1260172D03*
Y1614292D03*
X1256890Y1675383D03*
Y1679920D03*
X1264764Y1679320D03*
X1256890Y1684454D03*
Y1689556D03*
Y1694093D03*
Y1698627D03*
X1264764Y1688391D03*
Y1693493D03*
Y1698030D03*
Y1683857D03*
X1256890Y1703729D03*
Y1708266D03*
Y1712800D03*
X1264764Y1707666D03*
Y1712203D03*
Y1702564D03*
X1256890Y1726974D03*
Y1722440D03*
Y1717903D03*
X1264764Y1730911D03*
Y1726377D03*
Y1721840D03*
Y1716737D03*
X1266932Y1578182D03*
X1274732D03*
X1278992D03*
X1266932Y1590094D03*
X1274732D03*
X1278992D03*
X1267972Y1614292D03*
Y1602380D03*
X1272232D03*
Y1614292D03*
X1280032D03*
Y1602380D03*
X1272638Y1675383D03*
Y1679920D03*
X1280512Y1679320D03*
X1272638Y1684454D03*
Y1689556D03*
Y1694093D03*
Y1698627D03*
X1280512Y1688391D03*
Y1693493D03*
Y1698030D03*
Y1683857D03*
X1272638Y1703729D03*
Y1708266D03*
Y1712800D03*
X1280512Y1707666D03*
Y1712203D03*
Y1702564D03*
X1272638Y1726974D03*
Y1722440D03*
Y1717903D03*
X1280512Y1730911D03*
Y1726377D03*
Y1721840D03*
Y1716737D03*
X1286792Y1578182D03*
X1298852D03*
X1291052D03*
X1286792Y1590094D03*
X1298852D03*
X1291052D03*
X1284292Y1602380D03*
Y1614292D03*
X1292092D03*
Y1602380D03*
X1296352D03*
Y1614292D03*
X1296260Y1679320D03*
X1288386Y1675383D03*
Y1679920D03*
X1296260Y1688391D03*
Y1693493D03*
Y1698030D03*
Y1683857D03*
X1288386Y1684454D03*
Y1689556D03*
Y1694093D03*
Y1698627D03*
X1296260Y1707666D03*
Y1712203D03*
Y1702564D03*
X1288386Y1703729D03*
Y1708266D03*
Y1712800D03*
X1296260Y1730911D03*
Y1726377D03*
Y1721840D03*
Y1716737D03*
X1288386Y1726974D03*
Y1722440D03*
Y1717903D03*
X1314353Y1124651D03*
X1303112Y1578182D03*
X1310912D03*
X1315172D03*
X1303112Y1590094D03*
X1310912D03*
X1315172D03*
X1304152Y1602380D03*
Y1614292D03*
X1308412Y1602380D03*
Y1614292D03*
X1308071Y1675383D03*
Y1679920D03*
Y1684454D03*
Y1689556D03*
Y1694093D03*
Y1698627D03*
Y1703729D03*
Y1708266D03*
Y1712800D03*
Y1726974D03*
Y1722440D03*
Y1717903D03*
X1328721Y854584D03*
X1323171Y870606D03*
Y889832D03*
X1319849Y1091513D03*
X1318053Y1124651D03*
X1321753Y1131060D03*
X1322972Y1578182D03*
X1327232D03*
X1322972Y1590094D03*
X1327232D03*
X1316212Y1614292D03*
Y1602380D03*
X1328272D03*
Y1614292D03*
X1320472Y1602380D03*
Y1614292D03*
X1323819Y1675383D03*
Y1679920D03*
X1315945Y1679320D03*
X1323819Y1684454D03*
Y1689556D03*
Y1694093D03*
Y1698627D03*
X1315945Y1688391D03*
Y1693493D03*
Y1698030D03*
Y1683857D03*
X1323819Y1703729D03*
Y1708266D03*
Y1712800D03*
X1315945Y1707666D03*
Y1712203D03*
Y1702564D03*
X1323819Y1726974D03*
Y1722440D03*
Y1717903D03*
X1315945Y1730911D03*
Y1726377D03*
Y1721840D03*
Y1716737D03*
X1336121Y880219D03*
Y899445D03*
X1347220D03*
X1336121Y918670D03*
X1341671Y941100D03*
X1336121Y937896D03*
X1347220D03*
X1345804Y1006093D03*
X1342104Y1076587D03*
X1335032Y1578182D03*
X1347092D03*
X1339292D03*
X1335032Y1590094D03*
X1347092D03*
X1339292D03*
X1340332Y1602380D03*
Y1614292D03*
X1332532Y1602380D03*
Y1614292D03*
X1344592Y1602380D03*
Y1614292D03*
X1339567Y1675383D03*
Y1679920D03*
X1331693Y1679320D03*
X1347441D03*
X1339567Y1684454D03*
Y1689556D03*
Y1694093D03*
Y1698627D03*
X1331693Y1688391D03*
Y1693493D03*
Y1698030D03*
Y1683857D03*
X1347441Y1688391D03*
Y1693493D03*
Y1698030D03*
Y1683857D03*
X1339567Y1703729D03*
Y1708266D03*
Y1712800D03*
X1331693Y1707666D03*
Y1712203D03*
Y1702564D03*
X1347441Y1707666D03*
Y1712203D03*
Y1702564D03*
X1339567Y1726974D03*
Y1722440D03*
Y1717903D03*
X1331693Y1730911D03*
Y1726377D03*
Y1721840D03*
Y1716737D03*
X1347441Y1730911D03*
Y1726377D03*
Y1721840D03*
Y1716737D03*
X1354620Y931488D03*
X1355053Y1060565D03*
X1351352Y1578182D03*
X1359152D03*
X1363412D03*
X1351352Y1590094D03*
X1359152D03*
X1363412D03*
X1352392Y1602380D03*
Y1614292D03*
X1356652Y1602380D03*
Y1614292D03*
X1363189Y1679320D03*
X1355315Y1675383D03*
Y1679920D03*
X1363189Y1688391D03*
Y1693493D03*
Y1698030D03*
Y1683857D03*
X1355315Y1684454D03*
Y1689556D03*
Y1694093D03*
Y1698627D03*
X1363189Y1707666D03*
Y1712203D03*
Y1702564D03*
X1355315Y1703729D03*
Y1708266D03*
Y1712800D03*
X1363189Y1730911D03*
Y1726377D03*
Y1721840D03*
Y1716737D03*
X1355315Y1726974D03*
Y1722440D03*
Y1717903D03*
X1373120Y899445D03*
Y931488D03*
Y937896D03*
X1371212Y1578088D03*
X1375472Y1578182D03*
X1371212Y1590094D03*
X1375472D03*
X1364452Y1602380D03*
Y1614292D03*
X1376512Y1602286D03*
Y1614292D03*
X1368712Y1602380D03*
Y1614292D03*
X1393716Y985579D03*
X1391326D03*
Y1014539D03*
X1393716D03*
X1393903Y1115039D03*
X1392053Y1118243D03*
X1390203Y1121447D03*
X1388353Y1124651D03*
Y1118243D03*
X1390204Y1134264D03*
X1388354Y1131060D03*
X1383272Y1578182D03*
Y1590094D03*
X1380772Y1602380D03*
Y1614292D03*
X1388572D03*
Y1602380D03*
X1411971Y851380D03*
Y864197D03*
Y877014D03*
Y889832D03*
Y902649D03*
X1404571Y921875D03*
X1410121Y944304D03*
Y957122D03*
Y950713D03*
Y963530D03*
Y976347D03*
Y969939D03*
Y982756D03*
X1410553Y1009297D03*
Y1002888D03*
Y1028523D03*
Y1022114D03*
Y1015705D03*
X1405004Y1044544D03*
X1410553Y1034931D03*
X1406854Y1047749D03*
X1399453D03*
X1408703Y1050952D03*
X1401304Y1057361D03*
X1410553Y1060565D03*
Y1054157D03*
X1408703Y1076587D03*
X1406853Y1073383D03*
X1403153D03*
Y1066974D03*
X1401304Y1076587D03*
X1399453Y1066974D03*
X1410553Y1073383D03*
Y1066974D03*
X1403154Y1079791D03*
X1410553D03*
X1408703Y1089404D03*
Y1082995D03*
X1405003D03*
X1401304Y1089404D03*
X1410553Y1092608D03*
Y1086200D03*
X1408703Y1095813D03*
X1405003D03*
X1403153Y1099017D03*
X1401303Y1102221D03*
X1399453Y1105426D03*
X1397604Y1108630D03*
X1410553Y1105426D03*
X1399453Y1111834D03*
X1410553D03*
X1399453Y1124651D03*
Y1118243D03*
X1397604Y1115039D03*
X1410553Y1124651D03*
Y1118243D03*
X1399454Y1137469D03*
X1399453Y1131060D03*
X1410554Y1137769D03*
X1410553Y1131060D03*
X1426771Y851380D03*
Y877014D03*
X1413820Y912262D03*
X1423070Y941100D03*
X1423071Y947509D03*
Y960326D03*
Y953917D03*
Y966735D03*
Y979552D03*
Y973143D03*
X1423503Y1006093D03*
Y999684D03*
Y1012501D03*
Y1025318D03*
Y1018910D03*
Y1031727D03*
X1429053Y1041340D03*
X1423503Y1038136D03*
X1429053Y1092608D03*
X1427204Y1089404D03*
X1427203Y1095812D03*
X1429053Y1099017D03*
X1423503Y1108630D03*
Y1102221D03*
Y1121447D03*
Y1115039D03*
Y1127856D03*
Y1134264D03*
X1432320Y912262D03*
X1437871Y921875D03*
X1438402Y942151D03*
X1440702D03*
X1443002D03*
X1430564Y949138D03*
X1440015Y956539D03*
X1430564Y951438D03*
X1442413Y956539D03*
X1430534Y963828D03*
Y966128D03*
X1440015Y971139D03*
X1442413Y971099D03*
X1430404Y981208D03*
Y978908D03*
X1440015Y985579D03*
X1430604Y995298D03*
Y992998D03*
X1442413Y985579D03*
X1440015Y1014539D03*
Y1000059D03*
X1430584Y1009408D03*
Y1007108D03*
X1442413Y1014539D03*
Y1000059D03*
X1436454Y1105426D03*
X1434604Y1102221D03*
X1432753Y1099017D03*
X1440154Y1105426D03*
X1438304Y1108630D03*
X1440154Y1111834D03*
X1434604Y1121447D03*
Y1115039D03*
X1443854Y1124651D03*
X1443853Y1118243D03*
X1442004Y1121447D03*
Y1115039D03*
X1434604Y1127856D03*
Y1134264D03*
X1450820Y899445D03*
Y912262D03*
X1445703Y1115039D03*
X1447553Y1118243D03*
X1445704Y1127856D03*
X1445703Y1140973D03*
X1447554Y1137469D03*
Y1131060D03*
X1460095Y1578182D03*
Y1590094D03*
X1465620Y912262D03*
X1471604Y1108630D03*
X1469753Y1111834D03*
X1472155Y1578182D03*
X1467895D03*
X1472155Y1590094D03*
X1467895D03*
X1477455Y1602380D03*
Y1614292D03*
X1473195D03*
Y1602380D03*
X1465395D03*
Y1614292D03*
X1484120Y937896D03*
X1485971Y947509D03*
X1491953Y1086200D03*
X1492015Y1578182D03*
X1484215D03*
X1479955D03*
X1492015Y1590094D03*
X1484215D03*
X1479955D03*
X1489515Y1614292D03*
Y1602380D03*
X1485255D03*
Y1614292D03*
X1508335Y1578182D03*
X1496275D03*
X1504075D03*
X1508335Y1590094D03*
X1496275D03*
X1504075D03*
X1501575Y1614292D03*
Y1602380D03*
X1509375D03*
Y1614292D03*
X1497315Y1602380D03*
Y1614292D03*
X1505315Y1675383D03*
Y1679920D03*
Y1684454D03*
Y1689556D03*
Y1694093D03*
Y1698627D03*
Y1703729D03*
Y1708266D03*
Y1712800D03*
Y1726974D03*
Y1722440D03*
Y1717903D03*
X1511871Y928283D03*
X1519271D03*
X1515571D03*
X1524820Y925079D03*
X1513720D03*
X1524820Y944304D03*
X1513720D03*
X1520395Y1578182D03*
X1516135D03*
X1520395Y1590094D03*
X1516135D03*
X1525695Y1614292D03*
Y1602380D03*
X1521435D03*
Y1614292D03*
X1513635D03*
Y1602380D03*
X1521063Y1675383D03*
Y1679920D03*
X1513189Y1679320D03*
X1521063Y1684454D03*
Y1689556D03*
Y1694093D03*
Y1698627D03*
X1513189Y1688391D03*
Y1693493D03*
Y1698030D03*
Y1683857D03*
X1521063Y1703729D03*
Y1708266D03*
Y1712800D03*
X1513189Y1707666D03*
Y1712203D03*
Y1702564D03*
X1521063Y1726974D03*
Y1722440D03*
Y1717903D03*
X1513189Y1730911D03*
Y1726377D03*
Y1721840D03*
Y1716737D03*
X1540255Y1578182D03*
X1532455D03*
X1528195D03*
X1540255Y1590094D03*
X1532455D03*
X1528195D03*
X1537755Y1614292D03*
Y1602380D03*
X1533495D03*
Y1614292D03*
X1536811Y1675383D03*
Y1679920D03*
X1528937Y1679320D03*
X1536811Y1684454D03*
Y1689556D03*
Y1694093D03*
Y1698627D03*
X1528937Y1688391D03*
Y1693493D03*
Y1698030D03*
Y1683857D03*
X1536811Y1703729D03*
Y1708266D03*
Y1712800D03*
X1528937Y1707666D03*
Y1712203D03*
Y1702564D03*
X1536811Y1726974D03*
Y1722440D03*
Y1717903D03*
X1528937Y1730911D03*
Y1726377D03*
Y1721840D03*
Y1716737D03*
X1556575Y1578182D03*
X1544515D03*
X1552315D03*
X1556575Y1590094D03*
X1544515D03*
X1552315D03*
X1549815Y1614292D03*
Y1602380D03*
X1557615D03*
Y1614292D03*
X1545555Y1602380D03*
Y1614292D03*
X1552559Y1675383D03*
Y1679920D03*
X1544685Y1679320D03*
X1552559Y1684454D03*
Y1689556D03*
Y1694093D03*
Y1698627D03*
X1544685Y1688391D03*
Y1693493D03*
Y1698030D03*
Y1683857D03*
X1552559Y1703729D03*
Y1708266D03*
Y1712800D03*
X1544685Y1707666D03*
Y1712203D03*
Y1702564D03*
X1552559Y1726974D03*
Y1722440D03*
Y1717903D03*
X1544685Y1730911D03*
Y1726377D03*
Y1721840D03*
Y1716737D03*
X1568635Y1578182D03*
X1564375D03*
X1568635Y1590094D03*
X1564375D03*
X1573935Y1614292D03*
Y1602380D03*
X1569675Y1614292D03*
Y1602380D03*
X1561875Y1614292D03*
Y1602380D03*
X1560433Y1679320D03*
X1572244Y1675383D03*
Y1679920D03*
X1560433Y1688391D03*
Y1693493D03*
Y1698030D03*
Y1683857D03*
X1572244Y1684454D03*
Y1689556D03*
Y1694093D03*
Y1698627D03*
X1560433Y1707666D03*
Y1712203D03*
Y1702564D03*
X1572244Y1703729D03*
Y1708266D03*
Y1712800D03*
X1560433Y1730911D03*
Y1726377D03*
Y1721840D03*
Y1716737D03*
X1572244Y1726974D03*
Y1722440D03*
Y1717903D03*
X1588495Y1578182D03*
X1580695D03*
X1576435D03*
X1588495Y1590094D03*
X1580695D03*
X1576435D03*
X1585995Y1614292D03*
Y1602380D03*
X1581735D03*
Y1614292D03*
X1587992Y1675383D03*
Y1679920D03*
X1580118Y1679320D03*
X1587992Y1684454D03*
Y1689556D03*
Y1694093D03*
Y1698627D03*
X1580118Y1688391D03*
Y1693493D03*
Y1698030D03*
Y1683857D03*
X1587992Y1703729D03*
Y1708266D03*
Y1712800D03*
X1580118Y1707666D03*
Y1712203D03*
Y1702564D03*
X1587992Y1726974D03*
Y1722440D03*
Y1717903D03*
X1580118Y1730911D03*
Y1726377D03*
Y1721840D03*
Y1716737D03*
X1597041Y770144D03*
X1605741D03*
Y776837D03*
X1597041D03*
X1605741Y783530D03*
X1597041D03*
X1605741Y793570D03*
X1597041D03*
X1596988Y800263D03*
X1605741D03*
X1595774Y806955D03*
X1606934D03*
X1596218Y813648D03*
X1606735D03*
X1597041Y820341D03*
X1605741D03*
X1597041Y830381D03*
X1605741D03*
Y837074D03*
X1597041D03*
Y843766D03*
X1605741D03*
X1596147Y850459D03*
X1606896D03*
X1596200Y857152D03*
X1606623D03*
X1597041Y867192D03*
X1605741D03*
X1597041Y873885D03*
X1605741D03*
X1597041Y880577D03*
X1605741D03*
X1597041Y887270D03*
X1605741D03*
X1606898Y893963D03*
X1597041D03*
X1605741Y904003D03*
X1597041D03*
Y917389D03*
X1605741D03*
X1597041Y910696D03*
X1605741D03*
X1597041Y924081D03*
X1605741D03*
X1606541Y930697D03*
X1596047Y930774D03*
X1596106Y940814D03*
X1606919D03*
X1605741Y947507D03*
X1597041D03*
X1605741Y954200D03*
X1597041D03*
Y964239D03*
X1605741D03*
X1597041Y977625D03*
X1605741D03*
Y970932D03*
X1597041D03*
Y984318D03*
X1605741D03*
X1597041Y991011D03*
X1605741D03*
X1597041Y1024475D03*
X1605741D03*
X1597041Y1017782D03*
X1605741D03*
X1597041Y1031168D03*
X1605741D03*
X1597041Y1037861D03*
X1605741D03*
X1597041Y1044554D03*
X1605741D03*
Y1051247D03*
X1597041D03*
Y1057940D03*
X1605741D03*
X1597041Y1064633D03*
X1605741D03*
X1606541Y1071326D03*
X1596141D03*
X1597041Y1078018D03*
X1605741D03*
Y1094751D03*
X1597041D03*
Y1088058D03*
X1605741D03*
Y1101444D03*
X1597041D03*
Y1108137D03*
X1605741D03*
X1606541Y1114829D03*
X1596241D03*
X1596511Y1124969D03*
X1606505Y1124674D03*
X1605741Y1138255D03*
X1597041D03*
X1605741Y1144948D03*
X1597041D03*
Y1131562D03*
X1605741D03*
Y1151641D03*
X1597041D03*
X1596653Y1161680D03*
X1605975Y1161581D03*
X1605741Y1168373D03*
X1597041D03*
X1605741Y1175066D03*
X1597041D03*
X1605741Y1181759D03*
X1597041D03*
X1606765Y1188452D03*
X1597041D03*
Y1198491D03*
X1605741D03*
Y1205184D03*
X1597041D03*
Y1211877D03*
X1605741D03*
X1597041Y1218570D03*
X1605741D03*
X1597041Y1225263D03*
X1605741D03*
X1607064Y1235302D03*
X1596178D03*
X1605741Y1241995D03*
X1597041D03*
Y1248688D03*
X1605741D03*
X1603788Y1273144D03*
X1601388D03*
X1604815Y1578182D03*
X1592755D03*
X1600555D03*
X1604815Y1590094D03*
X1592755D03*
X1600555D03*
X1598055Y1614292D03*
Y1602380D03*
X1605855Y1614292D03*
Y1602380D03*
X1593795Y1614292D03*
Y1602380D03*
X1603740Y1675383D03*
Y1679920D03*
X1595866Y1679320D03*
X1603740Y1684454D03*
Y1689556D03*
Y1694093D03*
Y1698627D03*
X1595866Y1688391D03*
Y1693493D03*
Y1698030D03*
Y1683857D03*
X1603740Y1703729D03*
Y1708266D03*
Y1712800D03*
X1595866Y1707666D03*
Y1712203D03*
Y1702564D03*
X1603740Y1726974D03*
Y1722440D03*
Y1717903D03*
X1595866Y1730911D03*
Y1726377D03*
Y1721840D03*
Y1716737D03*
X1613183Y766798D03*
X1621883D03*
Y773491D03*
X1613183D03*
X1621883Y780184D03*
X1613183D03*
X1621883Y790223D03*
X1613183D03*
Y796916D03*
X1621883D03*
X1613183Y803609D03*
X1621883D03*
X1622916Y816995D03*
X1613183D03*
X1612363Y810302D03*
X1622986D03*
X1613183Y827034D03*
X1621883D03*
Y833727D03*
X1613183D03*
Y840420D03*
X1621883D03*
X1613183Y847113D03*
X1621943D03*
X1622060Y863845D03*
X1612408D03*
X1612474Y853955D03*
X1622961Y853806D03*
X1621883Y883924D03*
X1613183D03*
Y870538D03*
X1621883D03*
X1613183Y877231D03*
X1621883D03*
X1613183Y890617D03*
X1621883D03*
X1613183Y900656D03*
X1621883D03*
Y907349D03*
X1613183D03*
Y914042D03*
X1621883D03*
Y920735D03*
X1613183D03*
X1622535Y927526D03*
X1612168Y927428D03*
X1622845Y937467D03*
X1612312D03*
X1621883Y944160D03*
X1613183D03*
X1621883Y950853D03*
X1613183D03*
X1621883Y960892D03*
X1613183D03*
Y974278D03*
X1621883D03*
X1613183Y980971D03*
X1621883D03*
X1613183Y967585D03*
X1621883D03*
X1613183Y987664D03*
X1621883D03*
Y1017782D03*
X1613183D03*
Y1027822D03*
X1621883D03*
X1613183Y1034515D03*
X1621883D03*
X1613183Y1041207D03*
X1621883D03*
X1613183Y1047900D03*
X1621883D03*
Y1054593D03*
X1613183D03*
Y1061286D03*
X1621883D03*
Y1067979D03*
X1612983D03*
X1612283Y1074672D03*
X1622683D03*
X1621883Y1084711D03*
X1612383D03*
X1613183Y1091404D03*
X1621883D03*
Y1104790D03*
X1613183D03*
X1621883Y1098097D03*
X1613183D03*
X1621883Y1111483D03*
X1613183D03*
Y1128915D03*
X1621883Y1128215D03*
X1613183Y1121522D03*
X1621883D03*
Y1141601D03*
X1613183D03*
X1622726Y1135108D03*
X1611886Y1134908D03*
X1621883Y1158333D03*
X1613183D03*
X1621883Y1148294D03*
X1613183D03*
X1621883Y1165026D03*
X1613183D03*
Y1171719D03*
X1621883D03*
Y1178412D03*
X1613183D03*
X1621883Y1185105D03*
X1613183D03*
Y1195144D03*
X1621883D03*
Y1201837D03*
X1613183D03*
X1621883Y1208530D03*
X1613183D03*
X1621883Y1215223D03*
X1613183D03*
X1612147Y1221916D03*
X1622712D03*
X1612137Y1231862D03*
X1622681Y1231955D03*
X1621883Y1238648D03*
X1613183D03*
X1610150Y1257172D03*
X1621883Y1245341D03*
X1613183D03*
X1618888Y1273344D03*
X1616088D03*
X1616875Y1578182D03*
X1612615D03*
X1616875Y1590094D03*
X1612615D03*
X1622175Y1614292D03*
Y1602380D03*
X1617915Y1614292D03*
Y1602380D03*
X1610115Y1614292D03*
Y1602380D03*
X1619488Y1675383D03*
Y1679920D03*
X1611614Y1679320D03*
X1619488Y1684454D03*
Y1689556D03*
Y1694093D03*
Y1698627D03*
X1611614Y1688391D03*
Y1693493D03*
Y1698030D03*
Y1683857D03*
X1619488Y1703729D03*
Y1708266D03*
Y1712800D03*
X1611614Y1707666D03*
Y1712203D03*
Y1702564D03*
X1619488Y1726974D03*
Y1722440D03*
Y1717903D03*
X1611614Y1730911D03*
Y1726377D03*
Y1721840D03*
Y1716737D03*
X1626741Y770144D03*
X1635441D03*
X1626741Y776837D03*
X1635441D03*
X1626741Y783530D03*
X1635441D03*
X1626741Y793570D03*
X1635441D03*
Y800263D03*
X1626741D03*
X1636341Y820341D03*
X1626741D03*
X1636574Y813648D03*
X1626741D03*
X1635441Y806955D03*
X1626741D03*
X1635441Y830381D03*
X1626741D03*
X1635441Y837074D03*
X1626741D03*
Y843766D03*
X1635441D03*
Y850459D03*
X1626741D03*
X1625705Y867192D03*
X1636441D03*
X1635441Y857152D03*
X1626741D03*
Y880577D03*
X1635441D03*
Y873885D03*
X1626741D03*
Y887270D03*
X1635441D03*
X1626741Y893963D03*
X1635441D03*
X1626741Y904003D03*
X1635441D03*
Y910696D03*
X1626741D03*
X1635441Y917389D03*
X1626741D03*
X1636316Y930774D03*
X1625803D03*
X1636646Y924081D03*
X1626741D03*
X1635441Y940814D03*
X1626741D03*
X1635441Y947507D03*
X1626741D03*
X1635441Y954200D03*
X1626741D03*
Y964239D03*
X1635441D03*
Y977625D03*
X1626741D03*
X1635441Y970932D03*
X1626741D03*
X1635441Y984318D03*
X1626741D03*
Y991011D03*
X1635441D03*
Y1024475D03*
X1626741D03*
X1635441Y1017782D03*
X1626741D03*
X1635441Y1031168D03*
X1626741D03*
X1635441Y1037861D03*
X1626741D03*
X1635441Y1044554D03*
X1626741D03*
Y1057940D03*
X1635441D03*
Y1051247D03*
X1626741D03*
X1635441Y1064633D03*
X1626741D03*
X1635441Y1071326D03*
X1626741D03*
X1636241Y1078018D03*
X1625941D03*
Y1088058D03*
X1636241D03*
X1635441Y1094751D03*
X1626741D03*
Y1101444D03*
X1635441D03*
X1626741Y1108137D03*
X1635441D03*
X1626074Y1124640D03*
X1636341Y1124869D03*
X1635441Y1114829D03*
X1626741D03*
X1635441Y1144948D03*
X1626741D03*
X1635441Y1138255D03*
X1626741D03*
X1635441Y1130762D03*
X1626741D03*
Y1161680D03*
X1635441D03*
Y1151641D03*
X1626741D03*
Y1168373D03*
X1635441D03*
X1626741Y1175066D03*
X1635441D03*
X1626741Y1181759D03*
X1635441D03*
X1626741Y1188452D03*
X1635441D03*
X1626741Y1198491D03*
X1635441D03*
X1626741Y1205184D03*
X1635441D03*
Y1211877D03*
X1626741D03*
X1635441Y1218570D03*
X1626741D03*
X1636212Y1225263D03*
X1626055D03*
X1636376Y1235302D03*
X1625843D03*
X1635441Y1241995D03*
X1626741D03*
X1635688Y1257664D03*
X1626741Y1248688D03*
X1635441D03*
X1629788Y1273344D03*
X1632588D03*
X1625729Y1266766D03*
X1636735Y1578088D03*
X1628935Y1578182D03*
X1624675D03*
X1636735Y1590094D03*
X1628935D03*
X1624675D03*
X1634235Y1614292D03*
Y1602380D03*
X1629975Y1614292D03*
Y1602380D03*
X1627362Y1679320D03*
Y1688391D03*
Y1693493D03*
Y1698030D03*
Y1683857D03*
Y1707666D03*
Y1712203D03*
Y1702564D03*
Y1730911D03*
Y1726377D03*
Y1721840D03*
Y1716737D03*
X1651583Y766798D03*
X1642883D03*
X1656441Y770144D03*
Y776837D03*
X1642883Y773491D03*
X1651583D03*
X1642883Y780184D03*
X1651583D03*
X1656441Y783530D03*
Y793570D03*
X1642883Y790223D03*
X1651583D03*
X1642883Y796916D03*
X1651583D03*
X1656441Y800263D03*
X1651583Y803609D03*
X1642883D03*
X1656441Y806955D03*
Y813648D03*
Y820341D03*
X1651583Y810302D03*
X1642883D03*
X1652545Y816995D03*
X1641945D03*
X1656441Y830381D03*
X1652767Y827034D03*
X1642018D03*
X1651583Y833727D03*
X1642883D03*
X1656441Y837074D03*
Y843766D03*
X1642883Y840420D03*
X1651583D03*
X1656441Y850459D03*
X1651583Y847113D03*
X1642883D03*
X1642058Y863845D03*
X1652742D03*
X1656441Y857152D03*
Y867192D03*
X1652559Y853806D03*
X1642032D03*
X1656441Y873885D03*
Y880577D03*
X1642883Y883924D03*
X1651583D03*
Y870538D03*
X1642883D03*
X1651583Y877231D03*
X1642883D03*
X1656441Y887270D03*
Y893963D03*
X1642883Y890617D03*
X1651583D03*
X1642883Y900656D03*
X1651583D03*
X1656441Y904003D03*
Y910696D03*
X1642883Y907349D03*
X1651583D03*
X1656441Y917389D03*
X1651583Y914042D03*
X1642883D03*
X1656441Y924081D03*
Y930774D03*
X1652630Y927428D03*
X1642038D03*
X1651583Y920735D03*
X1642883D03*
X1656441Y940814D03*
Y947507D03*
X1652501Y937467D03*
X1642065D03*
X1651583Y944160D03*
X1642883D03*
X1656441Y954200D03*
X1642883Y950853D03*
X1651583D03*
Y960892D03*
X1642883D03*
X1656441Y964239D03*
Y977625D03*
Y970932D03*
X1651583Y967585D03*
X1642883D03*
X1651583Y974278D03*
X1642883D03*
X1651583Y980971D03*
X1642883D03*
X1656441Y984318D03*
Y991011D03*
X1651583Y987664D03*
X1642883D03*
X1651583Y1017782D03*
X1642883D03*
X1656441D03*
Y1024475D03*
X1651583Y1027822D03*
X1642883D03*
X1656441Y1031168D03*
Y1044554D03*
Y1037861D03*
X1651583Y1034515D03*
X1642883D03*
X1651583Y1041207D03*
X1642883D03*
X1651583Y1047900D03*
X1642883D03*
Y1061286D03*
X1651583D03*
X1656441Y1051247D03*
Y1057940D03*
X1651583Y1054593D03*
X1642883D03*
X1656441Y1064633D03*
Y1071326D03*
Y1078018D03*
X1652483Y1074672D03*
X1641983D03*
X1651583Y1067979D03*
X1642883D03*
X1656441Y1088058D03*
Y1094751D03*
X1652383Y1084711D03*
X1642083D03*
X1651583Y1091404D03*
X1642883D03*
X1656441Y1101444D03*
Y1108137D03*
X1642883Y1098097D03*
X1651583D03*
X1642883Y1104790D03*
X1651583D03*
X1642883Y1111483D03*
X1651583D03*
X1656441Y1114829D03*
Y1124869D03*
X1642883Y1121522D03*
X1651583D03*
X1642883Y1128215D03*
X1651583D03*
X1656441Y1131562D03*
Y1138255D03*
X1642883Y1134908D03*
X1651583D03*
X1642883Y1141601D03*
X1651583D03*
X1656441Y1144948D03*
Y1151641D03*
Y1161680D03*
X1652383Y1158333D03*
X1642083D03*
X1652794Y1148294D03*
X1641744D03*
X1656441Y1168373D03*
Y1175066D03*
X1642883Y1171719D03*
X1651583D03*
Y1165026D03*
X1642883D03*
X1656441Y1181759D03*
Y1188452D03*
X1651583Y1178412D03*
X1642883D03*
X1651583Y1185105D03*
X1642883D03*
X1656441Y1198491D03*
Y1205184D03*
X1642883Y1195144D03*
X1651583D03*
X1642883Y1201837D03*
X1651583D03*
X1642883Y1208530D03*
X1651583D03*
X1656441Y1211877D03*
X1652590Y1221916D03*
X1641793D03*
X1656441Y1225263D03*
Y1218570D03*
X1651583Y1215223D03*
X1642883D03*
X1656441Y1235302D03*
Y1241995D03*
X1652604Y1231955D03*
X1642054D03*
X1651583Y1238648D03*
X1642883D03*
X1656441Y1248688D03*
X1651583Y1245341D03*
X1642883D03*
X1648588Y1273344D03*
X1645788D03*
X1640995Y1578182D03*
X1648795D03*
X1640995Y1590094D03*
X1648795D03*
X1646295Y1614292D03*
Y1602380D03*
X1654095Y1614292D03*
Y1602380D03*
X1642035Y1614292D03*
Y1602286D03*
X1665141Y770144D03*
X1672583Y766798D03*
X1665141Y776837D03*
Y783530D03*
X1672583Y773491D03*
Y780184D03*
X1665141Y793570D03*
Y800263D03*
X1672583Y790223D03*
Y796916D03*
Y803609D03*
X1665141Y806955D03*
Y813648D03*
X1666030Y820341D03*
X1672583Y810302D03*
Y816995D03*
X1665141Y830381D03*
X1672583Y827034D03*
Y833727D03*
X1665141Y837074D03*
Y843766D03*
X1672583Y840420D03*
X1665141Y850459D03*
X1672583Y847113D03*
X1666038Y857152D03*
X1665141Y867192D03*
X1672583Y853806D03*
Y863845D03*
X1665141Y873885D03*
Y880577D03*
X1672583Y870538D03*
Y877231D03*
Y883924D03*
X1665141Y887270D03*
Y893963D03*
X1672583Y890617D03*
Y900656D03*
X1665141Y904003D03*
Y910696D03*
Y917389D03*
X1672583Y907349D03*
Y914042D03*
X1665141Y924081D03*
X1666246Y930774D03*
X1672583Y920735D03*
Y927428D03*
X1665141Y940814D03*
Y947507D03*
X1672583Y937467D03*
Y944160D03*
X1665141Y954200D03*
Y964239D03*
X1672583Y950853D03*
Y960892D03*
X1665141Y977625D03*
Y970932D03*
X1672583Y967585D03*
Y974278D03*
Y980971D03*
X1665141Y984318D03*
Y991011D03*
X1672583Y987664D03*
X1665141Y1017782D03*
Y1024475D03*
Y1031168D03*
X1672583Y1017782D03*
Y1027822D03*
X1665141Y1044554D03*
Y1037861D03*
X1672583Y1034515D03*
Y1041207D03*
Y1047900D03*
X1665141Y1057940D03*
X1672583Y1061286D03*
Y1054593D03*
X1665141Y1064633D03*
Y1071326D03*
Y1077118D03*
X1672583Y1067979D03*
Y1074672D03*
X1665141Y1088058D03*
Y1094751D03*
X1672583Y1084711D03*
Y1091404D03*
X1665141Y1101444D03*
Y1108137D03*
X1672583Y1098097D03*
Y1104790D03*
Y1111483D03*
X1665141Y1114829D03*
Y1124869D03*
X1672583Y1121522D03*
Y1128215D03*
X1665141Y1131562D03*
Y1138255D03*
Y1144948D03*
X1672583Y1134908D03*
Y1141601D03*
X1666141Y1151641D03*
X1665141Y1161680D03*
X1672583Y1148294D03*
Y1158333D03*
X1665141Y1168373D03*
Y1175066D03*
X1672583Y1165026D03*
Y1171719D03*
X1665141Y1181759D03*
Y1188452D03*
X1672583Y1178412D03*
Y1185105D03*
X1665141Y1198491D03*
Y1205184D03*
X1672583Y1195144D03*
Y1201837D03*
Y1208530D03*
X1665141Y1211877D03*
X1665941Y1225263D03*
X1665141Y1218570D03*
X1672583Y1215223D03*
Y1221916D03*
X1665141Y1235302D03*
Y1241995D03*
X1672583Y1231955D03*
Y1238648D03*
X1665141Y1248688D03*
X1672583Y1245341D03*
X1665688Y1257964D03*
X1659488Y1273344D03*
X1662288D03*
X1681283Y766798D03*
X1686141Y770144D03*
X1681283Y773491D03*
Y780184D03*
X1686141Y776837D03*
Y783530D03*
X1681283Y790223D03*
Y796916D03*
Y803609D03*
X1686141Y793570D03*
Y800263D03*
X1681283Y810302D03*
Y816995D03*
X1686141Y806955D03*
Y813648D03*
Y820341D03*
X1681283Y827034D03*
Y833727D03*
X1686141Y830381D03*
X1681283Y840420D03*
X1686141Y837074D03*
Y843766D03*
Y850459D03*
X1681283Y847113D03*
X1686141Y857152D03*
Y867192D03*
X1681283Y853806D03*
Y863845D03*
X1686141Y873885D03*
Y880577D03*
X1681283Y870538D03*
Y877231D03*
Y883924D03*
X1686141Y887270D03*
Y893963D03*
X1681283Y890617D03*
Y900656D03*
X1686141Y904003D03*
Y910696D03*
Y917389D03*
X1681283Y907349D03*
Y914042D03*
X1686141Y924081D03*
Y930774D03*
X1681283Y920735D03*
Y927428D03*
X1686141Y940814D03*
Y947507D03*
X1681283Y937467D03*
Y944160D03*
X1686141Y954200D03*
Y964239D03*
X1681283Y950853D03*
Y960892D03*
X1686141Y970932D03*
Y977625D03*
X1681283Y967585D03*
Y974278D03*
Y980971D03*
X1686141Y984318D03*
Y991011D03*
X1681283Y987664D03*
X1686141Y1017782D03*
Y1024475D03*
Y1031168D03*
X1681283Y1017782D03*
Y1027822D03*
X1686141Y1037861D03*
Y1044554D03*
X1681283Y1034515D03*
Y1041207D03*
Y1047900D03*
X1686141Y1051247D03*
Y1057940D03*
X1681283Y1061286D03*
Y1054593D03*
X1686141Y1064633D03*
Y1071326D03*
Y1078018D03*
X1681283Y1067979D03*
Y1074672D03*
X1686141Y1088058D03*
Y1094751D03*
X1681283Y1084711D03*
Y1091404D03*
X1686141Y1101444D03*
Y1108137D03*
X1681283Y1098097D03*
Y1104790D03*
Y1111483D03*
X1686141Y1114829D03*
Y1124869D03*
X1681283Y1121522D03*
Y1128215D03*
X1686141Y1131562D03*
Y1138255D03*
Y1144948D03*
X1681283Y1134908D03*
Y1141601D03*
X1686141Y1151641D03*
Y1161680D03*
X1681283Y1148294D03*
Y1158333D03*
X1686141Y1168373D03*
Y1175066D03*
X1681283Y1165026D03*
Y1171719D03*
X1686141Y1181759D03*
Y1188452D03*
X1681283Y1178412D03*
Y1185105D03*
X1686141Y1198491D03*
Y1205184D03*
X1681283Y1195144D03*
Y1201837D03*
Y1208530D03*
X1686141Y1211877D03*
Y1218570D03*
Y1225263D03*
X1681283Y1215223D03*
Y1221916D03*
Y1231955D03*
Y1238648D03*
X1686141Y1235302D03*
Y1241995D03*
X1681283Y1245341D03*
X1686141Y1248688D03*
X1675488Y1273344D03*
X1678288D03*
X1689188D03*
X1694841Y770144D03*
X1702283Y766798D03*
X1694841Y776837D03*
Y783530D03*
X1702283Y773491D03*
Y780184D03*
X1694841Y793570D03*
Y800263D03*
X1702283Y790223D03*
Y796916D03*
Y803609D03*
X1694841Y806955D03*
Y813648D03*
Y820341D03*
X1702283Y810302D03*
Y816995D03*
X1694841Y830381D03*
X1702283Y827034D03*
Y833727D03*
X1694841Y837074D03*
Y843766D03*
Y850459D03*
X1702283Y840420D03*
Y847113D03*
X1694841Y857152D03*
Y867192D03*
X1702283Y853806D03*
Y863845D03*
X1694841Y873885D03*
Y880577D03*
X1702283Y870538D03*
Y877231D03*
Y883924D03*
X1694841Y887270D03*
Y893963D03*
X1702283Y890617D03*
Y900656D03*
X1694841Y904003D03*
Y910696D03*
Y917389D03*
X1702283Y907349D03*
Y914042D03*
X1694841Y924081D03*
Y930774D03*
X1702283Y920735D03*
Y927428D03*
X1694841Y940814D03*
Y947507D03*
X1702283Y937467D03*
Y944160D03*
X1694841Y954200D03*
Y964239D03*
X1702283Y950853D03*
Y960892D03*
X1694841Y970932D03*
Y977625D03*
X1702283Y967585D03*
Y974278D03*
Y980971D03*
X1694841Y984318D03*
Y991011D03*
X1702283Y987664D03*
X1694841Y1017782D03*
Y1024475D03*
Y1031168D03*
X1702283Y1017782D03*
Y1027822D03*
X1694841Y1037861D03*
Y1044554D03*
X1702283Y1034515D03*
Y1041207D03*
Y1047900D03*
X1694841Y1051247D03*
Y1057940D03*
X1702283Y1054593D03*
Y1061286D03*
X1694841Y1064633D03*
Y1071326D03*
Y1078018D03*
X1702283Y1067979D03*
Y1074672D03*
X1694841Y1088058D03*
Y1094751D03*
X1702283Y1084711D03*
Y1091404D03*
X1694841Y1101444D03*
Y1108137D03*
X1702283Y1098097D03*
Y1104790D03*
Y1111483D03*
X1694841Y1114829D03*
Y1124869D03*
X1702283Y1121522D03*
Y1128215D03*
X1694841Y1131562D03*
Y1138255D03*
Y1144948D03*
X1702283Y1134908D03*
Y1141601D03*
X1694841Y1151641D03*
Y1161680D03*
X1702283Y1148294D03*
Y1158333D03*
X1694841Y1168373D03*
Y1175066D03*
X1702283Y1165026D03*
Y1171719D03*
X1694841Y1181759D03*
Y1188452D03*
X1702283Y1178412D03*
Y1185105D03*
X1694841Y1198491D03*
Y1205184D03*
X1702283Y1195144D03*
Y1201837D03*
Y1208530D03*
X1694841Y1211877D03*
Y1218570D03*
Y1225263D03*
X1702283Y1215223D03*
Y1221916D03*
X1694841Y1235302D03*
Y1241995D03*
X1702283Y1231955D03*
Y1238648D03*
X1694841Y1248688D03*
X1695188Y1257064D03*
X1702283Y1245341D03*
X1691988Y1273344D03*
X1705188D03*
X1710983Y766798D03*
X1715841Y770144D03*
X1710983Y773491D03*
Y780184D03*
X1715841Y783530D03*
Y776837D03*
X1710983Y790223D03*
Y796916D03*
Y803609D03*
X1715841Y793570D03*
Y800263D03*
X1710983Y810302D03*
Y816995D03*
X1715841Y806955D03*
Y813648D03*
Y820341D03*
X1710983Y827034D03*
Y833727D03*
X1715841Y830381D03*
X1710983Y840420D03*
Y847113D03*
X1715841Y837074D03*
Y843766D03*
Y850459D03*
X1710983Y853806D03*
Y863845D03*
X1715841Y857152D03*
Y867192D03*
X1710983Y870538D03*
Y877231D03*
Y883924D03*
X1715841Y873885D03*
Y880577D03*
X1710983Y890617D03*
Y900656D03*
X1715841Y893963D03*
Y887270D03*
X1710983Y907349D03*
Y914042D03*
X1715841Y904003D03*
Y910696D03*
Y917389D03*
X1710983Y920735D03*
Y927428D03*
X1715841Y924081D03*
Y930774D03*
X1710983Y937467D03*
Y944160D03*
X1715841Y940814D03*
Y947507D03*
X1710983Y950853D03*
Y960892D03*
X1715841Y954200D03*
Y964239D03*
X1710983Y967585D03*
Y974278D03*
Y980971D03*
X1715841Y970932D03*
Y977625D03*
X1710983Y987664D03*
X1715841Y984318D03*
Y991011D03*
X1710983Y1017782D03*
Y1027822D03*
X1715841Y1017782D03*
Y1024475D03*
Y1031168D03*
X1710983Y1034515D03*
Y1041207D03*
Y1047900D03*
X1715841Y1037861D03*
Y1044554D03*
X1710983Y1054593D03*
Y1061286D03*
X1715841Y1051247D03*
Y1057940D03*
X1710983Y1067979D03*
Y1074672D03*
X1715841Y1071326D03*
Y1064633D03*
Y1078018D03*
X1710983Y1084711D03*
Y1091404D03*
X1715841Y1088058D03*
Y1094751D03*
X1710983Y1098097D03*
Y1104790D03*
Y1111483D03*
X1715841Y1101444D03*
Y1108137D03*
X1710983Y1121522D03*
Y1128215D03*
X1715841Y1114829D03*
Y1124869D03*
X1710983Y1134908D03*
Y1141601D03*
X1715841Y1131562D03*
Y1138255D03*
Y1144948D03*
X1710983Y1148294D03*
Y1158333D03*
X1715841Y1151641D03*
Y1161680D03*
X1710983Y1165026D03*
Y1171719D03*
X1715841Y1168373D03*
Y1175066D03*
X1710983Y1178412D03*
Y1185105D03*
X1715841Y1181759D03*
Y1188452D03*
X1710983Y1195144D03*
Y1201837D03*
Y1208530D03*
X1715841Y1198491D03*
Y1205184D03*
X1710983Y1215223D03*
Y1221916D03*
X1715841Y1211877D03*
Y1218570D03*
Y1225263D03*
X1710983Y1231955D03*
Y1238648D03*
X1715841Y1235302D03*
Y1241995D03*
X1710983Y1245341D03*
X1715841Y1248688D03*
X1707514Y1273444D03*
X1718888Y1273344D03*
X1721688D03*
X1731983Y766798D03*
X1724541Y770144D03*
X1731983Y773491D03*
Y780184D03*
X1724541Y783530D03*
Y776837D03*
Y793570D03*
Y800263D03*
X1731983Y790223D03*
Y796916D03*
Y803609D03*
X1724541Y806955D03*
Y813648D03*
Y820341D03*
X1731983Y810302D03*
Y816995D03*
X1724541Y830381D03*
X1731983Y827034D03*
Y833727D03*
X1724541Y837074D03*
Y843766D03*
Y850459D03*
X1731983Y840420D03*
Y847113D03*
X1724541Y857152D03*
Y867192D03*
X1731983Y853806D03*
Y863845D03*
X1724541Y873885D03*
Y880577D03*
X1731983Y870538D03*
Y877231D03*
Y883924D03*
X1724541Y893963D03*
Y887270D03*
X1731983Y890617D03*
Y900656D03*
X1724541Y904003D03*
Y910696D03*
Y917389D03*
X1731983Y907349D03*
Y914042D03*
X1724541Y924081D03*
Y930774D03*
X1731983Y920735D03*
Y927428D03*
X1724541Y940814D03*
Y947507D03*
X1731983Y937467D03*
Y944160D03*
X1724541Y954200D03*
Y964239D03*
X1731983Y950853D03*
Y960892D03*
X1724541Y970932D03*
Y977625D03*
X1731983Y967585D03*
Y974278D03*
Y980971D03*
X1724541Y984318D03*
Y991011D03*
X1731983Y987664D03*
X1724541Y1017782D03*
Y1024475D03*
Y1031168D03*
X1731983Y1017782D03*
Y1027822D03*
X1724541Y1037861D03*
Y1044554D03*
X1731983Y1034515D03*
Y1041207D03*
Y1047900D03*
X1724541Y1057940D03*
X1731983Y1054593D03*
Y1061286D03*
X1724541Y1071326D03*
Y1064633D03*
Y1078018D03*
X1731983Y1074672D03*
Y1067979D03*
X1724541Y1088058D03*
Y1094751D03*
X1731983Y1084711D03*
Y1091404D03*
X1724541Y1101444D03*
Y1108137D03*
X1731983Y1098097D03*
Y1104790D03*
Y1111483D03*
X1724541Y1114829D03*
Y1124869D03*
X1731983Y1121522D03*
Y1128215D03*
X1724541Y1131562D03*
Y1138255D03*
Y1144948D03*
X1731983Y1134908D03*
Y1141601D03*
X1724541Y1151641D03*
Y1161680D03*
X1731983Y1148294D03*
Y1158333D03*
X1724541Y1168373D03*
Y1175066D03*
X1731983Y1165026D03*
Y1171719D03*
X1724541Y1181759D03*
Y1188452D03*
X1731983Y1178412D03*
Y1185105D03*
X1724541Y1198491D03*
Y1205184D03*
X1731983Y1195144D03*
Y1201837D03*
Y1208530D03*
X1724541Y1211877D03*
Y1218570D03*
Y1225263D03*
X1731983Y1215223D03*
Y1221916D03*
X1724541Y1235302D03*
Y1241995D03*
X1731983Y1231955D03*
Y1238648D03*
X1724541Y1248688D03*
X1724588Y1257164D03*
X1731983Y1245341D03*
X1734888Y1273344D03*
X1737688D03*
X1740683Y766798D03*
X1745541Y770144D03*
X1754241D03*
X1740683Y773491D03*
Y780184D03*
X1745541Y776837D03*
X1754241D03*
X1745541Y783530D03*
X1754241D03*
X1740683Y790223D03*
Y796916D03*
Y803609D03*
X1745541Y793570D03*
X1754241D03*
X1745541Y800263D03*
X1754241D03*
X1740683Y810302D03*
Y816995D03*
X1745541Y806955D03*
X1754241D03*
X1745541Y813648D03*
X1754241D03*
X1745541Y820341D03*
X1754241D03*
X1740683Y827034D03*
Y833727D03*
X1745541Y830381D03*
X1754241D03*
X1740683Y840420D03*
Y847113D03*
X1754241Y843766D03*
X1745541D03*
Y837074D03*
X1754241D03*
X1745541Y850459D03*
X1754241D03*
X1740683Y853806D03*
Y863845D03*
X1745541Y857152D03*
X1754241D03*
Y867192D03*
X1745541D03*
X1740683Y870538D03*
Y877231D03*
Y883924D03*
X1745541Y873885D03*
X1754241D03*
X1745541Y880577D03*
X1754241D03*
X1740683Y890617D03*
Y900656D03*
X1754241Y893963D03*
X1745541D03*
Y887270D03*
X1754241D03*
X1740683Y907349D03*
Y914042D03*
X1754241Y904003D03*
X1745541D03*
X1754241Y910696D03*
X1745541D03*
X1754241Y917389D03*
X1745541D03*
X1740683Y920735D03*
Y927428D03*
X1754241Y924081D03*
X1745541D03*
X1754241Y930774D03*
X1745541D03*
X1740683Y937467D03*
Y944160D03*
X1754241Y940814D03*
X1745541D03*
X1754241Y947507D03*
X1745541D03*
X1740683Y950853D03*
Y960892D03*
X1754241Y954200D03*
X1745541D03*
X1754241Y964239D03*
X1745541D03*
X1740683Y967585D03*
Y974278D03*
Y980971D03*
X1754241Y970932D03*
X1745541D03*
X1754241Y977625D03*
X1745541D03*
X1740683Y987664D03*
X1754241Y984318D03*
X1745541D03*
X1754241Y991011D03*
X1745541D03*
X1740683Y1017782D03*
Y1027822D03*
X1754241Y1017782D03*
X1745541D03*
Y1024475D03*
X1754241D03*
X1745541Y1031168D03*
X1754241D03*
X1740683Y1034515D03*
Y1041207D03*
Y1047900D03*
X1754241Y1044554D03*
X1745541D03*
Y1037861D03*
X1754241D03*
X1740683Y1054593D03*
Y1061286D03*
X1745541Y1051247D03*
X1754241D03*
X1745541Y1057940D03*
X1754241D03*
X1740683Y1074672D03*
Y1067979D03*
X1754241Y1071326D03*
X1745541D03*
Y1064633D03*
X1754241D03*
Y1078018D03*
X1745541D03*
X1740683Y1084711D03*
Y1091404D03*
X1754241Y1088058D03*
X1745541D03*
X1754241Y1094751D03*
X1745541D03*
X1740683Y1098097D03*
Y1104790D03*
Y1111483D03*
X1754241Y1101444D03*
X1745541D03*
X1754241Y1108137D03*
X1745541D03*
X1740683Y1121522D03*
Y1128215D03*
X1754241Y1114829D03*
X1745541D03*
X1754241Y1124869D03*
X1745541D03*
X1740683Y1134908D03*
Y1141601D03*
X1754241Y1131562D03*
X1745541D03*
X1754241Y1138255D03*
X1745541D03*
X1754241Y1144948D03*
X1745541D03*
X1740683Y1148294D03*
Y1158333D03*
X1754241Y1151641D03*
X1745541D03*
X1754241Y1161680D03*
X1745541D03*
X1740683Y1165026D03*
Y1171719D03*
X1745541Y1175066D03*
X1754241D03*
Y1168373D03*
X1745541D03*
X1740683Y1178412D03*
Y1185105D03*
X1745541Y1181759D03*
X1754241D03*
Y1188452D03*
X1745541D03*
X1740683Y1195144D03*
Y1201837D03*
Y1208530D03*
X1754241Y1198491D03*
X1745541D03*
X1754241Y1205184D03*
X1745541D03*
X1740683Y1215223D03*
Y1221916D03*
X1754241Y1211877D03*
X1745541D03*
X1754241Y1218570D03*
X1745541D03*
X1754241Y1225263D03*
X1745541D03*
X1740683Y1231955D03*
Y1238648D03*
X1754241Y1235302D03*
X1745541D03*
X1754241Y1241995D03*
X1745541D03*
X1740683Y1245341D03*
X1754241Y1248688D03*
X1745541D03*
X1754488Y1257264D03*
X1751388Y1273344D03*
X1748588D03*
X1749088Y1310474D03*
X1746288D03*
X1770383Y766798D03*
X1761683D03*
X1770383Y773491D03*
X1761683D03*
Y780184D03*
X1770383D03*
X1761683Y790223D03*
X1770383D03*
X1761683Y796916D03*
X1770383D03*
X1761683Y803609D03*
X1770383D03*
X1761683Y810302D03*
X1770383D03*
X1761683Y816995D03*
X1770383D03*
X1761683Y827034D03*
X1770383D03*
X1761683Y833727D03*
X1770383D03*
X1761683Y840420D03*
X1770383D03*
X1761683Y847113D03*
X1770383D03*
X1761683Y853806D03*
X1770383D03*
X1761683Y863845D03*
X1770383D03*
X1761683Y870538D03*
X1770383D03*
X1761683Y877231D03*
X1770383D03*
X1761683Y883924D03*
X1770383D03*
X1761683Y890617D03*
X1770383D03*
X1761683Y900656D03*
X1770383D03*
X1761683Y907349D03*
X1770383D03*
X1761683Y914042D03*
X1770383D03*
Y927428D03*
X1761683D03*
Y920735D03*
X1770383D03*
X1761683Y937467D03*
X1770383D03*
X1761683Y944160D03*
X1770383D03*
X1761683Y950853D03*
X1770383D03*
X1761683Y960892D03*
X1770383D03*
X1761683Y967585D03*
X1770383D03*
X1761683Y974278D03*
X1770383D03*
X1761683Y980971D03*
X1770383D03*
X1761683Y987664D03*
X1770383D03*
X1761683Y1017782D03*
X1770383D03*
X1761683Y1027822D03*
X1770383D03*
X1761683Y1034515D03*
X1770383D03*
X1761683Y1041207D03*
X1770383D03*
X1761683Y1047900D03*
X1770383D03*
X1761683Y1054593D03*
X1770383D03*
X1761683Y1061286D03*
X1770383D03*
X1761683Y1067979D03*
X1770383D03*
X1761683Y1074672D03*
X1770383D03*
X1761683Y1084711D03*
X1770383D03*
X1761683Y1091404D03*
X1770383D03*
Y1098097D03*
X1761683D03*
Y1104790D03*
X1770383D03*
X1761683Y1111483D03*
X1770383D03*
X1761683Y1121522D03*
X1770383D03*
X1761683Y1128215D03*
X1770383D03*
X1761683Y1134908D03*
X1770383D03*
X1761683Y1141601D03*
X1770383D03*
X1761683Y1148294D03*
X1770383D03*
X1761683Y1158333D03*
X1770383D03*
X1761683Y1165026D03*
X1770383D03*
X1761683Y1171719D03*
X1770383D03*
X1761683Y1178412D03*
X1770383D03*
X1761683Y1185105D03*
X1770383D03*
X1761683Y1195144D03*
X1770383D03*
X1761683Y1201837D03*
X1770383D03*
X1761683Y1208530D03*
X1770383D03*
X1761683Y1215223D03*
X1770383D03*
X1761683Y1221916D03*
X1770383D03*
X1761683Y1231955D03*
X1770383D03*
X1761683Y1238648D03*
X1770383D03*
X1761683Y1245341D03*
X1770383D03*
X1767388Y1273344D03*
X1764588D03*
X1775241Y770144D03*
X1783941D03*
X1775241Y776837D03*
X1783941D03*
X1775241Y783530D03*
X1783941D03*
X1775241Y793570D03*
X1783941D03*
X1775241Y800263D03*
X1783941D03*
X1775241Y806955D03*
X1783941D03*
X1775241Y813648D03*
X1783941D03*
X1775241Y820341D03*
X1783941D03*
Y830381D03*
X1775241D03*
Y837074D03*
X1783941D03*
X1775241Y843766D03*
X1783941D03*
X1775241Y850459D03*
X1783941D03*
X1775241Y857152D03*
X1783941D03*
X1775241Y867192D03*
X1783941D03*
X1775241Y873885D03*
X1783941D03*
X1775241Y880577D03*
X1783941D03*
X1775241Y887270D03*
X1783941D03*
X1775241Y893963D03*
X1783941D03*
X1775241Y904003D03*
X1783941D03*
X1775241Y910696D03*
X1783941D03*
X1775241Y917389D03*
X1783941D03*
X1775241Y924081D03*
X1783941D03*
X1775241Y930774D03*
X1783941D03*
X1775241Y940814D03*
X1783941D03*
X1775241Y947507D03*
X1783941D03*
X1775241Y954200D03*
X1783941D03*
X1775241Y964239D03*
X1783941D03*
X1775241Y970932D03*
X1783941D03*
X1775241Y977625D03*
X1783941D03*
X1775241Y984318D03*
X1783941D03*
X1775241Y991011D03*
X1783941D03*
X1775241Y1017782D03*
X1783941D03*
X1775241Y1024475D03*
X1783941D03*
X1775241Y1031168D03*
X1783941D03*
X1775241Y1037861D03*
X1783941D03*
X1775241Y1044554D03*
X1783941D03*
X1775241Y1051247D03*
X1783941D03*
X1775241Y1057940D03*
X1783941D03*
X1775241Y1064633D03*
X1783941D03*
X1775241Y1071326D03*
X1783941D03*
X1775241Y1078018D03*
X1783941D03*
X1775241Y1088058D03*
X1783941D03*
X1775241Y1094751D03*
X1783941D03*
X1775241Y1101444D03*
X1783941D03*
X1775241Y1108137D03*
X1783941D03*
X1775241Y1114829D03*
X1783941D03*
X1775241Y1124869D03*
X1783941D03*
X1775241Y1131562D03*
X1783941D03*
X1775241Y1138255D03*
X1783941D03*
X1775241Y1144948D03*
X1783941D03*
Y1151641D03*
X1775241D03*
Y1161680D03*
X1783941D03*
X1775241Y1168373D03*
X1783941D03*
X1775241Y1175066D03*
X1783941D03*
X1775241Y1181759D03*
X1783941D03*
X1775241Y1188452D03*
X1783941D03*
X1775241Y1198491D03*
X1783941D03*
X1775241Y1205184D03*
X1783941D03*
X1775241Y1211877D03*
X1783941D03*
X1775241Y1218570D03*
X1783941D03*
X1775241Y1225263D03*
X1783941D03*
X1775241Y1235302D03*
X1783941D03*
X1775241Y1241995D03*
X1783941D03*
X1784188Y1257664D03*
X1775241Y1248688D03*
X1783941D03*
X1781088Y1273344D03*
X1778288D03*
X1791383Y766798D03*
X1800083D03*
X1791383Y773491D03*
X1800083D03*
X1791383Y780184D03*
X1800083D03*
X1791383Y790223D03*
X1800083D03*
X1791383Y796916D03*
X1800083D03*
X1791383Y803609D03*
X1800083D03*
X1791383Y810302D03*
X1800083D03*
X1791383Y816995D03*
X1800083D03*
X1791383Y827034D03*
X1800083D03*
Y833727D03*
X1791383D03*
Y840420D03*
X1800083D03*
X1791383Y847113D03*
X1800083D03*
X1791383Y853806D03*
X1800083D03*
X1791383Y863845D03*
X1800083D03*
X1791383Y870538D03*
X1800083D03*
X1791383Y877231D03*
X1800083D03*
X1791383Y883924D03*
X1800083D03*
X1791383Y890617D03*
X1800083D03*
X1791383Y900656D03*
X1800083D03*
X1791383Y907349D03*
X1800083D03*
X1791383Y914042D03*
X1800083D03*
X1791383Y920735D03*
X1800083D03*
X1791383Y927428D03*
X1800083D03*
X1791383Y937467D03*
X1800083D03*
X1791383Y944160D03*
X1800083D03*
Y950853D03*
X1791383D03*
Y960892D03*
X1800083D03*
X1791383Y967585D03*
X1800083D03*
X1791383Y974278D03*
X1800083D03*
X1791383Y980971D03*
X1800083D03*
X1791383Y987664D03*
X1800083D03*
X1791383Y1017782D03*
X1800083D03*
X1791383Y1027822D03*
X1800083D03*
X1791383Y1034515D03*
X1800083D03*
X1791383Y1041207D03*
X1800083D03*
X1791383Y1047900D03*
X1800083D03*
X1791383Y1054593D03*
X1800083D03*
X1791383Y1061286D03*
X1800083D03*
X1791383Y1067979D03*
X1800083D03*
X1791383Y1074672D03*
X1800083D03*
X1791383Y1084711D03*
X1800083D03*
X1791383Y1091404D03*
X1800083D03*
X1791383Y1098097D03*
X1800083D03*
X1791383Y1104790D03*
X1800083D03*
X1791383Y1111483D03*
X1800083D03*
X1791383Y1121522D03*
X1800083D03*
X1791383Y1128215D03*
X1800083D03*
Y1134908D03*
X1791383D03*
Y1141601D03*
X1800083D03*
X1791383Y1148294D03*
X1800083D03*
X1791383Y1158333D03*
X1800083D03*
X1791383Y1165026D03*
X1800083D03*
X1791383Y1171719D03*
X1800083D03*
X1791383Y1178412D03*
X1800083D03*
X1791383Y1185105D03*
X1800083D03*
X1791383Y1195144D03*
X1800083D03*
X1791383Y1201837D03*
X1800083D03*
X1791383Y1208530D03*
X1800083D03*
X1791383Y1215223D03*
X1800083D03*
X1791383Y1221916D03*
X1800083D03*
X1791383Y1231955D03*
X1800083D03*
X1791383Y1238648D03*
X1800083D03*
X1791383Y1245341D03*
X1800083D03*
X1797088Y1273344D03*
X1794288D03*
X1804941Y770144D03*
X1813641D03*
X1804941Y776837D03*
X1813641D03*
X1804941Y783530D03*
X1813641D03*
X1804941Y793570D03*
X1813641D03*
X1804941Y800263D03*
X1813641D03*
X1804941Y806955D03*
X1813641D03*
X1804941Y813648D03*
X1813641D03*
X1804941Y820341D03*
X1813641D03*
X1804941Y830381D03*
X1813641D03*
X1804941Y843766D03*
X1813641D03*
X1804941Y837074D03*
X1813641D03*
X1804941Y850459D03*
X1813641D03*
X1804941Y857152D03*
X1813641D03*
Y867192D03*
X1804941D03*
Y873885D03*
X1813641D03*
X1804941Y880577D03*
X1813641D03*
X1804941Y887270D03*
X1813641D03*
X1804941Y893963D03*
X1813641D03*
X1804941Y904003D03*
X1813641D03*
X1804941Y910696D03*
X1813641D03*
X1804941Y917389D03*
X1813641D03*
X1804941Y924081D03*
X1813641D03*
X1804941Y930774D03*
X1813641D03*
X1804941Y940814D03*
X1813641D03*
X1804941Y947507D03*
X1813641D03*
X1804941Y954200D03*
X1813641D03*
X1804941Y964239D03*
X1813641D03*
X1804941Y970932D03*
X1813641D03*
X1804941Y977625D03*
X1813641D03*
X1804941Y984318D03*
X1813641D03*
X1804941Y991011D03*
X1813641D03*
X1804941Y1017782D03*
X1813641D03*
X1804941Y1024475D03*
X1813641D03*
X1804941Y1031168D03*
X1813641D03*
X1804941Y1037861D03*
X1813641D03*
X1804941Y1044554D03*
X1813641D03*
Y1057940D03*
X1804941D03*
Y1051247D03*
X1813641D03*
X1804941Y1064633D03*
X1813641D03*
Y1071326D03*
X1804941D03*
X1813641Y1078018D03*
X1804941D03*
X1813641Y1088058D03*
X1804941D03*
X1813641Y1094751D03*
X1804941D03*
X1813641Y1101444D03*
X1804941D03*
X1813641Y1108137D03*
X1804941D03*
X1813641Y1114829D03*
X1804941D03*
X1813641Y1124869D03*
X1804941D03*
X1813641Y1131562D03*
X1804941D03*
X1813641Y1138255D03*
X1804941D03*
X1813641Y1144948D03*
X1804941D03*
X1813641Y1151641D03*
X1804941D03*
X1813641Y1161680D03*
X1804941D03*
X1813641Y1168373D03*
X1804941D03*
X1813641Y1175066D03*
X1804941D03*
X1813641Y1181759D03*
X1804941D03*
X1813641Y1188452D03*
X1804941D03*
X1813641Y1198491D03*
X1804941D03*
X1813641Y1205184D03*
X1804941D03*
X1813641Y1211877D03*
X1804941D03*
X1813641Y1218570D03*
X1804941D03*
X1813641Y1225263D03*
X1804941D03*
X1813641Y1235302D03*
X1804941D03*
X1813641Y1241995D03*
X1804941D03*
X1813641Y1248688D03*
X1804941D03*
X1819054Y1253986D03*
X1818188Y1273044D03*
X1810788Y1273344D03*
X1807988D03*
X1815388Y1273044D03*
X1829783Y766798D03*
X1821083D03*
X1829783Y773491D03*
X1821083D03*
X1829783Y780184D03*
X1821083D03*
X1829783Y790223D03*
X1821083D03*
X1829783Y796916D03*
X1821083D03*
X1829783Y803609D03*
X1821083D03*
X1829783Y810302D03*
X1821083D03*
X1829783Y816995D03*
X1821083D03*
X1829783Y827034D03*
X1821083D03*
X1829783Y833727D03*
X1821083D03*
Y847113D03*
X1829783D03*
Y840420D03*
X1821083D03*
X1829783Y853806D03*
X1821083D03*
X1829783Y863845D03*
X1821083D03*
X1829783Y870538D03*
X1821083D03*
X1829783Y877231D03*
X1821083D03*
X1829783Y883924D03*
X1821083D03*
X1829783Y890617D03*
X1821083D03*
X1829783Y900656D03*
X1821083D03*
X1829783Y907349D03*
X1821083D03*
X1829783Y914042D03*
X1821083D03*
X1829783Y920735D03*
X1821083D03*
X1829783Y927428D03*
X1821083D03*
X1829783Y937467D03*
X1821083D03*
X1829783Y944160D03*
X1821083D03*
X1829783Y950853D03*
X1821083D03*
X1829783Y960892D03*
X1821083D03*
X1829783Y967585D03*
X1821083D03*
X1829783Y974278D03*
X1821083D03*
X1829783Y980971D03*
X1821083D03*
X1829783Y987664D03*
X1821083D03*
X1829783Y1017782D03*
X1821083D03*
X1829783Y1027822D03*
X1821083D03*
X1829783Y1034515D03*
X1821083D03*
X1829783Y1041207D03*
X1821083D03*
X1829783Y1047900D03*
X1821083D03*
X1829783Y1054593D03*
X1821083D03*
X1829783Y1061286D03*
X1821083D03*
X1829783Y1067979D03*
X1821083D03*
Y1074672D03*
X1829783D03*
X1821083Y1084711D03*
X1829783D03*
X1821083Y1091404D03*
X1829783D03*
X1821083Y1098097D03*
X1829783D03*
X1821083Y1104790D03*
X1829783D03*
X1821083Y1111483D03*
X1829783D03*
X1821083Y1121522D03*
X1829783D03*
X1821083Y1128215D03*
X1829783D03*
X1821083Y1134908D03*
X1829783D03*
X1821083Y1141601D03*
X1829783D03*
X1821083Y1148294D03*
X1829783D03*
X1821083Y1158333D03*
X1829783D03*
X1821083Y1165026D03*
X1829783D03*
X1821083Y1171719D03*
X1829783D03*
X1821083Y1178412D03*
X1829783D03*
X1821083Y1185105D03*
X1829783D03*
X1821083Y1195144D03*
X1829783D03*
X1821083Y1201837D03*
X1829783D03*
X1821083Y1208530D03*
X1829783D03*
X1821083Y1215223D03*
X1829783D03*
X1821083Y1221916D03*
X1829783D03*
X1821083Y1231955D03*
X1829783D03*
X1821083Y1238648D03*
X1829783D03*
Y1245341D03*
X1821083D03*
G54D58*
X841240Y1420330D03*
X1016240D03*
G54D64*
X986642Y-27947D03*
X986627Y-25432D03*
Y-21558D03*
X986642Y-17918D03*
X986627Y-15403D03*
Y-11529D03*
X986642Y-7889D03*
X986627Y-5374D03*
Y4655D03*
X986642Y2140D03*
X986627Y14684D03*
X986642Y12169D03*
X986627Y8529D03*
X986642Y22698D03*
X989910Y22684D03*
X986627Y19058D03*
Y25213D03*
X989895Y25199D03*
X1296019Y-35472D03*
Y-31598D03*
X1296034Y-37987D03*
Y-27958D03*
X1296019Y-25443D03*
Y-21569D03*
X1296034Y-17929D03*
X1296019Y-15414D03*
Y-11540D03*
X1296034Y-7900D03*
X1296019Y-5385D03*
Y4644D03*
X1296034Y2129D03*
X1296019Y-1511D03*
Y14673D03*
X1296034Y12158D03*
X1296019Y8518D03*
X1296034Y22687D03*
X1296019Y19047D03*
Y25202D03*
X1299302Y22673D03*
X1299287Y25188D03*
X1488393Y-27958D03*
X1488378Y-25443D03*
X1488393Y-37987D03*
X1488378Y-35472D03*
Y-31598D03*
X1488393Y-17929D03*
X1488378Y-15414D03*
Y-11540D03*
Y-21569D03*
X1488393Y2129D03*
X1488378Y4644D03*
X1488393Y-7900D03*
X1488378Y-5385D03*
Y-1511D03*
Y14673D03*
X1488393Y12158D03*
Y22687D03*
X1491661Y22673D03*
X1488378Y8518D03*
Y19047D03*
Y25202D03*
X1491646Y25188D03*
G54D72*
X1879155Y344948D03*
Y592848D03*
X1900275Y-19342D03*
X1889155Y344948D03*
Y592848D03*
X1900275Y716808D03*
X1910275Y-19342D03*
Y716808D03*
X1931395Y592868D03*
X1921395D03*
X1952395Y-19152D03*
X1942395D03*
X1963362Y593010D03*
X1984482Y-19180D03*
X1973362Y593010D03*
X1994482Y-19180D03*
X2015452Y593020D03*
X2005452D03*
X2026452Y-19000D03*
X2036452D03*
X2047419Y593162D03*
X2057419D03*
G54D24*
X57646Y12480D03*
X137272D03*
X186622D03*
X266858D03*
X315598D03*
X502528Y33268D03*
X582154D03*
X631504D03*
X711740D03*
X760480D03*
X1532055Y12480D03*
X1611681D03*
X1661031D03*
X1741267D03*
X1790007D03*
G54D65*
X1077638Y133866D03*
G54D47*
X460000Y278543D03*
G54D70*
X1771457Y1634646D03*
G54D59*
X900196Y175197D03*
X944684Y155216D03*
G54D79*
X1903086Y1318228D03*
X1902402Y1683256D03*
X1950484Y1683497D03*
X1993147Y1682875D03*
G54D77*
X1880836Y1317164D03*
X1881165Y1682207D03*
X1929695Y1683220D03*
X1971555Y1683130D03*
%LPC*%
G75*
G54D80*
G01X-6350Y-464479D02*
Y-539479D01*
X493650D01*
Y-464479D01*
X-6350D01*
G01X5650Y-529479D02*
Y-534479D01*
G01X4193Y-529479D02*
X7107D01*
G01X12017Y-534479D02*
X9483D01*
Y-529479D01*
X12017D01*
G01X11003Y-531896D02*
X9483D01*
G01X14583Y-529479D02*
Y-534479D01*
X17117D01*
G01X20950Y-534646D02*
X20823Y-534562D01*
Y-534396D01*
X20950Y-534312D01*
X21077Y-534396D01*
Y-534562D01*
X20950Y-534646D01*
G01Y-532396D02*
X20823Y-532312D01*
Y-532146D01*
X20950Y-532062D01*
X21077Y-532146D01*
Y-532312D01*
X20950Y-532396D01*
G01X25733Y-536146D02*
X25100Y-535312D01*
X24783Y-534479D01*
Y-531146D01*
X25100Y-530312D01*
X25733Y-529479D01*
G01X31150D02*
X30643Y-529646D01*
X30263Y-530062D01*
X30010Y-530562D01*
X29820Y-531229D01*
X29757Y-531979D01*
X29820Y-532729D01*
X30010Y-533396D01*
X30263Y-533896D01*
X30643Y-534312D01*
X31150Y-534479D01*
X31657Y-534312D01*
X32037Y-533896D01*
X32290Y-533396D01*
X32480Y-532729D01*
X32543Y-531979D01*
X32480Y-531229D01*
X32290Y-530562D01*
X32037Y-530062D01*
X31657Y-529646D01*
X31150Y-529479D01*
G01X34857Y-533479D02*
X35237Y-534062D01*
X35743Y-534396D01*
X36313Y-534479D01*
X36820Y-534396D01*
X37327Y-533979D01*
X37643Y-533479D01*
X37707Y-532979D01*
X37580Y-532396D01*
X37137Y-531979D01*
X36693Y-531812D01*
X36123D01*
G01X36693D02*
X37073Y-531562D01*
X37390Y-531146D01*
X37517Y-530646D01*
X37390Y-530146D01*
X37073Y-529729D01*
X36503Y-529479D01*
X35933Y-529562D01*
X35363Y-529896D01*
G01X41667Y-536146D02*
X42300Y-535312D01*
X42617Y-534479D01*
Y-531146D01*
X42300Y-530312D01*
X41667Y-529479D01*
G01X45057Y-533479D02*
X45437Y-534062D01*
X45943Y-534396D01*
X46513Y-534479D01*
X47020Y-534396D01*
X47527Y-533979D01*
X47843Y-533479D01*
X47907Y-532979D01*
X47780Y-532396D01*
X47337Y-531979D01*
X46893Y-531812D01*
X46323D01*
G01X46893D02*
X47273Y-531562D01*
X47590Y-531146D01*
X47717Y-530646D01*
X47590Y-530146D01*
X47273Y-529729D01*
X46703Y-529479D01*
X46133Y-529562D01*
X45563Y-529896D01*
G01X50347Y-530312D02*
X50727Y-529812D01*
X51170Y-529562D01*
X51677Y-529479D01*
X52310Y-529646D01*
X52753Y-530062D01*
X52880Y-530562D01*
X52817Y-531062D01*
X52563Y-531479D01*
X51297Y-532312D01*
X50727Y-532896D01*
X50347Y-533729D01*
X50220Y-534479D01*
X52880D01*
G01X56523D02*
X56650Y-533396D01*
X56840Y-532479D01*
X57093Y-531646D01*
X57410Y-530729D01*
X57917Y-529479D01*
X55383D01*
G01X60927Y-532812D02*
X62573D01*
G01X65647Y-530312D02*
X66027Y-529812D01*
X66470Y-529562D01*
X66977Y-529479D01*
X67610Y-529646D01*
X68053Y-530062D01*
X68180Y-530562D01*
X68117Y-531062D01*
X67863Y-531479D01*
X66597Y-532312D01*
X66027Y-532896D01*
X65647Y-533729D01*
X65520Y-534479D01*
X68180D01*
G01X70557Y-533479D02*
X70937Y-534062D01*
X71443Y-534396D01*
X72013Y-534479D01*
X72520Y-534396D01*
X73027Y-533979D01*
X73343Y-533479D01*
X73407Y-532979D01*
X73280Y-532396D01*
X72837Y-531979D01*
X72393Y-531812D01*
X71823D01*
G01X72393D02*
X72773Y-531562D01*
X73090Y-531146D01*
X73217Y-530646D01*
X73090Y-530146D01*
X72773Y-529729D01*
X72203Y-529479D01*
X71633Y-529562D01*
X71063Y-529896D01*
G01X77810Y-534479D02*
Y-529479D01*
X75467Y-533062D01*
X78633D01*
G01X80757Y-533729D02*
X81137Y-534146D01*
X81580Y-534396D01*
X82150Y-534479D01*
X82720Y-534312D01*
X83163Y-533979D01*
X83480Y-533396D01*
X83543Y-532729D01*
X83417Y-532062D01*
X83100Y-531646D01*
X82657Y-531312D01*
X82213Y-531229D01*
X81770Y-531312D01*
X81200Y-531646D01*
X81390Y-529479D01*
X83100D01*
G01X91147Y-534479D02*
Y-529479D01*
X93553D01*
G01X92667Y-531896D02*
X91147D01*
G01X95867Y-534479D02*
X97450Y-529479D01*
X99033Y-534479D01*
G01X98463Y-532729D02*
X96437D01*
G01X101220Y-534479D02*
X103880Y-529479D01*
G01X101220D02*
X103880Y-534479D01*
G01X107650Y-534646D02*
X107523Y-534562D01*
Y-534396D01*
X107650Y-534312D01*
X107777Y-534396D01*
Y-534562D01*
X107650Y-534646D01*
G01Y-532396D02*
X107523Y-532312D01*
Y-532146D01*
X107650Y-532062D01*
X107777Y-532146D01*
Y-532312D01*
X107650Y-532396D01*
G01X112433Y-536146D02*
X111800Y-535312D01*
X111483Y-534479D01*
Y-531146D01*
X111800Y-530312D01*
X112433Y-529479D01*
G01X117850D02*
X117343Y-529646D01*
X116963Y-530062D01*
X116710Y-530562D01*
X116520Y-531229D01*
X116457Y-531979D01*
X116520Y-532729D01*
X116710Y-533396D01*
X116963Y-533896D01*
X117343Y-534312D01*
X117850Y-534479D01*
X118357Y-534312D01*
X118737Y-533896D01*
X118990Y-533396D01*
X119180Y-532729D01*
X119243Y-531979D01*
X119180Y-531229D01*
X118990Y-530562D01*
X118737Y-530062D01*
X118357Y-529646D01*
X117850Y-529479D01*
G01X121557Y-533479D02*
X121937Y-534062D01*
X122443Y-534396D01*
X123013Y-534479D01*
X123520Y-534396D01*
X124027Y-533979D01*
X124343Y-533479D01*
X124407Y-532979D01*
X124280Y-532396D01*
X123837Y-531979D01*
X123393Y-531812D01*
X122823D01*
G01X123393D02*
X123773Y-531562D01*
X124090Y-531146D01*
X124217Y-530646D01*
X124090Y-530146D01*
X123773Y-529729D01*
X123203Y-529479D01*
X122633Y-529562D01*
X122063Y-529896D01*
G01X128367Y-536146D02*
X129000Y-535312D01*
X129317Y-534479D01*
Y-531146D01*
X129000Y-530312D01*
X128367Y-529479D01*
G01X131757Y-533479D02*
X132137Y-534062D01*
X132643Y-534396D01*
X133213Y-534479D01*
X133720Y-534396D01*
X134227Y-533979D01*
X134543Y-533479D01*
X134607Y-532979D01*
X134480Y-532396D01*
X134037Y-531979D01*
X133593Y-531812D01*
X133023D01*
G01X133593D02*
X133973Y-531562D01*
X134290Y-531146D01*
X134417Y-530646D01*
X134290Y-530146D01*
X133973Y-529729D01*
X133403Y-529479D01*
X132833Y-529562D01*
X132263Y-529896D01*
G01X137173Y-533896D02*
X137617Y-534312D01*
X138123Y-534479D01*
X138630Y-534312D01*
X139073Y-533812D01*
X139390Y-533062D01*
X139517Y-532312D01*
Y-531396D01*
X139390Y-530646D01*
X139073Y-529979D01*
X138693Y-529646D01*
X138250Y-529479D01*
X137743Y-529646D01*
X137363Y-529979D01*
X137110Y-530479D01*
X136983Y-531146D01*
X137110Y-531729D01*
X137427Y-532312D01*
X137807Y-532646D01*
X138250Y-532729D01*
X138757Y-532562D01*
X139137Y-532146D01*
X139517Y-531396D01*
G01X143223Y-534479D02*
X143350Y-533396D01*
X143540Y-532479D01*
X143793Y-531646D01*
X144110Y-530729D01*
X144617Y-529479D01*
X142083D01*
G01X147627Y-532812D02*
X149273D01*
G01X152157Y-533479D02*
X152537Y-534062D01*
X153043Y-534396D01*
X153613Y-534479D01*
X154120Y-534396D01*
X154627Y-533979D01*
X154943Y-533479D01*
X155007Y-532979D01*
X154880Y-532396D01*
X154437Y-531979D01*
X153993Y-531812D01*
X153423D01*
G01X153993D02*
X154373Y-531562D01*
X154690Y-531146D01*
X154817Y-530646D01*
X154690Y-530146D01*
X154373Y-529729D01*
X153803Y-529479D01*
X153233Y-529562D01*
X152663Y-529896D01*
G01X157447Y-532396D02*
X157890Y-531812D01*
X158270Y-531479D01*
X158777Y-531312D01*
X159220Y-531479D01*
X159537Y-531812D01*
X159790Y-532312D01*
X159853Y-532896D01*
X159790Y-533396D01*
X159537Y-533896D01*
X159157Y-534312D01*
X158713Y-534479D01*
X158207Y-534312D01*
X157763Y-533812D01*
X157510Y-533062D01*
X157447Y-532229D01*
X157573Y-531146D01*
X157763Y-530562D01*
X158080Y-529979D01*
X158523Y-529562D01*
X158967Y-529479D01*
X159410Y-529646D01*
X159727Y-530062D01*
G01X163750Y-534479D02*
Y-529479D01*
X162990Y-530479D01*
G01Y-534479D02*
X164510D01*
G01X169610D02*
Y-529479D01*
X167267Y-533062D01*
X170433D01*
G01X188650Y-464479D02*
Y-539479D01*
G01Y-514479D02*
X291650D01*
Y-489479D01*
G01X188650D02*
X291650D01*
G01Y-464479D02*
Y-539479D01*
G01X293650Y-464479D02*
Y-539479D01*
G01X299157Y-524479D02*
Y-519479D01*
X300423D01*
X300930Y-519729D01*
X301310Y-520062D01*
X301627Y-520562D01*
X301880Y-521146D01*
X301943Y-521979D01*
X301880Y-522812D01*
X301627Y-523396D01*
X301310Y-523896D01*
X300930Y-524229D01*
X300423Y-524479D01*
X299157D01*
G01X304067D02*
X305650Y-519479D01*
X307233Y-524479D01*
G01X306663Y-522729D02*
X304637D01*
G01X310750Y-519479D02*
Y-524479D01*
G01X309293Y-519479D02*
X312207D01*
G01X317117Y-524479D02*
X314583D01*
Y-519479D01*
X317117D01*
G01X316103Y-521896D02*
X314583D01*
G01X320950Y-524646D02*
X320823Y-524562D01*
Y-524396D01*
X320950Y-524312D01*
X321077Y-524396D01*
Y-524562D01*
X320950Y-524646D01*
G01Y-522396D02*
X320823Y-522312D01*
Y-522146D01*
X320950Y-522062D01*
X321077Y-522146D01*
Y-522312D01*
X320950Y-522396D01*
G01X299283Y-499479D02*
Y-494479D01*
X300803D01*
X301310Y-494729D01*
X301690Y-495312D01*
X301817Y-495979D01*
X301690Y-496646D01*
X301373Y-497146D01*
X300803Y-497396D01*
X299283D01*
G01X304510Y-499646D02*
X306790Y-494479D01*
G01X309293Y-499479D02*
Y-494479D01*
X312207Y-499479D01*
Y-494479D01*
G01X315850Y-499646D02*
X315723Y-499562D01*
Y-499396D01*
X315850Y-499312D01*
X315977Y-499396D01*
Y-499562D01*
X315850Y-499646D01*
G01Y-497396D02*
X315723Y-497312D01*
Y-497146D01*
X315850Y-497062D01*
X315977Y-497146D01*
Y-497312D01*
X315850Y-497396D01*
G01X293650Y-514479D02*
X493650D01*
G01X293650Y-489479D02*
X493650D01*
G01X299283Y-474479D02*
Y-469479D01*
X300803D01*
X301310Y-469729D01*
X301690Y-470312D01*
X301817Y-470979D01*
X301690Y-471646D01*
X301373Y-472146D01*
X300803Y-472396D01*
X299283D01*
G01X304383Y-474479D02*
Y-469479D01*
X305967D01*
X306473Y-469729D01*
X306790Y-470062D01*
X306917Y-470729D01*
X306790Y-471396D01*
X306410Y-471812D01*
X305967Y-472062D01*
X304383D01*
G01X305967D02*
X306917Y-474479D01*
G01X310750D02*
X310243Y-474396D01*
X309800Y-474062D01*
X309420Y-473562D01*
X309167Y-472979D01*
X309040Y-472312D01*
Y-471646D01*
X309167Y-470979D01*
X309420Y-470396D01*
X309800Y-469896D01*
X310243Y-469562D01*
X310750Y-469479D01*
X311257Y-469562D01*
X311700Y-469896D01*
X312080Y-470396D01*
X312333Y-470979D01*
X312460Y-471646D01*
Y-472312D01*
X312333Y-472979D01*
X312080Y-473562D01*
X311700Y-474062D01*
X311257Y-474396D01*
X310750Y-474479D01*
G01X314583Y-473479D02*
X314900Y-473979D01*
X315280Y-474312D01*
X315723Y-474479D01*
X316230Y-474312D01*
X316610Y-473979D01*
X316990Y-473479D01*
X317117Y-472812D01*
Y-469479D01*
G01X322217Y-474479D02*
X319683D01*
Y-469479D01*
X322217D01*
G01X321203Y-471896D02*
X319683D01*
G01X327443Y-469896D02*
X327063Y-469646D01*
X326620Y-469479D01*
X326113D01*
X325543Y-469729D01*
X325100Y-470146D01*
X324783Y-470646D01*
X324530Y-471479D01*
X324467Y-472229D01*
X324593Y-472979D01*
X324783Y-473479D01*
X325163Y-473979D01*
X325607Y-474312D01*
X326050Y-474479D01*
X326493D01*
X326937Y-474312D01*
X327317Y-474062D01*
X327633Y-473729D01*
G01X331150Y-469479D02*
Y-474479D01*
G01X329693Y-469479D02*
X332607D01*
G01X336250Y-474646D02*
X336123Y-474562D01*
Y-474396D01*
X336250Y-474312D01*
X336377Y-474396D01*
Y-474562D01*
X336250Y-474646D01*
G01Y-472396D02*
X336123Y-472312D01*
Y-472146D01*
X336250Y-472062D01*
X336377Y-472146D01*
Y-472312D01*
X336250Y-472396D01*
G01X408650Y-514479D02*
Y-539479D01*
G01X411283Y-516979D02*
Y-521979D01*
X413817D01*
G01X416890Y-516979D02*
X418410D01*
G01X417650D02*
Y-521979D01*
G01X416890D02*
X418410D01*
G01X423257Y-519312D02*
X423510Y-519062D01*
X423700Y-518646D01*
X423827Y-518062D01*
X423700Y-517562D01*
X423447Y-517229D01*
X423003Y-516979D01*
X421293D01*
Y-521979D01*
X423383D01*
X423827Y-521646D01*
X424080Y-521146D01*
X424207Y-520562D01*
X424080Y-519979D01*
X423700Y-519479D01*
X423257Y-519312D01*
X421293D01*
G01X427850Y-522146D02*
X427723Y-522062D01*
Y-521896D01*
X427850Y-521812D01*
X427977Y-521896D01*
Y-522062D01*
X427850Y-522146D01*
G01Y-519896D02*
X427723Y-519812D01*
Y-519646D01*
X427850Y-519562D01*
X427977Y-519646D01*
Y-519812D01*
X427850Y-519896D01*
G01X451650Y-514479D02*
Y-539479D01*
G01Y-489479D02*
Y-514479D01*
G01X456663Y-541646D02*
X456770Y-541521D01*
X456850Y-541312D01*
X456903Y-541021D01*
X456850Y-540771D01*
X456743Y-540604D01*
X456557Y-540479D01*
X455837D01*
Y-542979D01*
X456717D01*
X456903Y-542812D01*
X457010Y-542562D01*
X457063Y-542271D01*
X457010Y-541979D01*
X456850Y-541729D01*
X456663Y-541646D01*
X455837D01*
G01X459130Y-542979D02*
Y-541312D01*
G01Y-541604D02*
X459023Y-541437D01*
X458863Y-541354D01*
X458677Y-541312D01*
X458490Y-541396D01*
X458330Y-541562D01*
X458223Y-541812D01*
X458170Y-542146D01*
X458223Y-542479D01*
X458330Y-542729D01*
X458490Y-542896D01*
X458677Y-542979D01*
X458863Y-542937D01*
X459023Y-542812D01*
X459130Y-542646D01*
G01X460450Y-542687D02*
X460583Y-542854D01*
X460770Y-542979D01*
X460930D01*
X461090Y-542896D01*
X461197Y-542771D01*
X461250Y-542604D01*
X461223Y-542354D01*
X461117Y-542229D01*
X460637Y-541979D01*
X460530Y-541687D01*
X460583Y-541479D01*
X460690Y-541354D01*
X460850Y-541312D01*
X461010Y-541354D01*
X461170Y-541479D01*
G01X462650Y-541854D02*
X463503D01*
X463423Y-541562D01*
X463290Y-541396D01*
X463103Y-541312D01*
X462917Y-541354D01*
X462757Y-541479D01*
X462650Y-541771D01*
X462597Y-542021D01*
Y-542271D01*
X462650Y-542521D01*
X462783Y-542771D01*
X462943Y-542937D01*
X463130Y-542979D01*
X463317Y-542896D01*
X463503Y-542646D01*
G01X464770Y-542979D02*
Y-540479D01*
G01Y-541729D02*
X464903Y-541479D01*
X465063Y-541354D01*
X465223Y-541312D01*
X465463Y-541396D01*
X465623Y-541562D01*
X465730Y-541854D01*
Y-542187D01*
X465677Y-542521D01*
X465570Y-542771D01*
X465383Y-542937D01*
X465223Y-542979D01*
X465063Y-542937D01*
X464903Y-542812D01*
X464770Y-542604D01*
G01X467450Y-542979D02*
X467290Y-542937D01*
X467130Y-542771D01*
X467023Y-542479D01*
X466970Y-542146D01*
X467023Y-541812D01*
X467130Y-541521D01*
X467290Y-541354D01*
X467450Y-541312D01*
X467610Y-541354D01*
X467770Y-541521D01*
X467877Y-541812D01*
X467903Y-542146D01*
X467877Y-542479D01*
X467770Y-542771D01*
X467610Y-542937D01*
X467450Y-542979D01*
G01X470130D02*
Y-541312D01*
G01Y-541604D02*
X470023Y-541437D01*
X469863Y-541354D01*
X469677Y-541312D01*
X469490Y-541396D01*
X469330Y-541562D01*
X469223Y-541812D01*
X469170Y-542146D01*
X469223Y-542479D01*
X469330Y-542729D01*
X469490Y-542896D01*
X469677Y-542979D01*
X469863Y-542937D01*
X470023Y-542812D01*
X470130Y-542646D01*
G01X471477Y-542979D02*
Y-541312D01*
G01Y-541646D02*
X471610Y-541479D01*
X471743Y-541354D01*
X471930Y-541312D01*
X472063Y-541354D01*
X472223Y-541479D01*
G01X474530Y-540479D02*
Y-542979D01*
G01Y-542604D02*
X474423Y-542812D01*
X474263Y-542937D01*
X474077Y-542979D01*
X473863Y-542896D01*
X473703Y-542687D01*
X473597Y-542437D01*
X473570Y-542146D01*
X473597Y-541854D01*
X473703Y-541604D01*
X473863Y-541396D01*
X474077Y-541312D01*
X474263Y-541354D01*
X474397Y-541437D01*
X474530Y-541604D01*
G01X477917Y-542979D02*
Y-540479D01*
X478583D01*
X478797Y-540604D01*
X478930Y-540771D01*
X478983Y-541104D01*
X478930Y-541437D01*
X478770Y-541646D01*
X478583Y-541771D01*
X477917D01*
G01X478583D02*
X478983Y-542979D01*
G01X480250Y-541854D02*
X481103D01*
X481023Y-541562D01*
X480890Y-541396D01*
X480703Y-541312D01*
X480517Y-541354D01*
X480357Y-541479D01*
X480250Y-541771D01*
X480197Y-542021D01*
Y-542271D01*
X480250Y-542521D01*
X480383Y-542771D01*
X480543Y-542937D01*
X480730Y-542979D01*
X480917Y-542896D01*
X481103Y-542646D01*
G01X482370Y-541312D02*
X482850Y-542979D01*
X483330Y-541312D01*
G01X485050Y-543062D02*
X484997Y-543021D01*
Y-542937D01*
X485050Y-542896D01*
X485103Y-542937D01*
Y-543021D01*
X485050Y-543062D01*
G01X487250Y-542979D02*
X487437Y-542937D01*
X487650Y-542812D01*
X487783Y-542604D01*
X487837Y-542312D01*
X487783Y-542021D01*
X487623Y-541771D01*
X487383Y-541646D01*
X487117D01*
X486957Y-541562D01*
X486823Y-541354D01*
X486770Y-541062D01*
X486850Y-540771D01*
X487037Y-540562D01*
X487250Y-540479D01*
X487463Y-540562D01*
X487650Y-540771D01*
X487730Y-541062D01*
X487677Y-541354D01*
X487543Y-541562D01*
X487383Y-541646D01*
X487117D01*
X486877Y-541771D01*
X486717Y-542021D01*
X486663Y-542312D01*
X486717Y-542604D01*
X486850Y-542812D01*
X487063Y-542937D01*
X487250Y-542979D01*
G01X489663Y-541646D02*
X489770Y-541521D01*
X489850Y-541312D01*
X489903Y-541021D01*
X489850Y-540771D01*
X489743Y-540604D01*
X489557Y-540479D01*
X488837D01*
Y-542979D01*
X489717D01*
X489903Y-542812D01*
X490010Y-542562D01*
X490063Y-542271D01*
X490010Y-541979D01*
X489850Y-541729D01*
X489663Y-541646D01*
X488837D01*
G01X455550Y-516979D02*
Y-521979D01*
G01X454093Y-516979D02*
X457007D01*
G01X460650Y-521979D02*
X460270Y-521896D01*
X459890Y-521562D01*
X459637Y-520979D01*
X459510Y-520312D01*
X459637Y-519646D01*
X459890Y-519062D01*
X460270Y-518729D01*
X460650Y-518646D01*
X461030Y-518729D01*
X461410Y-519062D01*
X461663Y-519646D01*
X461727Y-520312D01*
X461663Y-520979D01*
X461410Y-521562D01*
X461030Y-521896D01*
X460650Y-521979D01*
G01X465750D02*
X465370Y-521896D01*
X464990Y-521562D01*
X464737Y-520979D01*
X464610Y-520312D01*
X464737Y-519646D01*
X464990Y-519062D01*
X465370Y-518729D01*
X465750Y-518646D01*
X466130Y-518729D01*
X466510Y-519062D01*
X466763Y-519646D01*
X466827Y-520312D01*
X466763Y-520979D01*
X466510Y-521562D01*
X466130Y-521896D01*
X465750Y-521979D01*
G01X470850D02*
Y-516979D01*
G01X475950Y-522146D02*
X475823Y-522062D01*
Y-521896D01*
X475950Y-521812D01*
X476077Y-521896D01*
Y-522062D01*
X475950Y-522146D01*
G01Y-519896D02*
X475823Y-519812D01*
Y-519646D01*
X475950Y-519562D01*
X476077Y-519646D01*
Y-519812D01*
X475950Y-519896D01*
G01X454283Y-496979D02*
Y-491979D01*
X455867D01*
X456373Y-492229D01*
X456690Y-492562D01*
X456817Y-493229D01*
X456690Y-493896D01*
X456310Y-494312D01*
X455867Y-494562D01*
X454283D01*
G01X455867D02*
X456817Y-496979D01*
G01X461917D02*
X459383D01*
Y-491979D01*
X461917D01*
G01X460903Y-494396D02*
X459383D01*
G01X464167Y-491979D02*
X465750Y-496979D01*
X467333Y-491979D01*
G01X470850Y-497146D02*
X470723Y-497062D01*
Y-496896D01*
X470850Y-496812D01*
X470977Y-496896D01*
Y-497062D01*
X470850Y-497146D01*
G01Y-494896D02*
X470723Y-494812D01*
Y-494646D01*
X470850Y-494562D01*
X470977Y-494646D01*
Y-494812D01*
X470850Y-494896D01*
G01X-984580Y-698988D02*
Y4193602D01*
X5868320D01*
Y-698988D01*
X-984580D01*
G01X7723Y-521204D02*
X7253Y-520889D01*
X6705Y-520679D01*
X6078D01*
X5373Y-520994D01*
X4825Y-521519D01*
X4433Y-522149D01*
X4120Y-523199D01*
X4042Y-524144D01*
X4198Y-525089D01*
X4433Y-525719D01*
X4903Y-526349D01*
X5452Y-526769D01*
X6000Y-526979D01*
X6548D01*
X7097Y-526769D01*
X7567Y-526454D01*
X7958Y-526034D01*
G01X11360Y-520679D02*
X13240D01*
G01X12300D02*
Y-526979D01*
G01X11360D02*
X13240D01*
G01X18600Y-520679D02*
Y-526979D01*
G01X16798Y-520679D02*
X20402D01*
G01X24900Y-526979D02*
Y-524144D01*
X23333Y-520679D01*
G01X26467D02*
X24900Y-524144D01*
G01X35777Y-525719D02*
X36247Y-526454D01*
X36873Y-526874D01*
X37578Y-526979D01*
X38205Y-526874D01*
X38832Y-526349D01*
X39223Y-525719D01*
X39302Y-525089D01*
X39145Y-524354D01*
X38597Y-523829D01*
X38048Y-523619D01*
X37343D01*
G01X38048D02*
X38518Y-523304D01*
X38910Y-522779D01*
X39067Y-522149D01*
X38910Y-521519D01*
X38518Y-520994D01*
X37813Y-520679D01*
X37108Y-520784D01*
X36403Y-521204D01*
G01X42077Y-525719D02*
X42547Y-526454D01*
X43173Y-526874D01*
X43878Y-526979D01*
X44505Y-526874D01*
X45132Y-526349D01*
X45523Y-525719D01*
X45602Y-525089D01*
X45445Y-524354D01*
X44897Y-523829D01*
X44348Y-523619D01*
X43643D01*
G01X44348D02*
X44818Y-523304D01*
X45210Y-522779D01*
X45367Y-522149D01*
X45210Y-521519D01*
X44818Y-520994D01*
X44113Y-520679D01*
X43408Y-520784D01*
X42703Y-521204D01*
G01X48377Y-525719D02*
X48847Y-526454D01*
X49473Y-526874D01*
X50178Y-526979D01*
X50805Y-526874D01*
X51432Y-526349D01*
X51823Y-525719D01*
X51902Y-525089D01*
X51745Y-524354D01*
X51197Y-523829D01*
X50648Y-523619D01*
X49943D01*
G01X50648D02*
X51118Y-523304D01*
X51510Y-522779D01*
X51667Y-522149D01*
X51510Y-521519D01*
X51118Y-520994D01*
X50413Y-520679D01*
X49708Y-520784D01*
X49003Y-521204D01*
G01X56243Y-526979D02*
X56400Y-525614D01*
X56635Y-524459D01*
X56948Y-523409D01*
X57340Y-522254D01*
X57967Y-520679D01*
X54833D01*
G01X62543Y-526979D02*
X62700Y-525614D01*
X62935Y-524459D01*
X63248Y-523409D01*
X63640Y-522254D01*
X64267Y-520679D01*
X61133D01*
G01X68843Y-528134D02*
X69157Y-526769D01*
G01X75300Y-520679D02*
Y-526979D01*
G01X73498Y-520679D02*
X77102D01*
G01X79642Y-526979D02*
X81600Y-520679D01*
X83558Y-526979D01*
G01X82853Y-524774D02*
X80347D01*
G01X86960Y-520679D02*
X88840D01*
G01X87900D02*
Y-526979D01*
G01X86960D02*
X88840D01*
G01X91850Y-520679D02*
X92947Y-526979D01*
X94200Y-520679D01*
X95453Y-526979D01*
X96550Y-520679D01*
G01X98542Y-526979D02*
X100500Y-520679D01*
X102458Y-526979D01*
G01X101753Y-524774D02*
X99247D01*
G01X104998Y-526979D02*
Y-520679D01*
X108602Y-526979D01*
Y-520679D01*
G01X119008Y-529079D02*
X118225Y-528029D01*
X117833Y-526979D01*
Y-522779D01*
X118225Y-521729D01*
X119008Y-520679D01*
G01X130433Y-526979D02*
Y-520679D01*
X132392D01*
X133018Y-520994D01*
X133410Y-521414D01*
X133567Y-522254D01*
X133410Y-523094D01*
X132940Y-523619D01*
X132392Y-523934D01*
X130433D01*
G01X132392D02*
X133567Y-526979D01*
G01X138300Y-527189D02*
X138143Y-527084D01*
Y-526874D01*
X138300Y-526769D01*
X138457Y-526874D01*
Y-527084D01*
X138300Y-527189D01*
G01X144600Y-526979D02*
X143973Y-526874D01*
X143425Y-526454D01*
X142955Y-525824D01*
X142642Y-525089D01*
X142485Y-524249D01*
Y-523409D01*
X142642Y-522569D01*
X142955Y-521834D01*
X143425Y-521204D01*
X143973Y-520784D01*
X144600Y-520679D01*
X145227Y-520784D01*
X145775Y-521204D01*
X146245Y-521834D01*
X146558Y-522569D01*
X146715Y-523409D01*
Y-524249D01*
X146558Y-525089D01*
X146245Y-525824D01*
X145775Y-526454D01*
X145227Y-526874D01*
X144600Y-526979D01*
G01X150900Y-527189D02*
X150743Y-527084D01*
Y-526874D01*
X150900Y-526769D01*
X151057Y-526874D01*
Y-527084D01*
X150900Y-527189D01*
G01X158923Y-521204D02*
X158453Y-520889D01*
X157905Y-520679D01*
X157278D01*
X156573Y-520994D01*
X156025Y-521519D01*
X155633Y-522149D01*
X155320Y-523199D01*
X155242Y-524144D01*
X155398Y-525089D01*
X155633Y-525719D01*
X156103Y-526349D01*
X156652Y-526769D01*
X157200Y-526979D01*
X157748D01*
X158297Y-526769D01*
X158767Y-526454D01*
X159158Y-526034D01*
G01X163500Y-527189D02*
X163343Y-527084D01*
Y-526874D01*
X163500Y-526769D01*
X163657Y-526874D01*
Y-527084D01*
X163500Y-527189D01*
G01X170192Y-529079D02*
X170975Y-528029D01*
X171367Y-526979D01*
Y-522779D01*
X170975Y-521729D01*
X170192Y-520679D01*
G01X6470Y-513829D02*
X8037D01*
Y-515719D01*
X7567Y-516349D01*
X7018Y-516769D01*
X6235Y-516979D01*
X5452Y-516769D01*
X4903Y-516349D01*
X4433Y-515719D01*
X4120Y-514984D01*
X3963Y-514144D01*
Y-513409D01*
X4120Y-512779D01*
X4433Y-512044D01*
X4903Y-511414D01*
X5373Y-510994D01*
X6000Y-510679D01*
X6548D01*
X7175Y-510889D01*
X7645Y-511309D01*
G01X10577Y-510679D02*
Y-515194D01*
X10890Y-516139D01*
X11517Y-516769D01*
X12300Y-516979D01*
X13083Y-516769D01*
X13710Y-516139D01*
X14023Y-515194D01*
Y-510679D01*
G01X17660D02*
X19540D01*
G01X18600D02*
Y-516979D01*
G01X17660D02*
X19540D01*
G01X23255Y-516139D02*
X23882Y-516664D01*
X24587Y-516979D01*
X25213D01*
X25840Y-516664D01*
X26310Y-516139D01*
X26545Y-515404D01*
X26388Y-514669D01*
X25997Y-514039D01*
X25292Y-513619D01*
X24352Y-513409D01*
X23803Y-512989D01*
X23568Y-512254D01*
X23725Y-511519D01*
X24117Y-510994D01*
X24665Y-510679D01*
X25213D01*
X25762Y-510889D01*
X26232Y-511414D01*
G01X29555Y-516979D02*
Y-510679D01*
G01X32845D02*
Y-516979D01*
G01Y-513829D02*
X29555D01*
G01X35542Y-516979D02*
X37500Y-510679D01*
X39458Y-516979D01*
G01X38753Y-514774D02*
X36247D01*
G01X41998Y-516979D02*
Y-510679D01*
X45602Y-516979D01*
Y-510679D01*
G01X54677Y-516979D02*
Y-510679D01*
X56243D01*
X56870Y-510994D01*
X57340Y-511414D01*
X57732Y-512044D01*
X58045Y-512779D01*
X58123Y-513829D01*
X58045Y-514879D01*
X57732Y-515614D01*
X57340Y-516244D01*
X56870Y-516664D01*
X56243Y-516979D01*
X54677D01*
G01X61760Y-510679D02*
X63640D01*
G01X62700D02*
Y-516979D01*
G01X61760D02*
X63640D01*
G01X67355Y-516139D02*
X67982Y-516664D01*
X68687Y-516979D01*
X69313D01*
X69940Y-516664D01*
X70410Y-516139D01*
X70645Y-515404D01*
X70488Y-514669D01*
X70097Y-514039D01*
X69392Y-513619D01*
X68452Y-513409D01*
X67903Y-512989D01*
X67668Y-512254D01*
X67825Y-511519D01*
X68217Y-510994D01*
X68765Y-510679D01*
X69313D01*
X69862Y-510889D01*
X70332Y-511414D01*
G01X75300Y-510679D02*
Y-516979D01*
G01X73498Y-510679D02*
X77102D01*
G01X81600Y-517189D02*
X81443Y-517084D01*
Y-516874D01*
X81600Y-516769D01*
X81757Y-516874D01*
Y-517084D01*
X81600Y-517189D01*
G01X87743Y-518134D02*
X88057Y-516769D01*
G01X94200Y-510679D02*
Y-516979D01*
G01X92398Y-510679D02*
X96002D01*
G01X98542Y-516979D02*
X100500Y-510679D01*
X102458Y-516979D01*
G01X101753Y-514774D02*
X99247D01*
G01X106800Y-516979D02*
X106173Y-516874D01*
X105625Y-516454D01*
X105155Y-515824D01*
X104842Y-515089D01*
X104685Y-514249D01*
Y-513409D01*
X104842Y-512569D01*
X105155Y-511834D01*
X105625Y-511204D01*
X106173Y-510784D01*
X106800Y-510679D01*
X107427Y-510784D01*
X107975Y-511204D01*
X108445Y-511834D01*
X108758Y-512569D01*
X108915Y-513409D01*
Y-514249D01*
X108758Y-515089D01*
X108445Y-515824D01*
X107975Y-516454D01*
X107427Y-516874D01*
X106800Y-516979D01*
G01X113100D02*
Y-514144D01*
X111533Y-510679D01*
G01X114667D02*
X113100Y-514144D01*
G01X117677Y-510679D02*
Y-515194D01*
X117990Y-516139D01*
X118617Y-516769D01*
X119400Y-516979D01*
X120183Y-516769D01*
X120810Y-516139D01*
X121123Y-515194D01*
Y-510679D01*
G01X123742Y-516979D02*
X125700Y-510679D01*
X127658Y-516979D01*
G01X126953Y-514774D02*
X124447D01*
G01X130198Y-516979D02*
Y-510679D01*
X133802Y-516979D01*
Y-510679D01*
G01X4198Y-506979D02*
Y-500679D01*
X7802Y-506979D01*
Y-500679D01*
G01X12300Y-506979D02*
X11673Y-506874D01*
X11125Y-506454D01*
X10655Y-505824D01*
X10342Y-505089D01*
X10185Y-504249D01*
Y-503409D01*
X10342Y-502569D01*
X10655Y-501834D01*
X11125Y-501204D01*
X11673Y-500784D01*
X12300Y-500679D01*
X12927Y-500784D01*
X13475Y-501204D01*
X13945Y-501834D01*
X14258Y-502569D01*
X14415Y-503409D01*
Y-504249D01*
X14258Y-505089D01*
X13945Y-505824D01*
X13475Y-506454D01*
X12927Y-506874D01*
X12300Y-506979D01*
G01X18600Y-507189D02*
X18443Y-507084D01*
Y-506874D01*
X18600Y-506769D01*
X18757Y-506874D01*
Y-507084D01*
X18600Y-507189D01*
G01X23412Y-501729D02*
X23882Y-501099D01*
X24430Y-500784D01*
X25057Y-500679D01*
X25840Y-500889D01*
X26388Y-501414D01*
X26545Y-502044D01*
X26467Y-502674D01*
X26153Y-503199D01*
X24587Y-504249D01*
X23882Y-504984D01*
X23412Y-506034D01*
X23255Y-506979D01*
X26545D01*
G01X31200D02*
Y-500679D01*
X30260Y-501939D01*
G01Y-506979D02*
X32140D01*
G01X37500D02*
Y-500679D01*
X36560Y-501939D01*
G01Y-506979D02*
X38440D01*
G01X43643Y-508134D02*
X43957Y-506769D01*
G01X47750Y-500679D02*
X48847Y-506979D01*
X50100Y-500679D01*
X51353Y-506979D01*
X52450Y-500679D01*
G01X57967Y-506979D02*
X54833D01*
Y-500679D01*
X57967D01*
G01X56713Y-503724D02*
X54833D01*
G01X60898Y-506979D02*
Y-500679D01*
X64502Y-506979D01*
Y-500679D01*
G01X67355Y-506979D02*
Y-500679D01*
G01X70645D02*
Y-506979D01*
G01Y-503829D02*
X67355D01*
G01X73577Y-500679D02*
Y-505194D01*
X73890Y-506139D01*
X74517Y-506769D01*
X75300Y-506979D01*
X76083Y-506769D01*
X76710Y-506139D01*
X77023Y-505194D01*
Y-500679D01*
G01X79642Y-506979D02*
X81600Y-500679D01*
X83558Y-506979D01*
G01X82853Y-504774D02*
X80347D01*
G01X92712Y-501729D02*
X93182Y-501099D01*
X93730Y-500784D01*
X94357Y-500679D01*
X95140Y-500889D01*
X95688Y-501414D01*
X95845Y-502044D01*
X95767Y-502674D01*
X95453Y-503199D01*
X93887Y-504249D01*
X93182Y-504984D01*
X92712Y-506034D01*
X92555Y-506979D01*
X95845D01*
G01X98698D02*
Y-500679D01*
X102302Y-506979D01*
Y-500679D01*
G01X105077Y-506979D02*
Y-500679D01*
X106643D01*
X107270Y-500994D01*
X107740Y-501414D01*
X108132Y-502044D01*
X108445Y-502779D01*
X108523Y-503829D01*
X108445Y-504879D01*
X108132Y-505614D01*
X107740Y-506244D01*
X107270Y-506664D01*
X106643Y-506979D01*
X105077D01*
G01X117833D02*
Y-500679D01*
X119792D01*
X120418Y-500994D01*
X120810Y-501414D01*
X120967Y-502254D01*
X120810Y-503094D01*
X120340Y-503619D01*
X119792Y-503934D01*
X117833D01*
G01X119792D02*
X120967Y-506979D01*
G01X123977D02*
Y-500679D01*
X125543D01*
X126170Y-500994D01*
X126640Y-501414D01*
X127032Y-502044D01*
X127345Y-502779D01*
X127423Y-503829D01*
X127345Y-504879D01*
X127032Y-505614D01*
X126640Y-506244D01*
X126170Y-506664D01*
X125543Y-506979D01*
X123977D01*
G01X132000Y-507189D02*
X131843Y-507084D01*
Y-506874D01*
X132000Y-506769D01*
X132157Y-506874D01*
Y-507084D01*
X132000Y-507189D01*
G01X28300Y-494279D02*
X25780Y-493862D01*
X23575Y-492196D01*
X21685Y-489696D01*
X20425Y-486779D01*
X19795Y-483446D01*
Y-480112D01*
X20425Y-476779D01*
X21685Y-473862D01*
X23575Y-471363D01*
X25780Y-469696D01*
X28300Y-469279D01*
X30820Y-469696D01*
X33025Y-471363D01*
X34915Y-473862D01*
X36175Y-476779D01*
X36805Y-480112D01*
Y-483446D01*
X36175Y-486779D01*
X34915Y-489696D01*
X33025Y-492196D01*
X30820Y-493862D01*
X28300Y-494279D01*
G01X30820Y-487612D02*
X34600Y-494279D01*
G01X48145Y-477613D02*
Y-489279D01*
X49405Y-492196D01*
X51295Y-493862D01*
X53500Y-494279D01*
X55705Y-493862D01*
X57595Y-492196D01*
X58855Y-489279D01*
G01Y-494279D02*
Y-477613D01*
G01X84370Y-494279D02*
Y-477613D01*
G01Y-480529D02*
X83110Y-478863D01*
X81220Y-478029D01*
X79015Y-477613D01*
X76810Y-478446D01*
X74920Y-480112D01*
X73660Y-482613D01*
X73030Y-485946D01*
X73660Y-489279D01*
X74920Y-491780D01*
X76810Y-493446D01*
X79015Y-494279D01*
X81220Y-493862D01*
X83110Y-492613D01*
X84370Y-490946D01*
G01X98545Y-494279D02*
Y-477613D01*
G01Y-481779D02*
X99805Y-479696D01*
X101695Y-478029D01*
X104215Y-477613D01*
X106420Y-478029D01*
X108310Y-479696D01*
X109255Y-482613D01*
Y-494279D01*
G01X129100Y-469279D02*
Y-494279D01*
G01X124690Y-477613D02*
X133510D01*
G01X159970Y-494279D02*
Y-477613D01*
G01Y-480529D02*
X158710Y-478863D01*
X156820Y-478029D01*
X154615Y-477613D01*
X152410Y-478446D01*
X150520Y-480112D01*
X149260Y-482613D01*
X148630Y-485946D01*
X149260Y-489279D01*
X150520Y-491780D01*
X152410Y-493446D01*
X154615Y-494279D01*
X156820Y-493862D01*
X158710Y-492613D01*
X159970Y-490946D01*
G01X199650Y-473979D02*
Y-481979D01*
X203650D01*
G01X211450D02*
Y-476646D01*
G01Y-477579D02*
X211050Y-477046D01*
X210450Y-476779D01*
X209750Y-476646D01*
X209050Y-476912D01*
X208450Y-477446D01*
X208050Y-478246D01*
X207850Y-479312D01*
X208050Y-480379D01*
X208450Y-481179D01*
X209050Y-481712D01*
X209750Y-481979D01*
X210450Y-481846D01*
X211050Y-481446D01*
X211450Y-480913D01*
G01X215550Y-484379D02*
X216150Y-484646D01*
X216950Y-484379D01*
X217450Y-483846D01*
X217850Y-483179D01*
X218450Y-481046D01*
X219750Y-476646D01*
G01X216550D02*
X218450Y-481046D01*
G01X224150Y-478379D02*
X227350D01*
X227050Y-477446D01*
X226550Y-476912D01*
X225850Y-476646D01*
X225150Y-476779D01*
X224550Y-477179D01*
X224150Y-478112D01*
X223950Y-478913D01*
Y-479712D01*
X224150Y-480512D01*
X224650Y-481312D01*
X225250Y-481846D01*
X225950Y-481979D01*
X226650Y-481712D01*
X227350Y-480913D01*
G01X232250Y-481979D02*
Y-476646D01*
G01Y-477712D02*
X232750Y-477179D01*
X233250Y-476779D01*
X233950Y-476646D01*
X234450Y-476779D01*
X235050Y-477179D01*
G01X223350Y-531979D02*
Y-523979D01*
X227950Y-531979D01*
Y-523979D01*
G01X233650Y-526646D02*
Y-531979D01*
G01Y-524512D02*
X233450Y-524379D01*
Y-524112D01*
X233650Y-523979D01*
X233850Y-524112D01*
Y-524379D01*
X233650Y-524512D01*
G01X239950Y-531979D02*
Y-526646D01*
G01Y-527979D02*
X240350Y-527312D01*
X240950Y-526779D01*
X241750Y-526646D01*
X242450Y-526779D01*
X243050Y-527312D01*
X243350Y-528246D01*
Y-531979D01*
G01X251450D02*
Y-526646D01*
G01Y-527579D02*
X251050Y-527046D01*
X250450Y-526779D01*
X249750Y-526646D01*
X249050Y-526912D01*
X248450Y-527446D01*
X248050Y-528246D01*
X247850Y-529312D01*
X248050Y-530379D01*
X248450Y-531179D01*
X249050Y-531712D01*
X249750Y-531979D01*
X250450Y-531846D01*
X251050Y-531446D01*
X251450Y-530913D01*
G01X220479Y-503336D02*
X222479D01*
Y-505736D01*
X221879Y-506536D01*
X221179Y-507069D01*
X220179Y-507336D01*
X219179Y-507069D01*
X218479Y-506536D01*
X217879Y-505736D01*
X217479Y-504803D01*
X217279Y-503736D01*
Y-502803D01*
X217479Y-502003D01*
X217879Y-501069D01*
X218479Y-500269D01*
X219079Y-499736D01*
X219879Y-499336D01*
X220579D01*
X221379Y-499603D01*
X221979Y-500136D01*
G01X225579Y-507336D02*
Y-499336D01*
X230179Y-507336D01*
Y-499336D01*
G01X233679Y-507336D02*
Y-499336D01*
X235679D01*
X236479Y-499736D01*
X237079Y-500269D01*
X237579Y-501069D01*
X237979Y-502003D01*
X238079Y-503336D01*
X237979Y-504669D01*
X237579Y-505603D01*
X237079Y-506403D01*
X236479Y-506936D01*
X235679Y-507336D01*
X233679D01*
G01X243679D02*
X243879Y-505603D01*
X244179Y-504136D01*
X244579Y-502803D01*
X245079Y-501336D01*
X245879Y-499336D01*
X241879D01*
G01X252079Y-483936D02*
Y-475936D01*
X250879Y-477536D01*
G01Y-483936D02*
X253279D01*
G01X259879D02*
X260079Y-482203D01*
X260379Y-480736D01*
X260779Y-479403D01*
X261279Y-477936D01*
X262079Y-475936D01*
X258079D01*
G01X326250Y-525312D02*
X326850Y-524512D01*
X327550Y-524112D01*
X328350Y-523979D01*
X329350Y-524246D01*
X330050Y-524912D01*
X330250Y-525712D01*
X330150Y-526513D01*
X329750Y-527179D01*
X327750Y-528512D01*
X326850Y-529446D01*
X326250Y-530779D01*
X326050Y-531979D01*
X330250D01*
G01X336150Y-523979D02*
X335350Y-524246D01*
X334750Y-524912D01*
X334350Y-525712D01*
X334050Y-526779D01*
X333950Y-527979D01*
X334050Y-529179D01*
X334350Y-530246D01*
X334750Y-531046D01*
X335350Y-531712D01*
X336150Y-531979D01*
X336950Y-531712D01*
X337550Y-531046D01*
X337950Y-530246D01*
X338250Y-529179D01*
X338350Y-527979D01*
X338250Y-526779D01*
X337950Y-525712D01*
X337550Y-524912D01*
X336950Y-524246D01*
X336150Y-523979D01*
G01X342250Y-525312D02*
X342850Y-524512D01*
X343550Y-524112D01*
X344350Y-523979D01*
X345350Y-524246D01*
X346050Y-524912D01*
X346250Y-525712D01*
X346150Y-526513D01*
X345750Y-527179D01*
X343750Y-528512D01*
X342850Y-529446D01*
X342250Y-530779D01*
X342050Y-531979D01*
X346250D01*
G01X349950Y-530379D02*
X350550Y-531312D01*
X351350Y-531846D01*
X352250Y-531979D01*
X353050Y-531846D01*
X353850Y-531179D01*
X354350Y-530379D01*
X354450Y-529579D01*
X354250Y-528646D01*
X353550Y-527979D01*
X352850Y-527712D01*
X351950D01*
G01X352850D02*
X353450Y-527312D01*
X353950Y-526646D01*
X354150Y-525846D01*
X353950Y-525046D01*
X353450Y-524379D01*
X352550Y-523979D01*
X351650Y-524112D01*
X350750Y-524646D01*
G01X358350Y-532246D02*
X361950Y-523979D01*
G01X368150D02*
X367350Y-524246D01*
X366750Y-524912D01*
X366350Y-525712D01*
X366050Y-526779D01*
X365950Y-527979D01*
X366050Y-529179D01*
X366350Y-530246D01*
X366750Y-531046D01*
X367350Y-531712D01*
X368150Y-531979D01*
X368950Y-531712D01*
X369550Y-531046D01*
X369950Y-530246D01*
X370250Y-529179D01*
X370350Y-527979D01*
X370250Y-526779D01*
X369950Y-525712D01*
X369550Y-524912D01*
X368950Y-524246D01*
X368150Y-523979D01*
G01X373950Y-530379D02*
X374550Y-531312D01*
X375350Y-531846D01*
X376250Y-531979D01*
X377050Y-531846D01*
X377850Y-531179D01*
X378350Y-530379D01*
X378450Y-529579D01*
X378250Y-528646D01*
X377550Y-527979D01*
X376850Y-527712D01*
X375950D01*
G01X376850D02*
X377450Y-527312D01*
X377950Y-526646D01*
X378150Y-525846D01*
X377950Y-525046D01*
X377450Y-524379D01*
X376550Y-523979D01*
X375650Y-524112D01*
X374750Y-524646D01*
G01X382350Y-532246D02*
X385950Y-523979D01*
G01X390250Y-525312D02*
X390850Y-524512D01*
X391550Y-524112D01*
X392350Y-523979D01*
X393350Y-524246D01*
X394050Y-524912D01*
X394250Y-525712D01*
X394150Y-526513D01*
X393750Y-527179D01*
X391750Y-528512D01*
X390850Y-529446D01*
X390250Y-530779D01*
X390050Y-531979D01*
X394250D01*
G01X401350D02*
Y-523979D01*
X397650Y-529712D01*
X402650D01*
G01X325950Y-506979D02*
Y-498979D01*
X327950D01*
X328750Y-499379D01*
X329350Y-499912D01*
X329850Y-500712D01*
X330250Y-501646D01*
X330350Y-502979D01*
X330250Y-504312D01*
X329850Y-505246D01*
X329350Y-506046D01*
X328750Y-506579D01*
X327950Y-506979D01*
X325950D01*
G01X333650D02*
X336150Y-498979D01*
X338650Y-506979D01*
G01X337750Y-504179D02*
X334550D01*
G01X344150Y-498979D02*
X343350Y-499246D01*
X342750Y-499912D01*
X342350Y-500712D01*
X342050Y-501779D01*
X341950Y-502979D01*
X342050Y-504179D01*
X342350Y-505246D01*
X342750Y-506046D01*
X343350Y-506712D01*
X344150Y-506979D01*
X344950Y-506712D01*
X345550Y-506046D01*
X345950Y-505246D01*
X346250Y-504179D01*
X346350Y-502979D01*
X346250Y-501779D01*
X345950Y-500712D01*
X345550Y-499912D01*
X344950Y-499246D01*
X344150Y-498979D01*
G01X350250Y-506979D02*
Y-498979D01*
X354050D01*
G01X352650Y-502846D02*
X350250D01*
G01X360150Y-498979D02*
X359350Y-499246D01*
X358750Y-499912D01*
X358350Y-500712D01*
X358050Y-501779D01*
X357950Y-502979D01*
X358050Y-504179D01*
X358350Y-505246D01*
X358750Y-506046D01*
X359350Y-506712D01*
X360150Y-506979D01*
X360950Y-506712D01*
X361550Y-506046D01*
X361950Y-505246D01*
X362250Y-504179D01*
X362350Y-502979D01*
X362250Y-501779D01*
X361950Y-500712D01*
X361550Y-499912D01*
X360950Y-499246D01*
X360150Y-498979D01*
G01X368150D02*
Y-506979D01*
G01X365850Y-498979D02*
X370450D01*
G01X373550Y-506979D02*
Y-498979D01*
X376150Y-505646D01*
X378750Y-498979D01*
Y-506979D01*
G01X384950Y-502712D02*
X385350Y-502312D01*
X385650Y-501646D01*
X385850Y-500712D01*
X385650Y-499912D01*
X385250Y-499379D01*
X384550Y-498979D01*
X381850D01*
Y-506979D01*
X385150D01*
X385850Y-506446D01*
X386250Y-505646D01*
X386450Y-504712D01*
X386250Y-503779D01*
X385650Y-502979D01*
X384950Y-502712D01*
X381850D01*
G01X390950Y-498979D02*
X393350D01*
G01X392150D02*
Y-506979D01*
G01X390950D02*
X393350D01*
G01X398150Y-505379D02*
X398650Y-506179D01*
X399250Y-506712D01*
X399950Y-506979D01*
X400750Y-506712D01*
X401350Y-506179D01*
X401950Y-505379D01*
X402150Y-504312D01*
Y-498979D01*
G01X408150D02*
X407350Y-499246D01*
X406750Y-499912D01*
X406350Y-500712D01*
X406050Y-501779D01*
X405950Y-502979D01*
X406050Y-504179D01*
X406350Y-505246D01*
X406750Y-506046D01*
X407350Y-506712D01*
X408150Y-506979D01*
X408950Y-506712D01*
X409550Y-506046D01*
X409950Y-505246D01*
X410250Y-504179D01*
X410350Y-502979D01*
X410250Y-501779D01*
X409950Y-500712D01*
X409550Y-499912D01*
X408950Y-499246D01*
X408150Y-498979D01*
G01X343750Y-481979D02*
Y-473979D01*
X347550D01*
G01X346150Y-477846D02*
X343750D01*
G01X353650Y-473979D02*
X352850Y-474246D01*
X352250Y-474912D01*
X351850Y-475712D01*
X351550Y-476779D01*
X351450Y-477979D01*
X351550Y-479179D01*
X351850Y-480246D01*
X352250Y-481046D01*
X352850Y-481712D01*
X353650Y-481979D01*
X354450Y-481712D01*
X355050Y-481046D01*
X355450Y-480246D01*
X355750Y-479179D01*
X355850Y-477979D01*
X355750Y-476779D01*
X355450Y-475712D01*
X355050Y-474912D01*
X354450Y-474246D01*
X353650Y-473979D01*
G01X361650D02*
Y-481979D01*
G01X359350Y-473979D02*
X363950D01*
G01X366650Y-484646D02*
X372650D01*
G01X375050Y-481979D02*
Y-473979D01*
X377650Y-480646D01*
X380250Y-473979D01*
Y-481979D01*
G01X386450Y-477712D02*
X386850Y-477312D01*
X387150Y-476646D01*
X387350Y-475712D01*
X387150Y-474912D01*
X386750Y-474379D01*
X386050Y-473979D01*
X383350D01*
Y-481979D01*
X386650D01*
X387350Y-481446D01*
X387750Y-480646D01*
X387950Y-479712D01*
X387750Y-478779D01*
X387150Y-477979D01*
X386450Y-477712D01*
X383350D01*
G01X390650Y-484646D02*
X396650D01*
G01X403650Y-481979D02*
X399650D01*
Y-473979D01*
X403650D01*
G01X402050Y-477846D02*
X399650D01*
G01X407050Y-481979D02*
Y-473979D01*
X409650Y-480646D01*
X412250Y-473979D01*
Y-481979D01*
G01X417650D02*
X418350Y-481846D01*
X419150Y-481446D01*
X419650Y-480779D01*
X419850Y-479846D01*
X419650Y-478913D01*
X419050Y-478112D01*
X418150Y-477712D01*
X417150D01*
X416550Y-477446D01*
X416050Y-476779D01*
X415850Y-475846D01*
X416150Y-474912D01*
X416850Y-474246D01*
X417650Y-473979D01*
X418450Y-474246D01*
X419150Y-474912D01*
X419450Y-475846D01*
X419250Y-476779D01*
X418750Y-477446D01*
X418150Y-477712D01*
X417150D01*
X416250Y-478112D01*
X415650Y-478913D01*
X415450Y-479846D01*
X415650Y-480779D01*
X416150Y-481446D01*
X416950Y-481846D01*
X417650Y-481979D01*
G01X423950Y-481046D02*
X424650Y-481712D01*
X425450Y-481979D01*
X426250Y-481712D01*
X426950Y-480913D01*
X427450Y-479712D01*
X427650Y-478512D01*
Y-477046D01*
X427450Y-475846D01*
X426950Y-474779D01*
X426350Y-474246D01*
X425650Y-473979D01*
X424850Y-474246D01*
X424250Y-474779D01*
X423850Y-475579D01*
X423650Y-476646D01*
X423850Y-477579D01*
X424350Y-478512D01*
X424950Y-479046D01*
X425650Y-479179D01*
X426450Y-478913D01*
X427050Y-478246D01*
X427650Y-477046D01*
G01X433650Y-473979D02*
X432850Y-474246D01*
X432250Y-474912D01*
X431850Y-475712D01*
X431550Y-476779D01*
X431450Y-477979D01*
X431550Y-479179D01*
X431850Y-480246D01*
X432250Y-481046D01*
X432850Y-481712D01*
X433650Y-481979D01*
X434450Y-481712D01*
X435050Y-481046D01*
X435450Y-480246D01*
X435750Y-479179D01*
X435850Y-477979D01*
X435750Y-476779D01*
X435450Y-475712D01*
X435050Y-474912D01*
X434450Y-474246D01*
X433650Y-473979D01*
G01X439450Y-481979D02*
Y-473979D01*
G01X443250D02*
X439450Y-478913D01*
G01X443850Y-481979D02*
X441150Y-476646D01*
G01X414650Y-534979D02*
Y-526979D01*
X413450Y-528579D01*
G01Y-534979D02*
X415850D01*
G01X420750Y-531646D02*
X421450Y-530712D01*
X422050Y-530179D01*
X422850Y-529912D01*
X423550Y-530179D01*
X424050Y-530712D01*
X424450Y-531512D01*
X424550Y-532446D01*
X424450Y-533246D01*
X424050Y-534046D01*
X423450Y-534712D01*
X422750Y-534979D01*
X421950Y-534712D01*
X421250Y-533913D01*
X420850Y-532712D01*
X420750Y-531379D01*
X420950Y-529646D01*
X421250Y-528712D01*
X421750Y-527779D01*
X422450Y-527112D01*
X423150Y-526979D01*
X423850Y-527246D01*
X424350Y-527912D01*
G01X430650Y-535246D02*
X430450Y-535112D01*
Y-534846D01*
X430650Y-534712D01*
X430850Y-534846D01*
Y-535112D01*
X430650Y-535246D01*
G01X436750Y-531646D02*
X437450Y-530712D01*
X438050Y-530179D01*
X438850Y-529912D01*
X439550Y-530179D01*
X440050Y-530712D01*
X440450Y-531512D01*
X440550Y-532446D01*
X440450Y-533246D01*
X440050Y-534046D01*
X439450Y-534712D01*
X438750Y-534979D01*
X437950Y-534712D01*
X437250Y-533913D01*
X436850Y-532712D01*
X436750Y-531379D01*
X436950Y-529646D01*
X437250Y-528712D01*
X437750Y-527779D01*
X438450Y-527112D01*
X439150Y-526979D01*
X439850Y-527246D01*
X440350Y-527912D01*
G01X459650Y-534979D02*
Y-526979D01*
X458450Y-528579D01*
G01Y-534979D02*
X460850D01*
G01X467450D02*
X467650Y-533246D01*
X467950Y-531779D01*
X468350Y-530446D01*
X468850Y-528979D01*
X469650Y-526979D01*
X465650D01*
G01X475650Y-535246D02*
X475450Y-535112D01*
Y-534846D01*
X475650Y-534712D01*
X475850Y-534846D01*
Y-535112D01*
X475650Y-535246D01*
G01X481750Y-528312D02*
X482350Y-527512D01*
X483050Y-527112D01*
X483850Y-526979D01*
X484850Y-527246D01*
X485550Y-527912D01*
X485750Y-528712D01*
X485650Y-529513D01*
X485250Y-530179D01*
X483250Y-531512D01*
X482350Y-532446D01*
X481750Y-533779D01*
X481550Y-534979D01*
X485750D01*
G01X479650Y-508379D02*
X480150Y-509179D01*
X480750Y-509712D01*
X481450Y-509979D01*
X482250Y-509712D01*
X482850Y-509179D01*
X483450Y-508379D01*
X483650Y-507312D01*
Y-501979D01*
M02*
